G04 ================== begin FILE IDENTIFICATION RECORD ==================*
G04 Layout Name:  13130-1b.brd*
G04 Film Name:    L1*
G04 File Format:  Gerber RS274X*
G04 File Origin:  Cadence Allegro 16.5-S037*
G04 Origin Date:  Thu Nov 13 17:26:47 2014*
G04 *
G04 Layer:  VIA CLASS/TOP*
G04 Layer:  PIN/TOP*
G04 Layer:  ETCH/TOP*
G04 Layer:  DRAWING FORMAT/LAYER_PCB_STORY*
G04 Layer:  DRAWING FORMAT/LAYER_L1*
G04 *
G04 Offset:    (0.00 0.00)*
G04 Mirror:    No*
G04 Mode:      Positive*
G04 Rotation:  0*
G04 FullContactRelief:  No*
G04 UndefLineWidth:     6.00*
G04 ================== end FILE IDENTIFICATION RECORD ====================*
%FSLAX35Y35*MOIN*%
%IR0*IPPOS*OFA0.00000B0.00000*MIA0B0*SFA1.00000B1.00000*%
%ADD136R,.01X.007*%
%ADD10C,.01*%
%ADD43R,.03X.008*%
%ADD42R,.008X.03*%
%ADD14C,.02*%
%ADD87C,.012*%
%AMMACRO17*
4,1,40,-.009,-.01,
.009,-.01,
.009347,-.00997,
.009684,-.009879,
.01,-.009732,
.010286,-.009532,
.010532,-.009286,
.010732,-.009,
.010879,-.008684,
.01097,-.008347,
.011,-.008,
.011,.008,
.01097,.008347,
.010879,.008684,
.010732,.009,
.010532,.009286,
.010286,.009532,
.01,.009732,
.009684,.009879,
.009347,.00997,
.009,.01,
-.009,.01,
-.009347,.00997,
-.009684,.009879,
-.01,.009732,
-.010286,.009532,
-.010532,.009286,
-.010732,.009,
-.010879,.008684,
-.01097,.008347,
-.011,.008,
-.011,-.008,
-.01097,-.008347,
-.010879,-.008684,
-.010732,-.009,
-.010532,-.009286,
-.010286,-.009532,
-.01,-.009732,
-.009684,-.009879,
-.009347,-.00997,
-.009,-.01,
0.0*
%
%ADD17MACRO17*%
%ADD71C,.022*%
%ADD62R,.08X.136*%
%AMMACRO25*
4,1,40,-.01,.009,
-.01,-.009,
-.00997,-.009347,
-.009879,-.009684,
-.009732,-.01,
-.009532,-.010286,
-.009286,-.010532,
-.009,-.010732,
-.008684,-.010879,
-.008347,-.01097,
-.008,-.011,
.008,-.011,
.008347,-.01097,
.008684,-.010879,
.009,-.010732,
.009286,-.010532,
.009532,-.010286,
.009732,-.01,
.009879,-.009684,
.00997,-.009347,
.01,-.009,
.01,.009,
.00997,.009347,
.009879,.009684,
.009732,.01,
.009532,.010286,
.009286,.010532,
.009,.010732,
.008684,.010879,
.008347,.01097,
.008,.011,
-.008,.011,
-.008347,.01097,
-.008684,.010879,
-.009,.010732,
-.009286,.010532,
-.009532,.010286,
-.009732,.01,
-.009879,.009684,
-.00997,.009347,
-.01,.009,
0.0*
%
%ADD25MACRO25*%
%ADD11C,.04*%
%ADD106C,.032*%
%ADD132C,.06*%
%ADD90R,.028X.126*%
%ADD89C,.015*%
%ADD60R,.041X.168*%
%ADD53R,.047X.108*%
%ADD127R,.168X.041*%
%ADD123R,.026X.008*%
%ADD122R,.008X.026*%
%ADD85C,.016*%
%AMMACRO49*
4,1,40,-.0155,.016,
-.0155,-.016,
-.015439,-.016695,
-.015259,-.017368,
-.014964,-.018,
-.014564,-.018571,
-.014071,-.019064,
-.0135,-.019464,
-.012868,-.019759,
-.012195,-.019939,
-.0115,-.02,
.0115,-.02,
.012195,-.019939,
.012868,-.019759,
.0135,-.019464,
.014071,-.019064,
.014564,-.018571,
.014964,-.018,
.015259,-.017368,
.015439,-.016695,
.0155,-.016,
.0155,.016,
.015439,.016695,
.015259,.017368,
.014964,.018,
.014564,.018571,
.014071,.019064,
.0135,.019464,
.012868,.019759,
.012195,.019939,
.0115,.02,
-.0115,.02,
-.012195,.019939,
-.012868,.019759,
-.0135,.019464,
-.014071,.019064,
-.014564,.018571,
-.014964,.018,
-.015259,.017368,
-.015439,.016695,
-.0155,.016,
0.0*
%
%ADD49MACRO49*%
%ADD39R,.075X.135*%
%ADD103R,.066X.118*%
%ADD84C,.017*%
%AMMACRO20*
4,1,40,.016,.0155,
-.016,.0155,
-.016695,.015439,
-.017368,.015259,
-.018,.014964,
-.018571,.014564,
-.019064,.014071,
-.019464,.0135,
-.019759,.012868,
-.019939,.012195,
-.02,.0115,
-.02,-.0115,
-.019939,-.012195,
-.019759,-.012868,
-.019464,-.0135,
-.019064,-.014071,
-.018571,-.014564,
-.018,-.014964,
-.017368,-.015259,
-.016695,-.015439,
-.016,-.0155,
.016,-.0155,
.016695,-.015439,
.017368,-.015259,
.018,-.014964,
.018571,-.014564,
.019064,-.014071,
.019464,-.0135,
.019759,-.012868,
.019939,-.012195,
.02,-.0115,
.02,.0115,
.019939,.012195,
.019759,.012868,
.019464,.0135,
.019064,.014071,
.018571,.014564,
.018,.014964,
.017368,.015259,
.016695,.015439,
.016,.0155,
0.0*
%
%ADD20MACRO20*%
%AMMACRO129*
4,1,6,.0915,.0525,
.0915,-.0525,
-.0915,-.0525,
-.0915,.0075,
-.0435,.0075,
-.0435,.0525,
.0915,.0525,
0.0*
%
%ADD129MACRO129*%
%ADD125R,.028X.008*%
%ADD124R,.008X.028*%
%ADD120R,.118X.066*%
%ADD33R,.028X.165*%
%ADD12C,.028*%
%ADD83C,.056*%
%ADD70R,.125X.098*%
%ADD135R,.098X.125*%
%AMMACRO76*
4,1,40,.02,-.005,
.019878,-.006389,
.019518,-.007736,
.018928,-.009,
.018128,-.010142,
.017142,-.011128,
.016,-.011928,
.014736,-.012518,
.013389,-.012878,
.012,-.013,
-.012,-.013,
-.013389,-.012878,
-.014736,-.012518,
-.016,-.011928,
-.017142,-.011128,
-.018128,-.010142,
-.018928,-.009,
-.019518,-.007736,
-.019878,-.006389,
-.02,-.005,
-.02,.005,
-.019878,.006389,
-.019518,.007736,
-.018928,.009,
-.018128,.010142,
-.017142,.011128,
-.016,.011928,
-.014736,.012518,
-.013389,.012878,
-.012,.013,
.012,.013,
.013389,.012878,
.014736,.012518,
.016,.011928,
.017142,.011128,
.018128,.010142,
.018928,.009,
.019518,.007736,
.019878,.006389,
.02,.005,
.02,-.005,
0.0*
%
%ADD76MACRO76*%
%AMMACRO36*
4,1,40,.009,.008,
.009,-.008,
.00897,-.008347,
.008879,-.008684,
.008732,-.009,
.008532,-.009286,
.008286,-.009532,
.008,-.009732,
.007684,-.009879,
.007347,-.00997,
.007,-.01,
-.007,-.01,
-.007347,-.00997,
-.007684,-.009879,
-.008,-.009732,
-.008286,-.009532,
-.008532,-.009286,
-.008732,-.009,
-.008879,-.008684,
-.00897,-.008347,
-.009,-.008,
-.009,.008,
-.00897,.008347,
-.008879,.008684,
-.008732,.009,
-.008532,.009286,
-.008286,.009532,
-.008,.009732,
-.007684,.009879,
-.007347,.00997,
-.007,.01,
.007,.01,
.007347,.00997,
.007684,.009879,
.008,.009732,
.008286,.009532,
.008532,.009286,
.008732,.009,
.008879,.008684,
.00897,.008347,
.009,.008,
0.0*
%
%ADD36MACRO36*%
%AMMACRO15*
4,1,40,.008,-.009,
-.008,-.009,
-.008347,-.00897,
-.008684,-.008879,
-.009,-.008732,
-.009286,-.008532,
-.009532,-.008286,
-.009732,-.008,
-.009879,-.007684,
-.00997,-.007347,
-.01,-.007,
-.01,.007,
-.00997,.007347,
-.009879,.007684,
-.009732,.008,
-.009532,.008286,
-.009286,.008532,
-.009,.008732,
-.008684,.008879,
-.008347,.00897,
-.008,.009,
.008,.009,
.008347,.00897,
.008684,.008879,
.009,.008732,
.009286,.008532,
.009532,.008286,
.009732,.008,
.009879,.007684,
.00997,.007347,
.01,.007,
.01,-.007,
.00997,-.007347,
.009879,-.007684,
.009732,-.008,
.009532,-.008286,
.009286,-.008532,
.009,-.008732,
.008684,-.008879,
.008347,-.00897,
.008,-.009,
0.0*
%
%ADD15MACRO15*%
%AMMACRO81*
4,1,40,.0145,-.0055,
.014378,-.006889,
.014018,-.008236,
.013428,-.0095,
.012628,-.010642,
.011642,-.011628,
.0105,-.012428,
.009236,-.013018,
.007889,-.013378,
.0065,-.0135,
-.0065,-.0135,
-.007889,-.013378,
-.009236,-.013018,
-.0105,-.012428,
-.011642,-.011628,
-.012628,-.010642,
-.013428,-.0095,
-.014018,-.008236,
-.014378,-.006889,
-.0145,-.0055,
-.0145,.0055,
-.014378,.006889,
-.014018,.008236,
-.013428,.0095,
-.012628,.010642,
-.011642,.011628,
-.0105,.012428,
-.009236,.013018,
-.007889,.013378,
-.0065,.0135,
.0065,.0135,
.007889,.013378,
.009236,.013018,
.0105,.012428,
.011642,.011628,
.012628,.010642,
.013428,.0095,
.014018,.008236,
.014378,.006889,
.0145,.0055,
.0145,-.0055,
0.0*
%
%ADD81MACRO81*%
%AMMACRO35*
4,1,6,.0135,-.025,
-.0065,-.005,
-.0135,-.005,
-.0135,.005,
-.0065,.005,
.0135,.025,
.0135,-.025,
0.0*
%
%ADD35MACRO35*%
%AMMACRO28*
4,1,6,-.0135,.005,
-.0065,.005,
.0135,.025,
.0135,-.025,
-.0065,-.005,
-.0135,-.005,
-.0135,.005,
0.0*
%
%ADD28MACRO28*%
%AMMACRO32*
4,1,40,.009,.008,
.009,-.008,
.00897,-.008347,
.008879,-.008684,
.008732,-.009,
.008532,-.009286,
.008286,-.009532,
.008,-.009732,
.007684,-.009879,
.007347,-.00997,
.007,-.01,
-.007,-.01,
-.007347,-.00997,
-.007684,-.009879,
-.008,-.009732,
-.008286,-.009532,
-.008532,-.009286,
-.008732,-.009,
-.008879,-.008684,
-.00897,-.008347,
-.009,-.008,
-.009,.008,
-.00897,.008347,
-.008879,.008684,
-.008732,.009,
-.008532,.009286,
-.008286,.009532,
-.008,.009732,
-.007684,.009879,
-.007347,.00997,
-.007,.01,
.007,.01,
.007347,.00997,
.007684,.009879,
.008,.009732,
.008286,.009532,
.008532,.009286,
.008732,.009,
.008879,.008684,
.00897,.008347,
.009,.008,
0.0*
%
%ADD32MACRO32*%
%AMMACRO16*
4,1,40,.008,-.009,
-.008,-.009,
-.008347,-.00897,
-.008684,-.008879,
-.009,-.008732,
-.009286,-.008532,
-.009532,-.008286,
-.009732,-.008,
-.009879,-.007684,
-.00997,-.007347,
-.01,-.007,
-.01,.007,
-.00997,.007347,
-.009879,.007684,
-.009732,.008,
-.009532,.008286,
-.009286,.008532,
-.009,.008732,
-.008684,.008879,
-.008347,.00897,
-.008,.009,
.008,.009,
.008347,.00897,
.008684,.008879,
.009,.008732,
.009286,.008532,
.009532,.008286,
.009732,.008,
.009879,.007684,
.00997,.007347,
.01,.007,
.01,-.007,
.00997,-.007347,
.009879,-.007684,
.009732,-.008,
.009532,-.008286,
.009286,-.008532,
.009,-.008732,
.008684,-.008879,
.008347,-.00897,
.008,-.009,
0.0*
%
%ADD16MACRO16*%
%ADD88O,.01X.0135*%
%ADD86O,.0135X.01*%
%ADD63R,.03X.014*%
%ADD104R,.033X.012*%
%ADD102R,.012X.05*%
%ADD101R,.05X.012*%
%ADD59R,.014X.03*%
%ADD45R,.032X.022*%
%ADD121R,.012X.033*%
%ADD75R,.012X.034*%
%ADD27R,.034X.012*%
%ADD111R,.032X.042*%
%ADD107R,.042X.032*%
%ADD65R,.04X.026*%
%AMMACRO21*
4,1,40,.01,-.009,
.01,.009,
.00997,.009347,
.009879,.009684,
.009732,.01,
.009532,.010286,
.009286,.010532,
.009,.010732,
.008684,.010879,
.008347,.01097,
.008,.011,
-.008,.011,
-.008347,.01097,
-.008684,.010879,
-.009,.010732,
-.009286,.010532,
-.009532,.010286,
-.009732,.01,
-.009879,.009684,
-.00997,.009347,
-.01,.009,
-.01,-.009,
-.00997,-.009347,
-.009879,-.009684,
-.009732,-.01,
-.009532,-.010286,
-.009286,-.010532,
-.009,-.010732,
-.008684,-.010879,
-.008347,-.01097,
-.008,-.011,
.008,-.011,
.008347,-.01097,
.008684,-.010879,
.009,-.010732,
.009286,-.010532,
.009532,-.010286,
.009732,-.01,
.009879,-.009684,
.00997,-.009347,
.01,-.009,
0.0*
%
%ADD21MACRO21*%
%AMMACRO18*
4,1,40,.009,.01,
-.009,.01,
-.009347,.00997,
-.009684,.009879,
-.01,.009732,
-.010286,.009532,
-.010532,.009286,
-.010732,.009,
-.010879,.008684,
-.01097,.008347,
-.011,.008,
-.011,-.008,
-.01097,-.008347,
-.010879,-.008684,
-.010732,-.009,
-.010532,-.009286,
-.010286,-.009532,
-.01,-.009732,
-.009684,-.009879,
-.009347,-.00997,
-.009,-.01,
.009,-.01,
.009347,-.00997,
.009684,-.009879,
.01,-.009732,
.010286,-.009532,
.010532,-.009286,
.010732,-.009,
.010879,-.008684,
.01097,-.008347,
.011,-.008,
.011,.008,
.01097,.008347,
.010879,.008684,
.010732,.009,
.010532,.009286,
.010286,.009532,
.01,.009732,
.009684,.009879,
.009347,.00997,
.009,.01,
0.0*
%
%ADD18MACRO18*%
%ADD134R,.026X.04*%
%ADD109R,.012X.028*%
%ADD108R,.028X.012*%
%ADD69R,.06X.025*%
%ADD40R,.105X.138*%
%ADD119R,.025X.06*%
%AMMACRO116*
4,1,12,.0725,-.069,
.0725,-.015,
-.0725,-.015,
-.0725,-.025,
-.1475,-.025,
-.1475,.025,
-.0725,.025,
-.0725,.015,
.0725,.015,
.0725,.069,
.1475,.069,
.1475,-.069,
.0725,-.069,
0.0*
%
%ADD116MACRO116*%
%ADD113R,.136X.171*%
%ADD78R,.012X.055*%
%ADD48R,.04X.073*%
%ADD115R,.05X.036*%
%ADD82R,.055X.014*%
%ADD68R,.026X.016*%
%ADD44R,.073X.04*%
%ADD118R,.037X.024*%
%ADD114R,.054X.025*%
%ADD79R,.038X.014*%
%AMMACRO51*
4,1,40,.0155,-.016,
.0155,.016,
.015439,.016695,
.015259,.017368,
.014964,.018,
.014564,.018571,
.014071,.019064,
.0135,.019464,
.012868,.019759,
.012195,.019939,
.0115,.02,
-.0115,.02,
-.012195,.019939,
-.012868,.019759,
-.0135,.019464,
-.014071,.019064,
-.014564,.018571,
-.014964,.018,
-.015259,.017368,
-.015439,.016695,
-.0155,.016,
-.0155,-.016,
-.015439,-.016695,
-.015259,-.017368,
-.014964,-.018,
-.014564,-.018571,
-.014071,-.019064,
-.0135,-.019464,
-.012868,-.019759,
-.012195,-.019939,
-.0115,-.02,
.0115,-.02,
.012195,-.019939,
.012868,-.019759,
.0135,-.019464,
.014071,-.019064,
.014564,-.018571,
.014964,-.018,
.015259,-.017368,
.015439,-.016695,
.0155,-.016,
0.0*
%
%ADD51MACRO51*%
%ADD24R,.014X.055*%
%AMMACRO19*
4,1,40,-.016,-.0155,
.016,-.0155,
.016695,-.015439,
.017368,-.015259,
.018,-.014964,
.018571,-.014564,
.019064,-.014071,
.019464,-.0135,
.019759,-.012868,
.019939,-.012195,
.02,-.0115,
.02,.0115,
.019939,.012195,
.019759,.012868,
.019464,.0135,
.019064,.014071,
.018571,.014564,
.018,.014964,
.017368,.015259,
.016695,.015439,
.016,.0155,
-.016,.0155,
-.016695,.015439,
-.017368,.015259,
-.018,.014964,
-.018571,.014564,
-.019064,.014071,
-.019464,.0135,
-.019759,.012868,
-.019939,.012195,
-.02,.0115,
-.02,-.0115,
-.019939,-.012195,
-.019759,-.012868,
-.019464,-.0135,
-.019064,-.014071,
-.018571,-.014564,
-.018,-.014964,
-.017368,-.015259,
-.016695,-.015439,
-.016,-.0155,
0.0*
%
%ADD19MACRO19*%
%ADD117R,.075X.05*%
%ADD72R,.073X.025*%
%ADD61R,.036X.026*%
%ADD52R,.014X.038*%
%ADD22R,.037X.061*%
%ADD128R,.026X.036*%
%ADD92R,.138X.181*%
%ADD58R,.016X.028*%
%ADD23R,.037X.053*%
%ADD13R,.061X.037*%
%AMMACRO77*
4,1,40,.002,.016,
.003389,.015878,
.004736,.015518,
.006,.014928,
.007142,.014128,
.008128,.013142,
.008928,.012,
.009518,.010736,
.009878,.009389,
.01,.008,
.01,-.008,
.009878,-.009389,
.009518,-.010736,
.008928,-.012,
.008128,-.013142,
.007142,-.014128,
.006,-.014928,
.004736,-.015518,
.003389,-.015878,
.002,-.016,
-.002,-.016,
-.003389,-.015878,
-.004736,-.015518,
-.006,-.014928,
-.007142,-.014128,
-.008128,-.013142,
-.008928,-.012,
-.009518,-.010736,
-.009878,-.009389,
-.01,-.008,
-.01,.008,
-.009878,.009389,
-.009518,.010736,
-.008928,.012,
-.008128,.013142,
-.007142,.014128,
-.006,.014928,
-.004736,.015518,
-.003389,.015878,
-.002,.016,
.002,.016,
0.0*
%
%ADD77MACRO77*%
%ADD55R,.089X.011*%
%AMMACRO50*
4,1,40,-.016,.002,
-.015878,.003389,
-.015518,.004736,
-.014928,.006,
-.014128,.007142,
-.013142,.008128,
-.012,.008928,
-.010736,.009518,
-.009389,.009878,
-.008,.01,
.008,.01,
.009389,.009878,
.010736,.009518,
.012,.008928,
.013142,.008128,
.014128,.007142,
.014928,.006,
.015518,.004736,
.015878,.003389,
.016,.002,
.016,-.002,
.015878,-.003389,
.015518,-.004736,
.014928,-.006,
.014128,-.007142,
.013142,-.008128,
.012,-.008928,
.010736,-.009518,
.009389,-.009878,
.008,-.01,
-.008,-.01,
-.009389,-.009878,
-.010736,-.009518,
-.012,-.008928,
-.013142,-.008128,
-.014128,-.007142,
-.014928,-.006,
-.015518,-.004736,
-.015878,-.003389,
-.016,-.002,
-.016,.002,
0.0*
%
%ADD50MACRO50*%
%ADD133R,.074X.053*%
%ADD57R,.096X.022*%
%ADD80R,.069X.05*%
%ADD67R,.085X.026*%
%ADD56R,.096X.041*%
%ADD46R,.037X.055*%
%ADD130R,.026X.085*%
%AMMACRO66*
4,1,6,.0525,-.0915,
-.0525,-.0915,
-.0525,.0915,
.0075,.0915,
.0075,.0435,
.0525,.0435,
.0525,-.0915,
0.0*
%
%ADD66MACRO66*%
%ADD112R,.043X.079*%
%AMMACRO64*
4,1,40,.005,.02,
.006389,.019878,
.007736,.019518,
.009,.018928,
.010142,.018128,
.011128,.017142,
.011928,.016,
.012518,.014736,
.012878,.013389,
.013,.012,
.013,-.012,
.012878,-.013389,
.012518,-.014736,
.011928,-.016,
.011128,-.017142,
.010142,-.018128,
.009,-.018928,
.007736,-.019518,
.006389,-.019878,
.005,-.02,
-.005,-.02,
-.006389,-.019878,
-.007736,-.019518,
-.009,-.018928,
-.010142,-.018128,
-.011128,-.017142,
-.011928,-.016,
-.012518,-.014736,
-.012878,-.013389,
-.013,-.012,
-.013,.012,
-.012878,.013389,
-.012518,.014736,
-.011928,.016,
-.011128,.017142,
-.010142,.018128,
-.009,.018928,
-.007736,.019518,
-.006389,.019878,
-.005,.02,
.005,.02,
0.0*
%
%ADD64MACRO64*%
%ADD131R,.075X.095*%
%ADD110R,.066X.086*%
%ADD91R,.185X.268*%
%ADD54R,.097X.072*%
%ADD105R,.236X.236*%
%ADD47R,.095X.075*%
%ADD126R,.138X.138*%
%AMMACRO74*
4,1,40,-.0145,.0055,
-.014378,.006889,
-.014018,.008236,
-.013428,.0095,
-.012628,.010642,
-.011642,.011628,
-.0105,.012428,
-.009236,.013018,
-.007889,.013378,
-.0065,.0135,
.0065,.0135,
.007889,.013378,
.009236,.013018,
.0105,.012428,
.011642,.011628,
.012628,.010642,
.013428,.0095,
.014018,.008236,
.014378,.006889,
.0145,.0055,
.0145,-.0055,
.014378,-.006889,
.014018,-.008236,
.013428,-.0095,
.012628,-.010642,
.011642,-.011628,
.0105,-.012428,
.009236,-.013018,
.007889,-.013378,
.0065,-.0135,
-.0065,-.0135,
-.007889,-.013378,
-.009236,-.013018,
-.0105,-.012428,
-.011642,-.011628,
-.012628,-.010642,
-.013428,-.0095,
-.014018,-.008236,
-.014378,-.006889,
-.0145,-.0055,
-.0145,.0055,
0.0*
%
%ADD74MACRO74*%
%AMMACRO73*
4,1,40,.0055,.0145,
.006889,.014378,
.008236,.014018,
.0095,.013428,
.010642,.012628,
.011628,.011642,
.012428,.0105,
.013018,.009236,
.013378,.007889,
.0135,.0065,
.0135,-.0065,
.013378,-.007889,
.013018,-.009236,
.012428,-.0105,
.011628,-.011642,
.010642,-.012628,
.0095,-.013428,
.008236,-.014018,
.006889,-.014378,
.0055,-.0145,
-.0055,-.0145,
-.006889,-.014378,
-.008236,-.014018,
-.0095,-.013428,
-.010642,-.012628,
-.011628,-.011642,
-.012428,-.0105,
-.013018,-.009236,
-.013378,-.007889,
-.0135,-.0065,
-.0135,.0065,
-.013378,.007889,
-.013018,.009236,
-.012428,.0105,
-.011628,.011642,
-.010642,.012628,
-.0095,.013428,
-.008236,.014018,
-.006889,.014378,
-.0055,.0145,
.0055,.0145,
0.0*
%
%ADD73MACRO73*%
%AMMACRO26*
4,1,40,-.009,-.008,
-.009,.008,
-.00897,.008347,
-.008879,.008684,
-.008732,.009,
-.008532,.009286,
-.008286,.009532,
-.008,.009732,
-.007684,.009879,
-.007347,.00997,
-.007,.01,
.007,.01,
.007347,.00997,
.007684,.009879,
.008,.009732,
.008286,.009532,
.008532,.009286,
.008732,.009,
.008879,.008684,
.00897,.008347,
.009,.008,
.009,-.008,
.00897,-.008347,
.008879,-.008684,
.008732,-.009,
.008532,-.009286,
.008286,-.009532,
.008,-.009732,
.007684,-.009879,
.007347,-.00997,
.007,-.01,
-.007,-.01,
-.007347,-.00997,
-.007684,-.009879,
-.008,-.009732,
-.008286,-.009532,
-.008532,-.009286,
-.008732,-.009,
-.008879,-.008684,
-.00897,-.008347,
-.009,-.008,
0.0*
%
%ADD26MACRO26*%
%ADD41R,.179X.179*%
%AMMACRO37*
4,1,40,-.008,.009,
.008,.009,
.008347,.00897,
.008684,.008879,
.009,.008732,
.009286,.008532,
.009532,.008286,
.009732,.008,
.009879,.007684,
.00997,.007347,
.01,.007,
.01,-.007,
.00997,-.007347,
.009879,-.007684,
.009732,-.008,
.009532,-.008286,
.009286,-.008532,
.009,-.008732,
.008684,-.008879,
.008347,-.00897,
.008,-.009,
-.008,-.009,
-.008347,-.00897,
-.008684,-.008879,
-.009,-.008732,
-.009286,-.008532,
-.009532,-.008286,
-.009732,-.008,
-.009879,-.007684,
-.00997,-.007347,
-.01,-.007,
-.01,.007,
-.00997,.007347,
-.009879,.007684,
-.009732,.008,
-.009532,.008286,
-.009286,.008532,
-.009,.008732,
-.008684,.008879,
-.008347,.00897,
-.008,.009,
0.0*
%
%ADD37MACRO37*%
%AMMACRO29*
4,1,6,-.0135,.025,
.0065,.005,
.0135,.005,
.0135,-.005,
.0065,-.005,
-.0135,-.025,
-.0135,.025,
0.0*
%
%ADD29MACRO29*%
%AMMACRO30*
4,1,20,-.0655,.1095,
-.051,.1095,
-.051,.12,
-.0375,.12,
-.0375,.1095,
.0375,.1095,
.0375,.12,
.051,.12,
.051,.1095,
.0655,.1095,
.0655,-.1095,
.051,-.1095,
.051,-.12,
.0375,-.12,
.0375,-.1095,
-.0375,-.1095,
-.0375,-.12,
-.051,-.12,
-.051,-.1095,
-.0655,-.1095,
-.0655,.1095,
0.0*
%
%ADD30MACRO30*%
%AMMACRO34*
4,1,6,.0135,-.005,
.0065,-.005,
-.0135,-.025,
-.0135,.025,
.0065,.005,
.0135,.005,
.0135,-.005,
0.0*
%
%ADD34MACRO34*%
%AMMACRO31*
4,1,40,-.009,-.008,
-.009,.008,
-.00897,.008347,
-.008879,.008684,
-.008732,.009,
-.008532,.009286,
-.008286,.009532,
-.008,.009732,
-.007684,.009879,
-.007347,.00997,
-.007,.01,
.007,.01,
.007347,.00997,
.007684,.009879,
.008,.009732,
.008286,.009532,
.008532,.009286,
.008732,.009,
.008879,.008684,
.00897,.008347,
.009,.008,
.009,-.008,
.00897,-.008347,
.008879,-.008684,
.008732,-.009,
.008532,-.009286,
.008286,-.009532,
.008,-.009732,
.007684,-.009879,
.007347,-.00997,
.007,-.01,
-.007,-.01,
-.007347,-.00997,
-.007684,-.009879,
-.008,-.009732,
-.008286,-.009532,
-.008532,-.009286,
-.008732,-.009,
-.008879,-.008684,
-.00897,-.008347,
-.009,-.008,
0.0*
%
%ADD31MACRO31*%
%AMMACRO38*
4,1,40,-.008,.009,
.008,.009,
.008347,.00897,
.008684,.008879,
.009,.008732,
.009286,.008532,
.009532,.008286,
.009732,.008,
.009879,.007684,
.00997,.007347,
.01,.007,
.01,-.007,
.00997,-.007347,
.009879,-.007684,
.009732,-.008,
.009532,-.008286,
.009286,-.008532,
.009,-.008732,
.008684,-.008879,
.008347,-.00897,
.008,-.009,
-.008,-.009,
-.008347,-.00897,
-.008684,-.008879,
-.009,-.008732,
-.009286,-.008532,
-.009532,-.008286,
-.009732,-.008,
-.009879,-.007684,
-.00997,-.007347,
-.01,-.007,
-.01,.007,
-.00997,.007347,
-.009879,.007684,
-.009732,.008,
-.009532,.008286,
-.009286,.008532,
-.009,.008732,
-.008684,.008879,
-.008347,.00897,
-.008,.009,
0.0*
%
%ADD38MACRO38*%
%ADD137C,.011*%
%ADD138C,.014*%
%ADD139C,.025*%
%ADD140C,.018*%
%ADD141C,.004*%
%ADD142C,.006*%
%ADD143C,.005*%
%ADD144C,.007*%
%ADD145C,.0035*%
%ADD146C,.008*%
%ADD147C,.0045*%
%ADD148C,.0055*%
%ADD149C,.0085*%
%ADD150C,.0095*%
%ADD160C,.03004*%
%ADD156C,.05204*%
%ADD152C,.04404*%
%ADD165C,.04604*%
%ADD155C,.09204*%
%ADD153R,.01X.01*%
%ADD161R,.01X.02*%
%ADD158R,.02X.01*%
%ADD159R,.021X.01*%
%ADD163R,.023X.01*%
%ADD157R,.025X.01*%
%ADD164R,.01X.02007*%
%ADD154C,.11004*%
%ADD151C,.15004*%
%ADD162R,.0453X.02956*%
G75*
%LPD*%
G75*
G36*
G01X82500Y34000D02*
X81000Y35500D01*
Y39000D01*
X82000Y40000D01*
Y41000D01*
X79000Y44000D01*
Y55500D01*
X77500Y57000D01*
X71000D01*
X67000Y61000D01*
X5000D01*
X3000Y63000D01*
Y111500D01*
X4000Y112500D01*
X14500D01*
X15500Y111500D01*
Y100500D01*
X16500Y99500D01*
X22499D01*
G02X22899Y99090I0J-400D01*
G03X22898Y99050I1600J-60D01*
G01Y96750D01*
G03X24279Y95164I1601J0D01*
G01X24345Y95155D01*
X25000Y94500D01*
X35500D01*
X36000Y94000D01*
Y91606D01*
X34995Y90602D01*
X32994D01*
X32207Y89814D01*
X32093Y89702D01*
X30400D01*
G03X29719Y89525I1J-1402D01*
G01X29674Y89500D01*
X29526D01*
X29481Y89525D01*
G03X28800Y89702I-682J-1225D01*
G01X27000D01*
G03X26319Y89525I1J-1402D01*
G01X26274Y89500D01*
X26000D01*
X25500Y89000D01*
Y83000D01*
X26198Y82302D01*
Y81445D01*
G03Y81355I2202J-45D01*
G01Y81195D01*
X26207Y81186D01*
X26216Y81119D01*
G03X30595Y81569I2184J281D01*
G02X30994Y82000I399J31D01*
G01X33500D01*
X35216Y83716D01*
X35282Y83726D01*
G03X36811Y84534I-382J2574D01*
G01X36871Y84598D01*
X36917D01*
X40917Y88598D01*
X41200D01*
G03X42702Y89500I0J1702D01*
G01X47500D01*
X48500Y90500D01*
Y112500D01*
X46000Y115000D01*
X37000D01*
X36000Y114000D01*
X23500D01*
X23106Y114394D01*
X23139Y114507D01*
G03X23202Y114950I-1539J445D01*
G01Y117250D01*
G03X23000Y118028I-1602J-1D01*
G01Y119500D01*
X25000Y121500D01*
X34000D01*
X36000Y119500D01*
X46500D01*
X47182Y118818D01*
G03X49473Y117398I2318J1182D01*
G01X49555Y117397D01*
X50398Y116554D01*
Y115200D01*
G03X51800Y113798I1402J0D01*
G01X52202D01*
X52500Y113500D01*
X60500D01*
X61241Y112759D01*
Y107572D01*
X61500D01*
Y91000D01*
X60082Y89582D01*
X60041Y89567D01*
G03X59698Y85593I759J-2067D01*
G01Y82598D01*
X60500D01*
Y79000D01*
X62000Y77500D01*
X86500D01*
X90500Y73500D01*
X101500D01*
X102000Y73000D01*
Y66124D01*
X99034D01*
Y63168D01*
X102000D01*
Y62000D01*
X102698Y61302D01*
Y61300D01*
X108000Y55998D01*
Y43500D01*
X106000Y41500D01*
Y39500D01*
X107500Y38000D01*
Y35500D01*
X106500Y34500D01*
X98000D01*
X97000Y35500D01*
Y39000D01*
X98000Y40000D01*
Y41500D01*
X96500Y43000D01*
X91500D01*
X90000Y41500D01*
Y40000D01*
X91500Y38500D01*
Y35500D01*
X90000Y34000D01*
X82500D01*
G37*
G36*
G01X40003Y101000D02*
X36452D01*
Y101452D01*
X27948D01*
Y101000D01*
X18000D01*
X17000Y102000D01*
Y111500D01*
X18000Y112500D01*
X36500D01*
X37348Y113348D01*
X37452D01*
Y113452D01*
X37500Y113500D01*
X46000D01*
X47500Y112000D01*
Y101500D01*
X47000Y101000D01*
X42997D01*
X42960Y101153D01*
G03X40040I-1460J-353D01*
G01X40003Y101000D01*
G37*
G36*
G01X21600Y126848D02*
G03X21605Y126849I-306J1541D01*
G02X21805Y126667I1J-200D01*
G03X21975Y126119I1395J132D01*
G01X22000Y126074D01*
Y125926D01*
X21975Y125881D01*
G03X21798Y125200I1225J-682D01*
G01Y123400D01*
G03X22000Y122676I1402J1D01*
G01Y120199D01*
X21798Y119998D01*
Y114798D01*
X21500Y114500D01*
X4000D01*
X3500Y115000D01*
Y128500D01*
X4500Y129500D01*
X15000D01*
X17000Y127500D01*
X17107D01*
X17167Y127428D01*
G03X18400Y126848I1233J1021D01*
G01X21600D01*
G37*
G36*
G01X21500Y151000D02*
Y136593D01*
G02X20993Y136208I-400J0D01*
G03X18421Y135500I-693J-2508D01*
G01X4000D01*
X3000Y136500D01*
Y150500D01*
X4500Y152000D01*
X20500D01*
X21500Y151000D01*
G37*
G36*
G01X4000Y153500D02*
X3000Y154500D01*
Y165000D01*
X4000Y166000D01*
X17000D01*
X21500Y161500D01*
Y154500D01*
X20500Y153500D01*
X4000D01*
G37*
G36*
G01X86500Y269000D02*
G02X86100Y269415I0J400D01*
G03X85500Y271013I-2200J86D01*
G01Y272500D01*
X83000Y275000D01*
X82706D01*
X82670Y275014D01*
G03X80730I-970J-2414D01*
G01X80694Y275000D01*
X80368D01*
Y275217D01*
X80371Y275233D01*
G03X76005Y275431I-2171J368D01*
G02X75606Y275000I-399J-31D01*
G01X74500D01*
X72598Y273098D01*
G03X72308Y272809I1403J-1697D01*
G01X72302Y272802D01*
X70000Y270500D01*
Y270070D01*
X69967Y270020D01*
G03X71249Y266668I1833J-1220D01*
G01X71398Y266629D01*
Y265399D01*
X71000Y265000D01*
X68500D01*
X67500Y264000D01*
Y259398D01*
G03Y259202I2600J-98D01*
G01Y257000D01*
X68500Y256000D01*
Y252500D01*
X68000Y252000D01*
X65924D01*
G03X65200Y252202I-725J-1200D01*
G01X63799D01*
X63502Y252498D01*
Y254200D01*
G03X63500Y254261I-1401J-15D01*
G01Y255000D01*
X63000Y255500D01*
X62625D01*
X62591Y255513D01*
G03X62100Y255602I-492J-1313D01*
G01X60500D01*
G03X60484Y255601I79J-1397D01*
G01X60400Y255600D01*
X60000Y256000D01*
Y262500D01*
X64798Y267298D01*
X65100D01*
G03X66502Y268700I0J1402D01*
G01Y270300D01*
G03X66313Y271001I-1401J-2D01*
G03X66895Y272327I-1613J1499D01*
G01X66901Y272401D01*
X67682Y273182D01*
X67715Y273197D01*
G03X68803Y274285I-915J2003D01*
G01X68818Y274318D01*
X69000Y274500D01*
Y275110D01*
G03Y275290I-2200J90D01*
G01Y276000D01*
X68718Y276282D01*
X68705Y276305D01*
G03X65532Y277000I-1905J-1105D01*
G01X58000D01*
X55500Y274500D01*
Y273361D01*
G03X55498Y273300I1399J-76D01*
G01Y271999D01*
X55201Y271702D01*
X53900D01*
G03X53176Y271500I1J-1402D01*
G01X51612D01*
G03X48082Y271082I-1612J-1500D01*
G01X47500Y270500D01*
Y253000D01*
X47101Y252602D01*
X44400D01*
G03X42943Y252050I1J-2202D01*
G01X42886Y252000D01*
X42500D01*
X41500Y251000D01*
X40500D01*
X40000Y251500D01*
Y259000D01*
X39000Y260000D01*
X26000D01*
X19500Y266500D01*
Y270000D01*
X18000Y271500D01*
X16000D01*
X14500Y270000D01*
Y267000D01*
X13500Y266000D01*
X9500D01*
X9000Y266500D01*
X7000D01*
X6000Y265500D01*
Y259500D01*
X6500Y259000D01*
X9000D01*
X9500Y259500D01*
X11000D01*
X11500Y259000D01*
Y254500D01*
X11000Y254000D01*
X9500D01*
X9000Y254500D01*
X6500D01*
X6000Y254000D01*
Y247500D01*
X6500Y247000D01*
X8500D01*
X9500Y248000D01*
X10500D01*
X11500Y247000D01*
Y242500D01*
X11000Y242000D01*
X9500D01*
X9000Y242500D01*
X6500D01*
X6000Y242000D01*
Y235500D01*
X6500Y235000D01*
X10000D01*
X11000Y234000D01*
Y230000D01*
X13500Y227500D01*
X18000D01*
X28500Y217000D01*
X30576D01*
G03X31300Y216798I725J1200D01*
G01X32700D01*
G03X33381Y216975I-1J1402D01*
G01X33426Y217000D01*
X33574D01*
X33619Y216975D01*
G03X34300Y216798I682J1225D01*
G01X35700D01*
G03X36424Y217000I-1J1402D01*
G01X38500D01*
X40000Y218500D01*
Y225000D01*
X40500Y225500D01*
X42000D01*
X48923Y218577D01*
X48910Y218480D01*
G03X48898Y218300I1390J-183D01*
G01Y216700D01*
G03X48987Y216209I1402J1D01*
G01X49000Y216175D01*
Y216000D01*
X48000Y215000D01*
X34000D01*
X33000Y214000D01*
Y207500D01*
X31750Y206250D01*
X30702D01*
Y207700D01*
G03X29300Y209102I-1402J0D01*
G01X27500D01*
G03X26700Y208851I0J-1402D01*
G03X25900Y209102I-800J-1151D01*
G01X24100D01*
G03X23858Y209080I5J-1402D01*
G01X23756Y209063D01*
X23516Y209302D01*
X23302D01*
Y210900D01*
G03X21900Y212302I-1402J0D01*
G01X20100D01*
G03X18846Y211526I0J-1401D01*
G01X18709D01*
X18683Y211500D01*
X18000D01*
X17201Y210701D01*
X17126Y210696D01*
G03X15418Y206304I174J-2596D01*
G01Y204777D01*
G03X15500Y201356I1426J-1677D01*
G01Y197500D01*
X14500Y196500D01*
X4501D01*
X3001Y198000D01*
Y234501D01*
X3000Y234502D01*
Y286500D01*
X4000Y287500D01*
X86500D01*
X87500Y286500D01*
Y280500D01*
X93000Y275000D01*
Y269500D01*
X92500Y269000D01*
X86500D01*
G37*
G36*
G01X28852Y143000D02*
Y143652D01*
X23348D01*
X23000Y144000D01*
Y163000D01*
X24000Y164000D01*
X34500D01*
X37000Y161500D01*
Y159325D01*
X36987Y159291D01*
G03X36898Y158800I1313J-492D01*
G01Y157200D01*
G03X36987Y156709I1402J1D01*
G01X37000Y156675D01*
Y156500D01*
X36000Y155500D01*
Y143500D01*
X35500Y143000D01*
X28852D01*
G37*
G36*
G01X38202Y159103D02*
Y161998D01*
X38000Y162201D01*
Y162500D01*
X35500Y165000D01*
X35201D01*
X34998Y165202D01*
X25798D01*
X25500Y165500D01*
Y170000D01*
X25574Y170074D01*
X28091D01*
X29218Y171200D01*
X30110D01*
Y177911D01*
X30235Y177962D01*
G03X30910Y178398I-837J2037D01*
G01X31052Y178531D01*
X31304Y178279D01*
X31300Y178191D01*
G03X34879Y179817I2200J-91D01*
G01X34804Y179973D01*
X34850Y180100D01*
G03X35188Y180666I-1700J1399D01*
G01X35203Y180703D01*
X36298Y181798D01*
X36400D01*
G03X37802Y183200I0J1402D01*
G01Y184798D01*
X39800D01*
G03X41014Y185500I0J1401D01*
G01X53000D01*
X54209Y184291D01*
X54217Y184220D01*
G03X55560Y182877I1503J160D01*
G01X55631Y182869D01*
X58651Y179849D01*
G02X58435Y179171I-282J-283D01*
G03X60971Y176635I365J-2171D01*
G02X61649Y176851I395J-66D01*
G01X63000Y175500D01*
Y169000D01*
X62500Y168500D01*
X61500D01*
X50000Y157000D01*
Y133000D01*
X44702Y127702D01*
X44198D01*
Y125198D01*
X44000Y125000D01*
X42592D01*
X42541Y125125D01*
G03X40576Y126500I-2041J-825D01*
G01X40497Y126503D01*
X39500Y127500D01*
Y130000D01*
X37000Y132500D01*
Y142799D01*
X37202Y143002D01*
Y155002D01*
X38202Y156002D01*
Y156897D01*
X38112Y157133D01*
G02X38102Y157178I188J65D01*
G01Y158822D01*
G02X38112Y158867I198J-20D01*
G01X38202Y159103D01*
G37*
G36*
G01X64500Y34500D02*
X62000D01*
X61000Y35500D01*
Y58500D01*
X62000Y59500D01*
X66000D01*
X70500Y55000D01*
X76500D01*
X77000Y54500D01*
Y45500D01*
X71750Y40250D01*
X65250D01*
X64500Y39500D01*
Y36000D01*
X65000Y35500D01*
Y35000D01*
X64500Y34500D01*
G37*
G36*
G01X66344Y100532D02*
Y100632D01*
X62367D01*
X62052Y100948D01*
Y112952D01*
X62000D01*
Y121000D01*
X62998Y121998D01*
X64234D01*
G03X66768Y122000I1266J1802D01*
G01X80000D01*
X81500Y120500D01*
Y102000D01*
X82500Y101000D01*
Y94000D01*
X82000Y93500D01*
X76500D01*
X76000Y94000D01*
Y98500D01*
X74000Y100500D01*
X70528D01*
G03X67962Y100532I-1293J-765D01*
G01X66344D01*
G37*
G36*
G01X67000Y136500D02*
X66500Y137000D01*
Y141000D01*
X66452Y141048D01*
Y141352D01*
X66148D01*
X65000Y142500D01*
X59301D01*
G03X56718Y142532I-1301J-750D01*
G01X54844D01*
Y142632D01*
X51368D01*
X51000Y143000D01*
Y156000D01*
X61500Y166500D01*
X68500D01*
X69648Y167648D01*
X69952D01*
Y167952D01*
X70000Y168000D01*
Y171500D01*
X70500Y172000D01*
X73500D01*
X74000Y171500D01*
Y166500D01*
X70000Y162500D01*
Y144500D01*
X74000Y140500D01*
Y138102D01*
G03X73121Y137500I1000J-2402D01*
G01X71000D01*
X70000Y136500D01*
X67000D01*
G37*
G36*
G01X51700Y252602D02*
G03X50900Y252351I0J-1402D01*
G03X50100Y252602I-800J-1151D01*
G01X49000D01*
Y270298D01*
X55498D01*
X55713Y270513D01*
X55772Y270525D01*
G03X56902Y271900I-272J1375D01*
G01Y273300D01*
G03X56844Y273697I-1402J-2D01*
G01X56811Y273811D01*
X57000Y274000D01*
X58500D01*
X58923Y273577D01*
X58910Y273480D01*
G03X58898Y273300I1390J-183D01*
G01Y271700D01*
G03X60300Y270298I1402J0D01*
G01X61898D01*
Y268700D01*
G03X61987Y268209I1402J1D01*
G01X62000Y268175D01*
Y266199D01*
X58798Y262998D01*
Y256432D01*
G02X58307Y256043I-400J0D01*
G03X56455Y255643I-506J-2143D01*
G01X56401Y255602D01*
X56195D01*
X53195Y252602D01*
X51700D01*
G37*
G36*
G01X77998Y185700D02*
G03X79400Y184298I1402J0D01*
G01X79702D01*
X80000Y184000D01*
X87278D01*
X87304Y183993D01*
G03X88696I696J2507D01*
G01X88722Y184000D01*
X128000D01*
X129000Y183000D01*
Y172500D01*
X128000Y171500D01*
X76000D01*
X74636Y172864D01*
G02X74615Y173407I283J283D01*
G03X75002Y174450I-1215J1044D01*
G01Y176750D01*
G03X73667Y178329I-1601J0D01*
G01X73500Y178357D01*
Y188000D01*
X74000Y188500D01*
X77222D01*
G03X78000Y187998I1777J1900D01*
G01Y187361D01*
G03X77998Y187300I1399J-76D01*
G01Y185700D01*
G37*
G36*
G01X115999Y85000D02*
X95500D01*
X94000Y86500D01*
Y98000D01*
X95000Y99000D01*
X116000D01*
X117000Y98000D01*
Y91736D01*
X116198Y90935D01*
Y85200D01*
X115999Y85000D01*
G37*
G36*
G01X116357Y126008D02*
G03X117500Y123538I2143J-508D01*
G01Y119000D01*
X119000Y117500D01*
X125500D01*
X126498Y116502D01*
Y101998D01*
X125000Y100500D01*
X92500D01*
X91500Y99500D01*
X87500D01*
X85500Y101500D01*
Y123000D01*
X89000Y126500D01*
X115968D01*
G02X116357Y126008I0J-400D01*
G37*
G36*
G01X89000Y128500D02*
X88000Y129500D01*
Y144000D01*
X88500Y144500D01*
X104000D01*
X105000Y143500D01*
Y140000D01*
X105581Y139419D01*
G03X106119Y138881I1369J831D01*
G01X106500Y138500D01*
X116500D01*
X118660Y136340D01*
X118619Y136221D01*
G03X119618Y133582I2081J-721D01*
G01X120000Y133200D01*
X120752D01*
X120954Y132998D01*
X121802D01*
X122298Y132502D01*
Y130898D01*
X122002Y130602D01*
X120700D01*
G03X120639Y130600I15J-1401D01*
G01X119361D01*
G03X119300Y130602I-76J-1399D01*
G01X117700D01*
G03X117639Y130600I15J-1401D01*
G01X117600D01*
X117531Y130591D01*
G03X116298Y129200I168J-1391D01*
G01Y128500D01*
X89000D01*
G37*
G36*
G01X82000Y137500D02*
X81500Y138000D01*
Y138339D01*
G03X81502Y138400I-1399J76D01*
G01Y140000D01*
G03X81500Y140061I-1401J-15D01*
G01Y145500D01*
X79500Y147500D01*
Y167500D01*
X82000Y170000D01*
X95175D01*
X95209Y169987D01*
G03X95700Y169898I492J1313D01*
G01X97300D01*
G03X97791Y169987I-1J1402D01*
G01X97825Y170000D01*
X111000D01*
X111500Y169500D01*
Y162000D01*
X110000Y160500D01*
Y145500D01*
X109500Y145000D01*
X107000D01*
X106000Y146000D01*
X87500D01*
X83500Y142000D01*
Y138000D01*
X83000Y137500D01*
X82000D01*
G37*
G36*
G01X126000Y262000D02*
X125000Y261000D01*
X109000D01*
X108000Y262000D01*
Y273050D01*
X104500Y276550D01*
X93850D01*
X88900Y281500D01*
Y285700D01*
X90200Y287000D01*
X124300D01*
X126000Y285300D01*
Y262000D01*
G37*
G36*
G01X115039Y193500D02*
X111500D01*
X110000Y195000D01*
Y200500D01*
X107302Y203198D01*
Y205302D01*
X108000Y206000D01*
X111500D01*
X112342Y206842D01*
X112398Y206855D01*
G03X112821Y207000I-499J2145D01*
G01X116500D01*
X117000Y206500D01*
Y194500D01*
X116097Y193597D01*
X116002Y193608D01*
G03X115070Y193510I-241J-2189D01*
G01X115039Y193500D01*
G37*
G36*
G01X112613Y241500D02*
X112412Y241702D01*
X106100D01*
G03X105574Y241599I1J-1402D01*
G01X105451Y241549D01*
X105000Y242000D01*
Y246000D01*
X105498Y246498D01*
X105712D01*
X106457Y247243D01*
G03X106677Y247500I-1558J1556D01*
G01X118000D01*
X123500Y242000D01*
Y221000D01*
X123000Y220500D01*
Y220326D01*
X122975Y220281D01*
G03X122798Y219600I1225J-682D01*
G01Y218798D01*
X122500Y218500D01*
X119500D01*
X119186Y218814D01*
X119175Y218873D01*
G03X118073Y219975I-1375J-273D01*
G01X118014Y219986D01*
X115000Y223000D01*
Y225322D01*
G03Y225478I-2200J78D01*
G01Y232732D01*
G03X115302Y233600I-1100J869D01*
G01Y235400D01*
G03X115051Y236200I-1402J0D01*
G03X115302Y237000I-1151J800D01*
G01Y238800D01*
G03X114422Y240101I-1402J0D01*
G01X114384Y240116D01*
X113000Y241500D01*
X112613D01*
G37*
G36*
G01X119854Y146102D02*
X119223Y145470D01*
X119163Y145458D01*
G03X118200Y145000I436J-2158D01*
G01X113000D01*
X111752Y146248D01*
Y147750D01*
G03X111742Y147926I-1602J-3D01*
G01X111741Y147937D01*
Y148148D01*
X111752D01*
Y157852D01*
X111500D01*
Y159500D01*
X113000Y161000D01*
Y169000D01*
X113500Y169500D01*
X123200D01*
X123700Y169000D01*
Y158500D01*
X121600Y156400D01*
Y155725D01*
X121587Y155691D01*
G03X121498Y155200I1313J-492D01*
G01Y153400D01*
G03X121587Y152909I1402J1D01*
G01X121600Y152875D01*
Y152325D01*
X121587Y152291D01*
G03X121498Y151800I1313J-492D01*
G01Y150000D01*
G03X121587Y149509I1402J1D01*
G01X121600Y149475D01*
Y148825D01*
X121587Y148791D01*
G03X121498Y148300I1313J-492D01*
G01Y146998D01*
X120602Y146102D01*
X119854D01*
G37*
G36*
G01X151000Y213898D02*
G03X151491Y213987I-1J1402D01*
G01X151525Y214000D01*
X151875D01*
X151909Y213987D01*
G03X152400Y213898I492J1313D01*
G01X154000D01*
G03X154491Y213987I-1J1402D01*
G01X154525Y214000D01*
X155500D01*
X159000Y217500D01*
Y237500D01*
X159500Y238000D01*
X165000D01*
X165110Y237890D01*
Y233498D01*
X165502D01*
X166000Y233000D01*
X169000D01*
X169500Y232500D01*
Y216101D01*
G03X169148Y215100I1250J-1002D01*
G01Y213862D01*
X168287Y213000D01*
X161500D01*
X160000Y211500D01*
X155112D01*
G03X151944Y211558I-1612J-1500D01*
G01X151886Y211500D01*
X151702D01*
X151642Y211567D01*
G03X148300Y211500I-1642J-1467D01*
G01X144000D01*
X142547Y210047D01*
X142492Y210034D01*
G03X140854Y208396I505J-2143D01*
G01X140841Y208341D01*
X129500Y197000D01*
Y190000D01*
X126500Y187000D01*
X111000D01*
X110577Y187423D01*
X110590Y187520D01*
G03X110602Y187700I-1390J183D01*
G01Y189300D01*
G03X110590Y189480I-1402J-3D01*
G01X110577Y189577D01*
X113000Y192000D01*
X117500D01*
X119000Y193500D01*
Y205800D01*
X126284Y213084D01*
X126322Y213099D01*
G03X127202Y214400I-522J1301D01*
G01Y215702D01*
X127500Y216000D01*
X147000D01*
X148039Y214961D01*
X148053Y214911D01*
G03X149400Y213898I1347J389D01*
G01X151000D01*
G37*
G36*
G01X158000Y238199D02*
X157798Y237998D01*
Y220298D01*
X155000Y217500D01*
Y215500D01*
X154702Y215202D01*
X149498D01*
X149000Y215699D01*
Y217000D01*
X148500Y217500D01*
X126325D01*
X126291Y217513D01*
G03X125800Y217602I-492J-1313D01*
G01X124398D01*
X124000Y218000D01*
Y218171D01*
X124022Y218214D01*
G03X124093Y218369I-1419J744D01*
G01X124108Y218409D01*
X124202Y218502D01*
Y219702D01*
X124500Y220000D01*
Y220301D01*
X124702Y220502D01*
Y227877D01*
X124712Y227909D01*
G03Y229591I-2462J841D01*
G01X124702Y229623D01*
Y232127D01*
X124712Y232159D01*
G03Y233841I-2462J841D01*
G01X124702Y233873D01*
Y236427D01*
X124712Y236459D01*
G03Y238141I-2462J841D01*
G01X124702Y238173D01*
Y240627D01*
X124712Y240659D01*
G03Y242341I-2462J841D01*
G01X124702Y242373D01*
Y242498D01*
X124616Y242583D01*
X124601Y242614D01*
G03X124525Y242763I-2355J-1107D01*
G01X124500Y242808D01*
Y243000D01*
X121052Y246448D01*
Y246502D01*
X120998D01*
X118500Y249000D01*
X117500D01*
X115500Y251000D01*
Y257500D01*
X116500Y258500D01*
X129500D01*
X130798Y257202D01*
Y256938D01*
X141562D01*
X142500Y256000D01*
Y243500D01*
X143500Y242500D01*
X156500D01*
X158000Y241000D01*
Y238199D01*
G37*
G36*
G01X149100Y166100D02*
X149031Y166091D01*
G03X147809Y164869I169J-1391D01*
G01X147800Y164800D01*
X147500Y164500D01*
X146256D01*
X146255Y164502D01*
X136538D01*
X134540Y166500D01*
Y183040D01*
X140400Y188900D01*
X156000D01*
X156300Y188600D01*
Y183500D01*
X155522Y182722D01*
X153838D01*
Y182200D01*
X148200D01*
X147600Y181600D01*
Y179579D01*
G03X150617Y175400I1800J-1879D01*
G01X155600D01*
X156800Y174200D01*
X158300D01*
X158598Y173902D01*
Y169978D01*
X159000D01*
Y169000D01*
X158022Y168022D01*
X156478D01*
X156000Y168500D01*
Y171400D01*
X155504Y171896D01*
G03X150964Y169414I-2404J-996D01*
G01X151000Y169362D01*
Y168826D01*
X150975Y168781D01*
G03X150798Y168100I1225J-682D01*
G01Y166298D01*
X150602Y166102D01*
X149200D01*
G03X149139Y166100I15J-1401D01*
G01X149100D01*
G37*
G36*
G01X152500Y249000D02*
X145500D01*
X144500Y250000D01*
Y257000D01*
X143500Y258000D01*
X142802D01*
Y258162D01*
X142037D01*
X141998Y258202D01*
X131798D01*
X131500Y258500D01*
Y261500D01*
X131898Y261898D01*
X142641D01*
Y262141D01*
X143000Y262500D01*
Y267500D01*
X139500Y271000D01*
Y273000D01*
X140500Y274000D01*
X151500D01*
X153000Y272500D01*
Y249500D01*
X152500Y249000D01*
G37*
G36*
G01X135060Y263440D02*
X135000Y263500D01*
Y267675D01*
X135013Y267709D01*
G03X135102Y268200I-1313J492D01*
G01Y269800D01*
G03X135014Y270287I-1402J-2D01*
G01X135002Y270321D01*
Y272112D01*
X135000Y272113D01*
Y273000D01*
X136000Y274000D01*
X137000D01*
X138298Y272701D01*
Y270502D01*
X138500Y270301D01*
Y269500D01*
X141500Y266500D01*
Y263500D01*
X141440Y263440D01*
X135060D01*
G37*
G36*
G01X161800Y152998D02*
G03X161861Y153000I-15J1401D01*
G01X163339D01*
G03X163400Y152998I76J1399D01*
G01X165200D01*
G03X165261Y153000I-15J1401D01*
G01X165500D01*
X165539Y153039D01*
X165589Y153053D01*
G03X166300Y153531I-389J1347D01*
G03X166600Y153498I302J1369D01*
G01X168200D01*
G03X169602Y154900I0J1402D01*
G01Y156083D01*
X169604Y156086D01*
Y156096D01*
X169607Y156098D01*
X172902D01*
X173000Y156000D01*
Y154000D01*
X172500Y153500D01*
X171500D01*
X170962Y152962D01*
X170418D01*
Y146598D01*
X171402D01*
X171500Y146500D01*
X174000D01*
X174500Y146000D01*
Y145000D01*
X173000Y143500D01*
Y143192D01*
X172848Y143041D01*
Y141348D01*
X172500Y141000D01*
X162000D01*
X161500Y141500D01*
Y147500D01*
X159684Y149316D01*
X159673Y149380D01*
G03X159000Y150637I-2173J-355D01*
G01Y152500D01*
X159500Y153000D01*
X159939D01*
G03X160000Y152998I76J1399D01*
G01X161800D01*
G37*
G36*
G01X179000Y151700D02*
X180838Y153538D01*
X181382D01*
Y154082D01*
X183500Y156200D01*
Y168000D01*
X182918Y168582D01*
G03X182100Y169408I-1918J-1082D01*
G01Y172026D01*
G03X182440Y172897I-1169J958D01*
G01Y172910D01*
X182441Y172914D01*
G03Y173056I-1510J71D01*
G01X182440Y173061D01*
Y173064D01*
X182439Y173088D01*
G03X182100Y173943I-1508J-103D01*
G01Y174675D01*
X182113Y174709D01*
G03X182202Y175200I-1313J492D01*
G01Y176800D01*
G03X180800Y178202I-1402J0D01*
G01X175788D01*
X174843Y177257D01*
G03X174200Y175776I1557J-1556D01*
G01X174197Y175697D01*
X174000Y175500D01*
X163900D01*
X160100Y179300D01*
Y181600D01*
X164500Y186000D01*
X169385D01*
G03X170260Y185798I876J1800D01*
G01X171260D01*
G03X172097Y185982I-1J2002D01*
G01X172136Y186000D01*
X172387D01*
X175088Y183298D01*
X182391D01*
G03X183500Y182998I1110J1902D01*
G01X187502D01*
X187682Y182818D01*
X187696Y182791D01*
G03X188500Y181874I2304J1209D01*
G01Y180015D01*
G03X187648Y178600I749J-1415D01*
G01Y175400D01*
G03X189129Y173803I1602J0D01*
G01X189203Y173797D01*
X193898Y169102D01*
Y169098D01*
X194044Y168952D01*
Y157508D01*
X194050Y157502D01*
Y153450D01*
X188950Y148350D01*
X180250D01*
X179327Y149273D01*
X179312Y149322D01*
G03X179000Y149968I-2112J-622D01*
G01Y151700D01*
G37*
G36*
G01X168698Y195998D02*
X168502Y195802D01*
X166700D01*
G03X166019Y195625I1J-1402D01*
G01X165974Y195600D01*
X165361D01*
G03X165300Y195602I-76J-1399D01*
G01X163898D01*
X163702Y195798D01*
Y197050D01*
G03X163400Y197985I-1602J-1D01*
G01Y199015D01*
G03X163702Y199950I-1300J936D01*
G01Y202250D01*
G03X163400Y203185I-1602J-1D01*
G01Y204800D01*
X164000Y205400D01*
X170800D01*
X172100Y204100D01*
Y201700D01*
X172498Y201302D01*
X172512Y201253D01*
G03X174050Y200098I1538J447D01*
G01X176350D01*
G03X177911Y201343I0J1601D01*
G01X177947Y201498D01*
X179600D01*
G03X179661Y201500I-15J1401D01*
G01X180939D01*
G03X181000Y201498I76J1399D01*
G01X182600D01*
G03X184002Y202900I0J1402D01*
G01Y203152D01*
X185350Y204500D01*
X186672D01*
G03X187600Y204148I929J1050D01*
G01X189200D01*
G03X190602Y205550I0J1402D01*
G01Y205992D01*
X191558Y206948D01*
X191652D01*
X192300Y206300D01*
Y201950D01*
X190500Y200150D01*
Y194825D01*
X190487Y194791D01*
G03X190398Y194300I1313J-492D01*
G01Y192700D01*
G03X190487Y192209I1402J1D01*
G01X190500Y192175D01*
Y191500D01*
X190000Y191000D01*
X188991D01*
X188943Y191029D01*
G03X186211Y191000I-1342J-2229D01*
G01X180575D01*
G03X179900Y191831I-1835J-801D01*
G01Y193900D01*
X175600Y198200D01*
X173051D01*
G03X171900Y198802I-1151J-799D01*
G01X170100D01*
G03X168698Y197400I0J-1402D01*
G01Y195998D01*
G37*
G36*
G01X175500Y211500D02*
X175000Y212000D01*
Y215500D01*
X170952Y219548D01*
Y232452D01*
X171000Y232500D01*
X175000D01*
X175998Y233498D01*
X176012D01*
Y237012D01*
X179000Y240000D01*
Y241522D01*
G03Y241678I-2200J78D01*
G01Y245500D01*
X180500Y247000D01*
X190500D01*
X191500Y246000D01*
Y219500D01*
X190500Y218500D01*
X180000D01*
X179000Y217500D01*
Y212000D01*
X178500Y211500D01*
X178421D01*
G03X176616Y211517I-921J-2000D01*
G01X176578Y211500D01*
X175500D01*
G37*
G36*
G01X212458Y255542D02*
X211000Y257000D01*
X181000D01*
X180252Y256252D01*
X180248D01*
Y256248D01*
X180000Y256000D01*
Y253500D01*
X176500Y250000D01*
X168500D01*
X168000Y250500D01*
Y266000D01*
X169500Y267500D01*
X221500D01*
X223000Y266000D01*
Y252500D01*
X221500Y251000D01*
X217000D01*
X214442Y253558D01*
X214429Y253612D01*
G03X212512Y255529I-2529J-612D01*
G01X212458Y255542D01*
G37*
G36*
G01X226000Y252000D02*
X225000Y253000D01*
Y266500D01*
X222500Y269000D01*
X170500D01*
X168500Y271000D01*
Y286500D01*
X169500Y287500D01*
X193147D01*
G02X193486Y286887I0J-400D01*
G03X206908I6711J-4210D01*
G02X207247Y287500I339J213D01*
G01X241500D01*
X250000Y279000D01*
Y266000D01*
X253000Y263000D01*
X258500D01*
X262000Y259500D01*
Y254213D01*
G03X261406Y252508I1600J-1513D01*
G01X261415Y252415D01*
X261000Y252000D01*
X226000D01*
G37*
G36*
G01X179000Y58000D02*
X178500Y58500D01*
Y61500D01*
X179000Y62000D01*
X182500D01*
X182948Y62448D01*
X183966D01*
X184216Y62698D01*
X185300D01*
G03X186000Y62886I-1J1402D01*
G03X186700Y62698I701J1214D01*
G01X188300D01*
G03X189000Y62886I-1J1402D01*
G03X189700Y62698I701J1214D01*
G01X191300D01*
G03X192000Y62886I-1J1402D01*
G03X192700Y62698I701J1214D01*
G01X194300D01*
G03X195567Y63500I0J1402D01*
G01X197500D01*
X198000Y63000D01*
Y61500D01*
X194500Y58000D01*
X179000D01*
G37*
G36*
G01X209000Y251000D02*
X208500Y250500D01*
X182000D01*
X181500Y251000D01*
Y255000D01*
X182000Y255500D01*
X208000D01*
X209000Y254500D01*
Y251000D01*
G37*
G36*
G01X207500Y102500D02*
X192000D01*
X191000Y103500D01*
Y107000D01*
X191500Y107500D01*
X207700D01*
X208500Y106700D01*
Y103500D01*
X207500Y102500D01*
G37*
G36*
G01X214100Y164500D02*
X215009Y165409D01*
X215100Y165402D01*
G03X215200Y165398I106J1398D01*
G01X216602D01*
X217000Y165000D01*
Y163500D01*
X216400Y162900D01*
Y156300D01*
X216202Y156102D01*
X212971D01*
X210994Y154125D01*
Y154124D01*
X210197Y153326D01*
X203274D01*
X202079Y154521D01*
X202069Y154583D01*
G03X200337Y156358I-2168J-383D01*
G01X200277Y156370D01*
X197648Y159000D01*
Y163948D01*
X199200Y165500D01*
X209500D01*
X210500Y164500D01*
X211150D01*
X211190Y164482D01*
G03X213346I1078J2368D01*
G01X213386Y164500D01*
X214100D01*
G37*
G36*
G01X211600Y193398D02*
G03X213002Y194800I0J1402D01*
G01Y195502D01*
X215435Y197935D01*
X215487Y197949D01*
G03X216551Y199013I-387J1451D01*
G01X216565Y199065D01*
X217000Y199500D01*
X220500D01*
X221000Y199000D01*
Y194500D01*
X221500Y194000D01*
X224000D01*
X224500Y193500D01*
Y188000D01*
X224246Y187746D01*
X221254D01*
X219902Y189098D01*
Y189200D01*
G03X218500Y190602I-1402J0D01*
G01X216900D01*
G03X215749Y190000I0J-1401D01*
G01X209509D01*
G03X206762Y190448I-1648J-1460D01*
G01X206629Y190371D01*
X204882Y192118D01*
X204867Y192159D01*
G03X203559Y193467I-2067J-759D01*
G01X203518Y193482D01*
X202000Y195000D01*
Y199000D01*
X202500Y199500D01*
X206000D01*
X206500Y199000D01*
Y196500D01*
X208684Y194316D01*
X208699Y194278D01*
G03X210000Y193398I1301J522D01*
G01X211600D01*
G37*
G36*
G01X200500Y205191D02*
Y207000D01*
X200450Y207050D01*
Y209750D01*
X198602Y211598D01*
Y211750D01*
G03X197001Y213352I-1602J0D01*
G01X196848D01*
X196500Y213700D01*
Y217000D01*
X197000Y217500D01*
X200000D01*
X206098Y211402D01*
Y210500D01*
G03X206189Y209938I1801J3D01*
G01X206198Y209907D01*
Y205177D01*
X206500Y205052D01*
Y201500D01*
X206000Y201000D01*
X202000D01*
X201402Y201598D01*
Y203751D01*
G03X200500Y205191I-1600J0D01*
G37*
G36*
G01X221500Y224000D02*
X219500Y222000D01*
X209500D01*
X208500Y223000D01*
Y247500D01*
X210000Y249000D01*
X224000D01*
X225000Y250000D01*
X260500D01*
X261000Y249500D01*
Y245500D01*
X259000Y243500D01*
Y237000D01*
X260500Y235500D01*
Y224500D01*
X260000Y224000D01*
X221500D01*
G37*
G36*
G01X246751Y199251D02*
X246500Y199000D01*
X245000D01*
X243500Y197500D01*
Y195000D01*
X241328Y192828D01*
G03X238880Y192833I-1228J-1828D01*
G01X238830Y192800D01*
X238600D01*
X237150Y191350D01*
Y188650D01*
X237000Y188500D01*
Y186500D01*
X238000Y185500D01*
Y179200D01*
X237200Y178400D01*
X232900D01*
X232482Y178818D01*
Y179166D01*
X231402Y180246D01*
Y180324D01*
X230250Y181476D01*
Y183750D01*
X226500Y187500D01*
Y194000D01*
X227000Y194500D01*
Y195500D01*
X227478Y195978D01*
X231406D01*
Y198180D01*
X227320D01*
X227000Y198500D01*
Y201500D01*
X227300Y201800D01*
X231400D01*
X232359Y202759D01*
X232450Y202752D01*
G03X233393Y203000I110J1498D01*
G01X246500D01*
X247000Y202500D01*
Y200517D01*
G03X246749Y199337I2350J-1117D01*
G01X246751Y199251D01*
G37*
G36*
G01X232500Y208500D02*
X232000Y209000D01*
X227000D01*
X226500Y208500D01*
Y205500D01*
X225500Y204500D01*
X223000D01*
X222000Y205500D01*
Y209500D01*
X222513Y210013D01*
X222573Y210025D01*
G03X223702Y211400I-273J1375D01*
G01Y211980D01*
X225120Y213398D01*
X226800D01*
G03X227291Y213487I-1J1402D01*
G01X227325Y213500D01*
X232711D01*
G03X234698Y213168I1389J2200D01*
G01X234807Y213193D01*
X237000Y211000D01*
X245500D01*
X247000Y209500D01*
X250500D01*
X251000Y209000D01*
Y205500D01*
X250500Y205000D01*
X233861D01*
G03X232683Y205747I-1301J-750D01*
G02X232500Y205946I17J199D01*
G01Y208500D01*
G37*
G36*
G01X226861Y218000D02*
G03X226800Y218002I-76J-1399D01*
G01X225200D01*
G03X225139Y218000I15J-1401D01*
G01X223500D01*
X223000Y218500D01*
Y222000D01*
X223500Y222500D01*
X258000D01*
X259000Y221500D01*
Y212500D01*
X257500Y211000D01*
X247500D01*
X246000Y212500D01*
X240500D01*
X236609Y216391D01*
X236595Y216440D01*
G03X232883Y218000I-2495J-740D01*
G01X226861D01*
G37*
G36*
G01X250499Y81002D02*
X245148Y75651D01*
Y75648D01*
X245000Y75500D01*
X244470D01*
X244420Y75533D01*
G03X241932Y75500I-1220J-1833D01*
G01X240000D01*
X238868Y76632D01*
X238853Y76676D01*
G03X238500Y77416I-3224J-1084D01*
G01Y81000D01*
X240000Y82500D01*
X246000D01*
X246898Y83398D01*
X246946D01*
X248146Y84598D01*
X251002D01*
X251904Y85500D01*
X254500D01*
X264000Y95000D01*
X285000D01*
X286242Y93758D01*
X286255Y93702D01*
G03X289747Y92458I2145J498D01*
G01X289801Y92500D01*
X290000D01*
X292399Y94898D01*
X292600D01*
G03X293751Y95500I0J1401D01*
G01X296193D01*
X296200Y95307D01*
G03X298336Y92840I2600J93D01*
G01X298500Y92810D01*
Y90000D01*
X296551Y88052D01*
X292430D01*
X290505Y86126D01*
X281705D01*
X281578Y86000D01*
X281500D01*
X280000Y84500D01*
X274000D01*
X271250Y87250D01*
X264750D01*
X259305Y81805D01*
X259176Y81871D01*
G03X255840Y81002I-1177J-2321D01*
G01X250499D01*
G37*
G36*
G01X258500Y201029D02*
X255492Y198022D01*
X248978D01*
X248100Y198900D01*
X248202Y199002D01*
Y200202D01*
X253000Y205000D01*
Y209000D01*
X253500Y209500D01*
X258000D01*
X258500Y209000D01*
Y201029D01*
G37*
G36*
G01X288500Y207500D02*
X285000Y211000D01*
X284319D01*
X284308Y211001D01*
G03X284115Y211012I-199J-1791D01*
G01X281489D01*
X280500Y212000D01*
Y214500D01*
X281500Y215500D01*
X283500D01*
X284500Y214500D01*
X287290D01*
X287301Y214313D01*
G03X288700Y212998I1399J87D01*
G01X289000D01*
X291400Y210598D01*
X291401D01*
X291500Y210500D01*
X292186D01*
X292231Y210475D01*
G03X294369I1069J1925D01*
G01X294414Y210500D01*
X294600D01*
X303600Y219500D01*
X314000D01*
X318000Y223500D01*
X326000D01*
X326500Y223000D01*
Y221500D01*
X326325Y221325D01*
X326301Y221311D01*
G03X325724Y220724I723J-1287D01*
G01X320500Y215500D01*
X319000D01*
X318000Y216500D01*
X317824D01*
X317784Y216520D01*
G03X316616I-584J-1220D01*
G01X316576Y216500D01*
X316500D01*
X316357Y216357D01*
X316349Y216351D01*
G03X316143Y216143I852J-1050D01*
G01X316000Y216000D01*
Y215924D01*
X315980Y215884D01*
G03X315848Y215266I1220J-584D01*
G01Y213134D01*
G03X318517Y212794I1352J-35D01*
G01X318553Y212948D01*
X320051D01*
X320500Y212500D01*
Y211786D01*
G03X320248Y210966I1100J-787D01*
G01Y208734D01*
G03X322906Y208352I1352J-34D01*
G01X322946Y208500D01*
X328237D01*
X329970Y206768D01*
Y206079D01*
X329390Y205500D01*
X326000D01*
X324500Y204000D01*
Y203049D01*
G03X324291Y202367I1142J-723D01*
G01X324288Y202288D01*
X324000Y202000D01*
X320500D01*
X315000Y196500D01*
Y193000D01*
X314500Y192500D01*
X308000D01*
X307000Y193500D01*
Y194776D01*
X307020Y194816D01*
G03Y195984I-1220J584D01*
G01X307000Y196024D01*
Y199000D01*
X309500Y201500D01*
Y204500D01*
X306500Y207500D01*
X288500D01*
G37*
G36*
G01X381175Y56000D02*
X381000D01*
X380500Y56500D01*
X357500D01*
X355002Y54002D01*
X334279D01*
X334277Y54000D01*
X331500D01*
X329000Y56500D01*
X322000D01*
X321500Y57000D01*
Y58000D01*
X320000Y59500D01*
X314000D01*
X312500Y58000D01*
Y57000D01*
X312000Y56500D01*
X311000D01*
X310500Y57000D01*
Y58000D01*
X309000Y59500D01*
X303500D01*
X302500Y58500D01*
X301857D01*
X294656Y65702D01*
X294500D01*
Y66000D01*
X296499Y67998D01*
X310513D01*
X310514Y68000D01*
X311000D01*
X315959Y72958D01*
X329542D01*
X330500Y72000D01*
Y63500D01*
X335500Y58500D01*
X352500D01*
X354998Y60998D01*
X381502D01*
X383500Y59000D01*
Y56500D01*
X383101Y56102D01*
X381700D01*
G03X381209Y56013I1J-1402D01*
G01X381175Y56000D01*
G37*
G36*
G01X336500Y60500D02*
X336000Y61000D01*
Y67408D01*
X336907Y68314D01*
X340684D01*
X342000Y66998D01*
X342001D01*
X342500Y66500D01*
X347999D01*
X350000Y64499D01*
Y61000D01*
X349500Y60500D01*
X336500D01*
G37*
G36*
G01X362858Y129000D02*
X363000D01*
X363500Y129500D01*
X364000D01*
X364500Y129000D01*
Y119000D01*
X364000Y118500D01*
X363000D01*
X362500Y119000D01*
Y120000D01*
X361500Y121000D01*
X359000D01*
X357000Y123000D01*
Y127500D01*
X356500Y128000D01*
X356391D01*
X356342Y128031D01*
G03X355116Y128000I-590J-930D01*
G01X353629D01*
G03X353398Y128126I-639J-898D01*
G01X353359Y128141D01*
X352000Y129500D01*
Y134000D01*
X351000Y135000D01*
Y136954D01*
X351148Y136994D01*
G03X352134Y138517I-348J1306D01*
G01X352118Y138618D01*
X353000Y139500D01*
X357500D01*
X358000Y139000D01*
Y138500D01*
X355500Y136000D01*
Y134500D01*
X356500Y133500D01*
X357000D01*
X360843Y129657D01*
X360858Y129619D01*
G03X362811Y128971I1253J509D01*
G01X362858Y129000D01*
G37*
G36*
G01X356697Y146000D02*
X360459D01*
X360516Y145897D01*
G03X362884I1184J652D01*
G01X362941Y146000D01*
X363500D01*
X364500Y145000D01*
X365500D01*
X366000Y145500D01*
X367000D01*
X367500Y145000D01*
X368500D01*
X369000Y145500D01*
X370000D01*
X370500Y145000D01*
Y138500D01*
X369500Y137500D01*
Y136500D01*
X370500Y135500D01*
Y132500D01*
X370000Y132000D01*
X365000D01*
X362000Y135000D01*
Y138500D01*
X363500Y140000D01*
Y140500D01*
X361000Y143000D01*
X357500D01*
X356613Y143887D01*
X356598Y143925D01*
G03X356000Y144605I-1256J-501D01*
G01Y145289D01*
X356103Y145346D01*
G03X356641Y145894I-656J1182D01*
G01X356697Y146000D01*
G37*
G36*
G01X381074Y49209D02*
X383104Y47179D01*
X383100Y47091D01*
G03X384842Y44846I2200J-91D01*
G01X385000Y44813D01*
Y37500D01*
X384000Y36500D01*
X379000D01*
X378000Y37500D01*
Y39000D01*
X376500Y40500D01*
X371000D01*
X370000Y41500D01*
Y48676D01*
G03X370202Y49400I-1200J725D01*
G01Y51200D01*
G03X370025Y51881I-1402J-1D01*
G01X370000Y51926D01*
Y52074D01*
X370025Y52119D01*
G03X370202Y52800I-1225J682D01*
G01Y53202D01*
X371000Y54000D01*
X379500D01*
X380000Y53500D01*
Y50500D01*
X381074Y49426D01*
Y49209D01*
G37*
G36*
G01X364500Y151161D02*
G02X364700Y151361I200J0D01*
G03X365099Y154005I0J1352D01*
G01X365051Y154020D01*
X364500Y154571D01*
Y157000D01*
X366000Y158500D01*
Y160000D01*
X364000Y162000D01*
X361000D01*
X359500Y163500D01*
Y164000D01*
X361000Y165500D01*
X364000D01*
X364500Y166000D01*
X365500D01*
X366000Y165500D01*
X367000D01*
X367500Y166000D01*
X368500D01*
X369000Y165500D01*
X375754D01*
G02X376152Y165132I-1J-400D01*
G03X378848I1348J108D01*
G02X379246Y165500I399J-32D01*
G01X379500D01*
X380000Y166000D01*
X381000D01*
X381500Y165500D01*
X382500D01*
X383000Y166000D01*
X384405D01*
G03X384668Y165818I838J930D01*
G01X384696Y165804D01*
X385000Y165500D01*
X389000D01*
X389500Y166000D01*
X390500D01*
X391000Y165500D01*
X392000D01*
X392500Y166000D01*
X393500D01*
X395500Y164000D01*
Y163500D01*
X395000Y163000D01*
X393999D01*
G03X392057I-971J-941D01*
G01X388000D01*
X387500Y163500D01*
X386915D01*
X386905Y163501D01*
G03X386649I-128J-1346D01*
G01X386639Y163500D01*
X386000D01*
X385500Y163000D01*
X385000D01*
X384500Y163500D01*
X384069D01*
X384044Y163507D01*
G03X383356I-344J-1308D01*
G01X383331Y163500D01*
X383000D01*
X382500Y163000D01*
X381500D01*
X381000Y163500D01*
X380000D01*
X378500Y162000D01*
X375500D01*
X375277Y161777D01*
X375246Y161762D01*
G03X374651Y161167I536J-1131D01*
G01X374636Y161136D01*
X374000Y160500D01*
X373932Y160492D01*
G03X373500Y157938I168J-1342D01*
G01Y156890D01*
G03Y154710I800J-1090D01*
G01Y150651D01*
G03Y148337I700J-1157D01*
G01Y146500D01*
X373065Y146065D01*
X372954Y146093D01*
G03X372119Y146018I-312J-1212D01*
G01X372079Y146000D01*
X370209D01*
X370208Y146002D01*
X370042D01*
X370003Y146020D01*
G03X368961I-521J-1139D01*
G01X368922Y146002D01*
X368792D01*
X368791Y146000D01*
X367500D01*
X364500Y149000D01*
Y151161D01*
G37*
G36*
G01X360687Y172130D02*
X360763Y172205D01*
G03X361068Y172510I-721J1026D01*
G01X362602Y174044D01*
Y174214D01*
X362634Y174263D01*
G03X361674Y176341I-1134J737D01*
G01X361500Y176363D01*
Y177000D01*
X361777Y177277D01*
X361806Y177291D01*
G03X362422Y177922I-607J1208D01*
G01X362500Y178000D01*
X366500D01*
X367000Y177500D01*
X367393D01*
X367418Y177494D01*
G03X367966I274J1067D01*
G01X367991Y177500D01*
X368000D01*
X368003Y177503D01*
X368047Y177518D01*
G03X368500Y179310I-355J1043D01*
G01Y180500D01*
X370500Y182500D01*
X372500D01*
X373500Y181500D01*
Y169500D01*
X373153Y169154D01*
X372380D01*
X372326Y169269D01*
G03X369820Y169136I-1226J-569D01*
G01X369774Y169000D01*
X369500D01*
X368500Y170000D01*
X367000D01*
X366500Y169500D01*
X365500D01*
X364222Y170778D01*
G03X363893Y171111I-1039J-698D01*
G01X363878Y171122D01*
X363500Y171500D01*
X362500D01*
X360500Y169500D01*
X359500D01*
X359000Y170000D01*
Y170500D01*
X360614Y172115D01*
G03X360642Y172130I-578J1113D01*
G01X360687D01*
G37*
G36*
G01X416000Y197500D02*
X414500Y196000D01*
X413286D01*
G03X411853Y196087I-786J-1100D01*
G01X411808Y196062D01*
X410014D01*
X409977Y196078D01*
G03X409018Y196025I-425J-1017D01*
G01X408973Y196000D01*
X407371D01*
X407326Y196025D01*
G03X406258I-534J-964D01*
G01X406213Y196000D01*
X403882D01*
G03X402052I-915J-995D01*
G01X396572D01*
X396547Y196007D01*
G03X395853I-347J-1307D01*
G01X395828Y196000D01*
X394491D01*
X394446Y196025D01*
G03X393378I-534J-964D01*
G01X393333Y196000D01*
X391731D01*
X391686Y196025D01*
G03X390618I-534J-964D01*
G01X390573Y196000D01*
X386500D01*
X385703Y196797D01*
X385689Y196847D01*
G03X383514Y197500I-1299J-377D01*
G01X381700D01*
X381119Y196919D01*
X381071Y196905D01*
G03X380165Y195999I389J-1295D01*
G01X380151Y195951D01*
X379500Y195300D01*
Y186800D01*
X378300Y185600D01*
X372900D01*
X371500Y187000D01*
Y187219D01*
X371508Y187247D01*
G03Y187875I-1056J314D01*
G01X371500Y187903D01*
Y190219D01*
X371508Y190247D01*
G03Y190875I-1056J314D01*
G01X371500Y190903D01*
Y191500D01*
X366000Y197000D01*
Y199000D01*
X366859Y199859D01*
X366898Y199874D01*
G03X367646Y200555I-506J1307D01*
G01X369152Y203569D01*
Y206152D01*
X370500Y207500D01*
X371500D01*
X371694Y207305D01*
Y204194D01*
X371000Y203500D01*
Y202000D01*
X373500Y199500D01*
Y197500D01*
X374000Y197000D01*
X374291D01*
X374341Y196968D01*
G03X375940Y197423I602J923D01*
G01X375954Y197454D01*
X376200Y197700D01*
Y199900D01*
X376600Y200300D01*
X377300D01*
X377680Y199919D01*
Y198180D01*
X377700Y198161D01*
Y197700D01*
X377953Y197447D01*
X377967Y197416D01*
G03X379925Y198426I994J476D01*
G01X379900Y198472D01*
Y199400D01*
X381955Y201455D01*
X382006Y201469D01*
G03X382774Y202237I-294J1062D01*
G01X382788Y202288D01*
X383000Y202500D01*
Y205500D01*
X382300Y206200D01*
Y207800D01*
X384000Y209500D01*
X385000D01*
X385500Y209000D01*
Y201500D01*
X387000Y200000D01*
X390500D01*
X391000Y199500D01*
X391959D01*
G03X392045I43J1101D01*
G01X393000D01*
X394000Y200500D01*
X395500D01*
X396500Y199500D01*
X398000D01*
X398500Y200000D01*
Y204031D01*
X398519Y204072D01*
G03Y205010I-997J469D01*
G01X398500Y205051D01*
Y205500D01*
X397800Y206200D01*
Y208100D01*
X400200Y210500D01*
X401000D01*
X401998Y209502D01*
Y205998D01*
X400500Y204500D01*
Y201000D01*
X400915Y200585D01*
G03X401230Y200265I926J597D01*
G01X401246Y200254D01*
X401500Y200000D01*
X402500D01*
X404500Y202000D01*
X406000D01*
X409000Y199000D01*
X411625D01*
G03X413502Y199932I787J771D01*
G01X413500Y199947D01*
Y201000D01*
X414000Y201500D01*
X415500D01*
X415944Y201056D01*
G03X416000Y199091I956J-956D01*
G01Y197500D01*
G37*
G36*
G01X373000Y136638D02*
Y137374D01*
X373123Y137425D01*
G03X373867Y138321I-481J1156D01*
G01X373879Y138379D01*
X374000Y138500D01*
Y139000D01*
X373500Y139500D01*
Y140500D01*
X375500Y142500D01*
X379405D01*
G03X379763Y142224I993J918D01*
G01X379790Y142210D01*
X380000Y142000D01*
Y141500D01*
X376500Y138000D01*
Y135000D01*
X376000Y134500D01*
X375000D01*
X373881Y135619D01*
X373869Y135678D01*
G03X373123Y136587I-1227J-247D01*
G01X373000Y136638D01*
G37*
G36*
G01X379947Y145628D02*
G03X378719Y146113I-1005J-747D01*
G01X378616Y146094D01*
X378163Y146547D01*
Y148524D01*
G03X378800Y149412I-686J1165D01*
G01X378812Y149471D01*
X379331Y149990D01*
X379373Y150005D01*
G03X379188Y152409I-430J1176D01*
G01X379128Y152421D01*
X377921Y153628D01*
Y154563D01*
X378203Y154845D01*
G03X378655Y155297I-703J1155D01*
G01X378845Y155487D01*
X385000D01*
X385962Y154525D01*
X385928Y154491D01*
Y150635D01*
X383921Y148628D01*
Y146128D01*
X383421Y145628D01*
X383087D01*
G03X381077I-1005J-747D01*
G01X379947D01*
G37*
G36*
G01X398563Y177537D02*
X398700Y177400D01*
Y175300D01*
X398100Y174700D01*
X395200D01*
X393300Y176600D01*
X390000D01*
X388900Y175500D01*
X387812D01*
G03X385391Y175506I-1212J-600D01*
G01X385377Y175477D01*
X385100Y175200D01*
X381600D01*
X381300Y175500D01*
Y176200D01*
X381900Y176800D01*
X382800D01*
X383465Y177465D01*
X383527Y177476D01*
G03X383831Y177578I-195J1085D01*
G01X383873Y177600D01*
X385551D01*
X385593Y177578D01*
G03X386591I499J983D01*
G01X386633Y177600D01*
X386800D01*
X387800Y178600D01*
X394400D01*
X395400Y179600D01*
X396500D01*
X397948Y178152D01*
X397963Y178118D01*
G03X398529Y177552I1009J443D01*
G01X398563Y177537D01*
G37*
G36*
G01X394000Y139063D02*
X395954Y141016D01*
X396546D01*
X397000Y140563D01*
X397390D01*
X397422Y140551D01*
G03X398262I420J1180D01*
G01X398294Y140563D01*
X398500D01*
X400500Y142563D01*
X401500D01*
X403500Y140563D01*
Y137063D01*
X404500Y136063D01*
Y135063D01*
X404000Y134563D01*
X401000D01*
X400500Y135063D01*
X400242D01*
X400192Y135096D01*
G03X398712I-740J-1132D01*
G01X398662Y135063D01*
X398500D01*
X397155Y133718D01*
X397139Y133707D01*
G03X396796Y133359I703J-1036D01*
G01X396500Y133063D01*
X392500D01*
X391550Y134013D01*
X391539Y134077D01*
G03X390636Y135139I-1334J-219D01*
G01X390500Y135185D01*
Y135934D01*
G03X391026Y137782I-652J1184D01*
G01X391000Y137828D01*
Y138063D01*
X390500Y138563D01*
Y139063D01*
X391000Y139563D01*
X391500D01*
X392000Y139063D01*
X392385D01*
X392426Y139044D01*
G03X393574I574J1224D01*
G01X393615Y139063D01*
X394000D01*
G37*
G36*
G01X400981Y146182D02*
G03X400351Y146019I1J-1301D01*
G01X400305Y145994D01*
X398417D01*
X398377Y146013D01*
G03X397307I-535J-1132D01*
G01X397267Y145994D01*
X395462D01*
X394412Y147044D01*
X394398Y147071D01*
G03X392017Y147084I-1194J-635D01*
G01X391212D01*
X390963Y147333D01*
X390953Y147347D01*
G03X390627Y147673I-1105J-779D01*
G01X390613Y147683D01*
X390222Y148074D01*
Y152959D01*
G02X390845Y153291I400J0D01*
G03X392725Y153921I697J1040D01*
G01X392740Y153964D01*
X392841Y154065D01*
G02X393501Y153915I283J-283D01*
G03X395865Y153921I1181J416D01*
G01X395880Y153964D01*
X396148Y154232D01*
X397153Y153228D01*
X397249D01*
X397290Y153207D01*
G03X397982Y155575I552J1124D01*
G01X397913Y155583D01*
X397483Y156013D01*
X397470Y156071D01*
G03X395014Y156526I-1322J-281D01*
G02X394342I-336J217D01*
G03X391967Y156327I-1134J-736D01*
G01X391952Y156292D01*
X391195Y155535D01*
X391150Y155520D01*
G03X390845Y155371I392J-1189D01*
G02X390222Y155703I-223J332D01*
G01Y161544D01*
X391177Y162498D01*
X395208D01*
X395593Y162884D01*
X396969D01*
G03X398715I873J897D01*
G01X400109D01*
G03X400357Y162696I874J896D01*
G01X400380Y162683D01*
X400500Y162563D01*
X400691D01*
X400713Y162558D01*
G03X401251I269J1223D01*
G01X401273Y162563D01*
X401500D01*
X403500Y160563D01*
Y160559D01*
X404000Y160059D01*
X419504D01*
X419548Y160015D01*
G03X422118Y159450I1352J22D01*
G01X422172Y159563D01*
X425629D01*
X425683Y159450D01*
G03X428117I1217J590D01*
G01X428171Y159563D01*
X429899D01*
X429941Y159542D01*
G03X430044Y159496I602J1210D01*
G01X430082Y159481D01*
X430789Y158774D01*
X431105D01*
X431369Y158510D01*
X432070D01*
X432107Y158494D01*
G03X433588Y159196I425J1017D01*
G01X433602Y159244D01*
X433692Y159334D01*
Y160692D01*
X434000Y161000D01*
X435000D01*
X435500Y160500D01*
Y159500D01*
X436432Y158568D01*
X436656D01*
X436710Y158525D01*
G03X437812Y158372I682J866D01*
G01X437849Y158388D01*
X438778D01*
X438811Y158375D01*
G03X439985Y158494I464J1270D01*
G01X441494D01*
X448000Y165000D01*
X459000D01*
X459500Y164500D01*
Y153500D01*
X459000Y153000D01*
X440000D01*
X439949Y153051D01*
X438949D01*
X438392Y152494D01*
Y152387D01*
X438375Y152348D01*
G03X438291Y152060I1006J-450D01*
G01X438282Y151994D01*
X437374Y151086D01*
X437299Y151081D01*
G03X436894Y150974I74J-1100D01*
G01X436853Y150954D01*
X436202D01*
X433800Y148552D01*
X430252D01*
X429196Y149608D01*
X422892D01*
X421500Y151000D01*
X421184D01*
X421162Y151005D01*
G03X420560I-301J-1318D01*
G01X420538Y151000D01*
X420000D01*
X419000Y150000D01*
X417000D01*
X416000Y151000D01*
X415724D01*
X415684Y151020D01*
G03X414516I-584J-1220D01*
G01X414476Y151000D01*
X409479D01*
X409437Y151021D01*
G03X408237I-600J-1212D01*
G01X408195Y151000D01*
X407786D01*
X406382Y149596D01*
X404504D01*
X404325Y149417D01*
X404281Y149402D01*
G03X403540Y148361I361J-1041D01*
G01Y148359D01*
G03X403992Y147470I1102J1D01*
G01Y146784D01*
X403277Y146069D01*
X403164Y146182D01*
X400981D01*
G37*
G36*
G01X393128Y176063D02*
X394335Y174856D01*
X394350Y174824D01*
G03X395233Y174092I1223J576D01*
G01X395285Y174078D01*
X395363Y174000D01*
X401394D01*
G03X401975Y173412I1206J611D01*
G01X402002Y173398D01*
X403220Y172180D01*
Y171220D01*
X401063Y169063D01*
X400478D01*
G03X398122I-1178J-663D01*
G01X394500D01*
X394000Y169563D01*
X393854D01*
X393805Y169594D01*
G03X391869Y169063I-728J-1139D01*
G01X388000D01*
X387500Y169563D01*
Y170563D01*
X387518Y170582D01*
X387500Y170600D01*
Y173563D01*
X388722Y174785D01*
X388768Y174800D01*
G03X389443Y175327I-386J1191D01*
G01X389455Y175346D01*
X390172Y176063D01*
X390683D01*
X390720Y176047D01*
G03X391584I432J1014D01*
G01X391621Y176063D01*
X393128D01*
G37*
G36*
G01X496500Y151651D02*
X446349Y101500D01*
X441263D01*
X440148Y102616D01*
X437294Y105471D01*
Y106593D01*
X437700Y107000D01*
X442300D01*
X443800Y108500D01*
Y117100D01*
X447150Y120450D01*
X450500Y117100D01*
X459900D01*
X460377Y117577D01*
X460406Y117591D01*
G03X461009Y118194I-606J1209D01*
G01X461023Y118223D01*
X461500Y118700D01*
Y121900D01*
X465500Y125900D01*
Y137000D01*
X467500Y139000D01*
Y142000D01*
X468500Y143000D01*
X485500D01*
X492500Y150000D01*
Y158500D01*
X479002Y171998D01*
Y191500D01*
X479000Y191502D01*
Y193000D01*
X459000Y213000D01*
Y225500D01*
X440500Y244000D01*
Y246500D01*
X443500Y249500D01*
Y249629D01*
X443538Y249681D01*
G03X443802Y250500I-1138J819D01*
G01Y252301D01*
X443998Y252498D01*
X445400D01*
G03X445461Y252500I-15J1401D01*
G01X446675D01*
X446709Y252487D01*
G03X447200Y252398I492J1313D01*
G01X448800D01*
G03X449291Y252487I-1J1402D01*
G01X449325Y252500D01*
X449500D01*
X450000Y253000D01*
Y253074D01*
X450025Y253119D01*
G03X450202Y253800I-1225J682D01*
G01Y254984D01*
X451531Y256314D01*
X450602Y257246D01*
Y257579D01*
X451926Y258904D01*
Y260118D01*
X452402D01*
Y264500D01*
X455371D01*
G03X457821Y264026I1659J2005D01*
G01X457937Y264063D01*
X459000Y263000D01*
Y243000D01*
X463750Y238250D01*
X464000D01*
X466250Y236000D01*
X499500D01*
X501241Y234259D01*
X501126Y234144D01*
Y208056D01*
X502000Y207183D01*
Y195000D01*
X493000Y186000D01*
Y181500D01*
X496500Y178000D01*
Y155663D01*
G03Y153537I2375J-1063D01*
G01Y151651D01*
G37*
G36*
G01X445716Y193784D02*
X440996Y189063D01*
X440395D01*
X440181Y189278D01*
X438583D01*
X438369Y189063D01*
X434212D01*
X433753Y189522D01*
Y190722D01*
X434153Y191122D01*
X438653D01*
X439153Y191622D01*
Y192398D01*
X439168Y192435D01*
G03Y193477I-1247J521D01*
G01X439153Y193514D01*
Y195929D01*
X439274Y195981D01*
G03Y198467I-532J1243D01*
G01X439153Y198519D01*
Y199722D01*
X438976Y199899D01*
X438962Y199948D01*
G03X438601Y200560I-1371J-396D01*
G01X437294Y201867D01*
Y206075D01*
X438718Y207500D01*
X443953D01*
X445716Y205737D01*
Y193784D01*
G37*
G36*
G01X485000Y149000D02*
X463000D01*
X461500Y150500D01*
Y164500D01*
X462000Y165000D01*
X479500D01*
X488200Y156300D01*
Y152200D01*
X485000Y149000D01*
G37*
G36*
G01X465499Y3001D02*
X465000Y3500D01*
Y4500D01*
X466500Y6000D01*
X469000D01*
X472898Y9898D01*
X476223D01*
X477826Y11500D01*
X498500D01*
X500000Y10000D01*
Y4501D01*
X498500Y3001D01*
X465499D01*
G37*
G36*
G01X474500Y242500D02*
X473000Y244000D01*
Y256500D01*
X474000Y257500D01*
X493500D01*
X496250Y260250D01*
Y278750D01*
X499500Y282000D01*
X500790D01*
X501500Y281290D01*
Y251500D01*
X500500Y250500D01*
Y248162D01*
X500477Y248116D01*
X500442Y248024D01*
X500430Y247975D01*
X500406Y247901D01*
X500398Y247842D01*
X500387Y247799D01*
X500376Y247693D01*
Y247653D01*
X500367Y247580D01*
X500376Y247507D01*
Y247467D01*
X500387Y247361D01*
X500398Y247318D01*
X500406Y247259D01*
X500430Y247185D01*
X500442Y247136D01*
X500477Y247044D01*
X500500Y246998D01*
Y243000D01*
X500000Y242500D01*
X474500D01*
G37*
G36*
G01X505000Y212000D02*
X504000Y213000D01*
Y220000D01*
X505000Y221000D01*
X519000D01*
X519303Y220697D01*
X519300Y220610D01*
G03X519298Y220550I1599J-83D01*
G01Y218250D01*
G03X519478Y217514I1602J2D01*
G01X519500Y217471D01*
Y217000D01*
X520000Y216500D01*
X521000D01*
X521398Y216101D01*
Y214700D01*
G03X521487Y214209I1402J1D01*
G01X521500Y214175D01*
Y213000D01*
X520500Y212000D01*
X505000D01*
G37*
G36*
G01X526500Y223000D02*
X504500D01*
X504000Y223500D01*
Y227000D01*
X504500Y227500D01*
X527500D01*
X528500Y226500D01*
Y225000D01*
X526500Y223000D01*
G37*
G36*
G01X528052Y183052D02*
X527500Y182500D01*
X525500D01*
X525000Y183000D01*
Y184402D01*
G03Y184598I-2600J98D01*
G01Y196336D01*
G03Y199664I-2000J1664D01*
G01Y206500D01*
X526500Y208000D01*
X533175D01*
X533209Y207987D01*
G03X533700Y207898I492J1313D01*
G01X535300D01*
G03X535791Y207987I-1J1402D01*
G01X535825Y208000D01*
X539500D01*
X541000Y206500D01*
Y205925D01*
X540987Y205891D01*
G03X540898Y205400I1313J-492D01*
G01Y203800D01*
G03X540987Y203309I1402J1D01*
G01X541000Y203275D01*
Y192000D01*
X543436Y189564D01*
Y188018D01*
X544982D01*
X546500Y186500D01*
Y183500D01*
X545500Y182500D01*
X544500D01*
X542976Y184024D01*
X542961Y184066D01*
G03X542066Y184961I-1411J-516D01*
G01X542024Y184976D01*
X541500Y185500D01*
X535863D01*
G03X533637I-1113J-1900D01*
G01X531094D01*
X531057Y185515D01*
G03X528037Y183152I-843J-2034D01*
G01X528052Y183052D01*
G37*
G36*
G01X537500Y231618D02*
Y232775D01*
X537513Y232809D01*
G03X537602Y233300I-1313J492D01*
G01Y234900D01*
G03X537513Y235391I-1402J-1D01*
G01X537500Y235425D01*
Y239000D01*
X537000Y239500D01*
X523000D01*
X522500Y239000D01*
Y229500D01*
X522000Y229000D01*
X512500D01*
X511500Y230000D01*
Y240000D01*
X513500Y242000D01*
X539000D01*
X544500Y236500D01*
Y216500D01*
X544000Y216000D01*
X538000D01*
X537500Y216500D01*
Y229183D01*
G03X537522Y231575I-2300J1217D01*
G01X537500Y231618D01*
G37*
G36*
G01X530500Y226500D02*
X528500Y228500D01*
X528199D01*
X527998Y228702D01*
X524299D01*
X524000Y229000D01*
Y237500D01*
X524500Y238000D01*
X527500D01*
X530500Y235000D01*
X532000D01*
X533000Y234000D01*
Y231789D01*
G03X532778Y229448I2200J-1390D01*
G01X532826Y229326D01*
X532500Y229000D01*
Y227000D01*
X532000Y226500D01*
X530500D01*
G37*
G36*
G01X586300Y80898D02*
G03X586791Y80987I-1J1402D01*
G01X586825Y81000D01*
X590138D01*
X590209Y80987D01*
X590225Y80981D01*
G03X590700Y80898I475J1319D01*
G01X592300D01*
G03X592791Y80987I-1J1402D01*
G01X592825Y81000D01*
X593138D01*
X593209Y80987D01*
X593225Y80981D01*
G03X593700Y80898I475J1319D01*
G01X595300D01*
G03X596702Y82300I0J1402D01*
G01Y83700D01*
G03X596282Y84700I-1402J-1D01*
G01Y94200D01*
G03X596000Y95167I-1802J-1D01*
G01Y96500D01*
X596500Y97000D01*
X598000D01*
X598500Y96500D01*
Y89462D01*
G03X598395Y85595I1000J-1962D01*
G01X598418Y85582D01*
X599000Y85000D01*
X606500D01*
X610500Y89000D01*
Y91638D01*
X610513Y91709D01*
X610519Y91725D01*
G03X610602Y92200I-1319J475D01*
G01Y93800D01*
G03X610513Y94291I-1402J-1D01*
G01X610500Y94325D01*
Y94638D01*
X610513Y94709D01*
X610519Y94725D01*
G03X610602Y95200I-1319J475D01*
G01Y96602D01*
X611000Y97000D01*
X612000D01*
X612500Y96500D01*
Y73500D01*
X589000Y50000D01*
X531500D01*
X530500Y51000D01*
Y58500D01*
X530598Y58598D01*
X536352D01*
Y58706D01*
G02X536572Y58905I200J0D01*
G03X536700Y58898I140J1394D01*
G01X538300D01*
G03X538791Y58987I-1J1402D01*
G01X538825Y59000D01*
X539000D01*
X540000Y60000D01*
Y68000D01*
X542298Y70298D01*
X544100D01*
G03X545502Y71700I0J1402D01*
G01Y73300D01*
G03X545498Y73400I-1402J-6D01*
G01X545491Y73491D01*
X555000Y83000D01*
Y88439D01*
X555008Y88467D01*
G03X555075Y89437I-2108J633D01*
G01Y89439D01*
X555059Y89559D01*
X555500Y90000D01*
X558000D01*
X558500Y89500D01*
Y77500D01*
X558698Y77302D01*
Y77268D01*
X558732D01*
X559000Y77000D01*
X564000D01*
X564301Y76699D01*
X564309Y76631D01*
G03X565700Y75398I1391J168D01*
G01X567300D01*
G03X567791Y75487I-1J1402D01*
G01X567825Y75500D01*
X571000D01*
X571500Y75000D01*
Y72000D01*
X573500Y70000D01*
X583000D01*
X585000Y72000D01*
Y76500D01*
X584000Y77500D01*
Y80500D01*
X584423Y80923D01*
X584521Y80910D01*
G03X584700Y80898I183J1390D01*
G01X586300D01*
G37*
G36*
G01X573500Y123000D02*
X550000D01*
X549000Y124000D01*
Y148500D01*
X550000Y149500D01*
X574000D01*
X575000Y148500D01*
Y124500D01*
X573500Y123000D01*
G37*
G36*
G01X679000Y186579D02*
Y184874D01*
G03X678498Y183800I900J-1075D01*
G01Y182200D01*
G03X679900Y180798I1402J0D01*
G01X681700D01*
G03X682381Y180975I-1J1402D01*
G01X682426Y181000D01*
X682574D01*
X682619Y180975D01*
G03X683300Y180798I682J1225D01*
G01X685100D01*
G03X685116Y180799I-79J1397D01*
G01X685200Y180800D01*
X687199Y178801D01*
X687205Y178727D01*
G03X687915Y177274I2195J173D01*
G01X687976Y177218D01*
X687983Y177052D01*
X687927Y176991D01*
G03X687345Y175500I1620J-1491D01*
G01X684500D01*
X682000Y173000D01*
Y168000D01*
X682110Y167890D01*
Y167338D01*
X686662D01*
X687000Y167000D01*
Y165113D01*
X686548Y164662D01*
X682110D01*
Y159858D01*
X682642D01*
X683000Y159500D01*
X688500D01*
X689500Y160500D01*
X697510D01*
G03X698681Y159976I1488J1756D01*
G01X698870Y159787D01*
X698756Y159674D01*
Y143256D01*
X698000Y142500D01*
X689500D01*
X685500Y138500D01*
X668500D01*
X668000Y139000D01*
Y144000D01*
X672500Y148500D01*
X675500D01*
X678500Y151500D01*
Y159858D01*
X678891D01*
Y172142D01*
X678500D01*
Y173000D01*
X675500Y176000D01*
X674904D01*
G03X672896I-1004J-2400D01*
G01X671500D01*
X668500Y173000D01*
Y172862D01*
X668487Y172790D01*
G03X668398Y172300I1313J-492D01*
G01Y170700D01*
G03X668487Y170209I1402J1D01*
G01X668500Y170175D01*
Y167500D01*
X668102Y167102D01*
X666700D01*
G03X666521Y167090I4J-1402D01*
G01X666423Y167077D01*
X666064Y167436D01*
Y170250D01*
X666000D01*
Y175500D01*
X668809Y178309D01*
X668900Y178302D01*
G03X669000Y178298I106J1398D01*
G01X670800D01*
G03X671193Y178355I-3J1402D01*
G03X673849Y181526I1907J1100D01*
G02X673702Y182185I136J376D01*
G01X674470Y182953D01*
Y183970D01*
X675000Y184500D01*
Y189445D01*
G03X675020Y191427I-1956J1011D01*
G01X674970Y191530D01*
X674962Y191538D01*
X674949Y191561D01*
G03X674149Y192361I-1905J-1105D01*
G01X674126Y192374D01*
X674000Y192500D01*
X673864D01*
X673829Y192513D01*
G03X672259I-785J-2057D01*
G01X672224Y192500D01*
X672000D01*
X671701Y192201D01*
G03X671299Y191799I1343J-1745D01*
G01X671000Y191500D01*
Y191276D01*
X670987Y191241D01*
Y191240D01*
G03Y189672I2057J-784D01*
G01Y189671D01*
X671000Y189636D01*
Y183517D01*
X670184Y182702D01*
X669000D01*
G03X668983Y182701I74J-1398D01*
G02X668777Y182939I-10J200D01*
G03X668802Y183200I-1377J264D01*
G01Y184800D01*
G03X668000Y186067I-1402J0D01*
G01Y196500D01*
X674000Y202500D01*
Y211000D01*
X664000Y221000D01*
X658862D01*
X658790Y221013D01*
G03X658300Y221102I-492J-1313D01*
G01X656700D01*
G03X656209Y221013I1J-1402D01*
G01X656175Y221000D01*
X645500D01*
X645000Y220500D01*
Y203500D01*
X643500Y202000D01*
X632000D01*
X631000Y203000D01*
Y225500D01*
X630500Y226000D01*
X619338D01*
G03X616560I-1389J-2200D01*
G01X602717D01*
X601441Y227276D01*
X593278D01*
X592002Y226000D01*
X579102D01*
Y226256D01*
X571198D01*
Y226000D01*
X571000D01*
X570500Y225500D01*
Y224372D01*
X570074Y223946D01*
Y222584D01*
X569990Y222500D01*
X567500D01*
X567000Y223000D01*
Y225638D01*
X567013Y225710D01*
G03X567102Y226200I-1313J492D01*
G01Y227800D01*
G03X567013Y228291I-1402J-1D01*
G01X567000Y228325D01*
Y229000D01*
X562000Y234000D01*
X559021D01*
X558935Y234019D01*
X558934Y234020D01*
G03X558230Y234184I-706J-1438D01*
G01X555930D01*
G03X555514Y234128I4J-1602D01*
G01X555402Y234098D01*
X555000Y234500D01*
Y240500D01*
X556000Y241500D01*
X571500D01*
X579900Y233100D01*
X639400D01*
X642000Y230500D01*
X642262D01*
X642314Y230464D01*
G03X646000Y233989I1486J2136D01*
G01Y239000D01*
X648000Y241000D01*
X712500D01*
X716000Y237500D01*
Y214505D01*
G03Y212495I2400J-1005D01*
G01Y209000D01*
X716467Y208533D01*
X716481Y208509D01*
X716482Y208508D01*
G03X717700Y207798I1219J691D01*
G01X719202D01*
X719500Y207500D01*
Y205500D01*
X718500Y204500D01*
Y202500D01*
X718077Y202077D01*
X717979Y202090D01*
G03X717800Y202102I-183J-1390D01*
G01X716200D01*
G03X715709Y202013I1J-1402D01*
G01X715675Y202000D01*
X715500D01*
X714500Y201000D01*
Y196000D01*
X714102Y195602D01*
X714054D01*
X710698Y192246D01*
Y192198D01*
X710000Y191500D01*
Y187500D01*
X705500Y183000D01*
X704593D01*
X704000Y183593D01*
Y191138D01*
X704013Y191210D01*
G03X704102Y191700I-1313J492D01*
G01Y193300D01*
G03X704013Y193791I-1402J-1D01*
G01X704000Y193825D01*
Y228500D01*
X697500Y235000D01*
X688500D01*
X683500Y230000D01*
Y228324D01*
G03X683298Y227600I1200J-725D01*
G01Y225799D01*
X683102Y225602D01*
X681700D01*
G03X681209Y225513I1J-1402D01*
G01X681175Y225500D01*
X680500D01*
X679500Y224500D01*
Y218500D01*
X681000Y217000D01*
X681685D01*
X681716Y216990D01*
G03X682562Y216854I830J2466D01*
G01X682645Y216855D01*
X683000Y216500D01*
Y202500D01*
X679000Y198500D01*
Y188021D01*
X678993Y187995D01*
G03Y186605I2507J-695D01*
G01X679000Y186579D01*
G37*
G36*
G01X640199Y234000D02*
X639898Y234302D01*
X580398D01*
X579000Y235699D01*
Y238700D01*
X583800Y243500D01*
Y249800D01*
X583900Y249900D01*
X585000D01*
X585100Y249800D01*
Y242600D01*
X585700Y242000D01*
X592800D01*
X593200Y242400D01*
Y249900D01*
X593400Y250100D01*
X594300D01*
X594600Y249800D01*
Y242500D01*
X595100Y242000D01*
X602400D01*
X602700Y242300D01*
Y249800D01*
X602800Y249900D01*
X603800D01*
X604000Y249700D01*
Y242300D01*
X604300Y242000D01*
X609200D01*
X609800Y242600D01*
Y249700D01*
X610100Y250000D01*
X610700D01*
X611000Y249700D01*
Y242700D01*
X611700Y242000D01*
X618800D01*
X619200Y242400D01*
Y249700D01*
X619500Y250000D01*
X620200D01*
X620500Y249700D01*
Y242600D01*
X621000Y242100D01*
X627900D01*
X628700Y242900D01*
Y249600D01*
X629000Y249900D01*
X629700D01*
X630000Y249600D01*
Y242900D01*
X630800Y242100D01*
X637000D01*
X638100Y243200D01*
Y249700D01*
X638400Y250000D01*
X639100D01*
X639400Y249700D01*
Y242500D01*
X641000Y240900D01*
Y234500D01*
X640500Y234000D01*
X640199D01*
G37*
G36*
G01X610602Y49402D02*
X611006Y49806D01*
X612600D01*
G03X613091Y49894I2J1401D01*
G01X613125Y49907D01*
X632639D01*
G03X632700Y49906I53J1400D01*
G01X634300D01*
G03X634361Y49907I8J1401D01*
G01X635939D01*
G03X636000Y49906I53J1400D01*
G01X637600D01*
G03X637661Y49907I8J1401D01*
G01X644439D01*
G03X644500Y49906I53J1400D01*
G01X646100D01*
G03X646161Y49907I8J1401D01*
G01X649939D01*
G03X650000Y49906I53J1400D01*
G01X651600D01*
G03X651661Y49907I8J1401D01*
G01X672196D01*
X672220Y49901D01*
G03X672600Y49856I377J1556D01*
G01X675152D01*
X677000Y48007D01*
Y45007D01*
X676000Y44007D01*
X670500D01*
X670100Y43607D01*
Y36007D01*
X669700Y35607D01*
X669200D01*
X668900Y35907D01*
Y43507D01*
X668400Y44007D01*
X661500D01*
X660700Y43207D01*
Y36007D01*
X660400Y35707D01*
X659600D01*
X659400Y35907D01*
Y43107D01*
X658500Y44007D01*
X652000D01*
X651300Y43307D01*
Y35807D01*
X650800Y35307D01*
X650300D01*
X649900Y35707D01*
Y43307D01*
X649200Y44007D01*
X644800D01*
X644200Y43407D01*
Y35807D01*
X643700Y35307D01*
X643300D01*
X642800Y35807D01*
Y43307D01*
X642100Y44007D01*
X635500D01*
X634700Y43207D01*
Y35707D01*
X634300Y35307D01*
X633800D01*
X633400Y35707D01*
Y43307D01*
X632700Y44007D01*
X625900D01*
X625300Y43407D01*
Y35807D01*
X624900Y35407D01*
X624300D01*
X623900Y35807D01*
Y43307D01*
X623200Y44007D01*
X617100D01*
X615700Y42607D01*
Y35907D01*
X615400Y35607D01*
X614800D01*
X614600Y35807D01*
Y42707D01*
X614000Y43307D01*
X613993D01*
X612800Y44500D01*
X612253D01*
X612035Y44718D01*
X610782D01*
X610500Y45000D01*
Y47682D01*
X610513Y47716D01*
G03X610602Y48207I-1313J492D01*
G01Y49402D01*
G37*
G36*
G01X786500Y74000D02*
X789500Y71000D01*
Y50000D01*
X783577Y44077D01*
X783480Y44090D01*
G03X783300Y44102I-183J-1390D01*
G01X781700D01*
G03X781209Y44013I1J-1402D01*
G01X781175Y44000D01*
X779500D01*
X763000Y60500D01*
X762666D01*
X762611Y60543D01*
G03X759336Y60500I-1611J-2043D01*
G01X752500D01*
X752000Y61000D01*
Y62500D01*
X750500Y64000D01*
X746000D01*
X745606Y64394D01*
X745639Y64507D01*
G03X745702Y64950I-1539J445D01*
G01Y66895D01*
X746402Y67595D01*
Y68227D01*
G03X746801Y68778I-902J1073D01*
G01X746816Y68816D01*
X747000Y69000D01*
Y71000D01*
X746816Y71184D01*
X746801Y71222D01*
G03X745500Y72102I-1301J-522D01*
G01X743900D01*
G03X743409Y72013I1J-1402D01*
G01X743375Y72000D01*
X742179D01*
G03X738002Y71421I-1879J-1800D01*
G01X737988Y71394D01*
X737094Y70500D01*
X725000D01*
X724500Y71000D01*
X724006D01*
X723805Y71202D01*
X722969D01*
G03X718696Y70709I-1969J-1702D01*
G01X718682Y70682D01*
X718077Y70077D01*
X717980Y70090D01*
G03X717800Y70102I-183J-1390D01*
G01X716200D01*
G03X715709Y70013I1J-1402D01*
G01X715675Y70000D01*
X715325D01*
X715291Y70013D01*
G03X714800Y70102I-492J-1313D01*
G01X713200D01*
G03X712709Y70013I1J-1402D01*
G01X712675Y70000D01*
X710000D01*
X707000Y67000D01*
Y59000D01*
X708500Y57500D01*
X723000D01*
X724000Y58500D01*
Y60500D01*
X724500Y61000D01*
X727500D01*
X728000Y60500D01*
Y45500D01*
X726500Y44000D01*
X682500D01*
X678202Y48298D01*
Y48505D01*
X675598Y51108D01*
X613121D01*
X613087Y51121D01*
G03X612600Y51208I-486J-1314D01*
G01X610602D01*
Y52807D01*
G03X610000Y53958I-1401J0D01*
G01Y59108D01*
X619392Y68500D01*
X631000D01*
X642500Y80000D01*
X705000D01*
X712000Y87000D01*
X716972D01*
G03X717750Y86798I779J1400D01*
G01X720050D01*
G03X720110Y86800I-23J1601D01*
G01X720197Y86803D01*
X720500Y86500D01*
Y84013D01*
X720398Y83912D01*
Y81887D01*
G03X720464Y79014I2202J-1387D01*
G01X720500Y78962D01*
Y78000D01*
X721500Y77000D01*
X737000D01*
X741693Y81693D01*
G03X741805Y81805I-1783J1895D01*
G01X741807Y81807D01*
X744000Y84000D01*
Y88500D01*
X743500Y89000D01*
X742825D01*
X742791Y89013D01*
G03X742300Y89102I-492J-1313D01*
G01X740700D01*
G03X740209Y89013I1J-1402D01*
G01X740175Y89000D01*
X738000D01*
X737500Y89500D01*
Y92000D01*
X738000Y92500D01*
X742000D01*
X742398Y92898D01*
X742400D01*
X747502Y98000D01*
Y98002D01*
X748883Y99383D01*
X748992Y99357D01*
G03X749085Y103662I508J2143D01*
G01X748980Y103642D01*
X747702Y104921D01*
Y106578D01*
G03X747902Y107300I-1203J722D01*
G01Y107902D01*
X748000Y108000D01*
X757000D01*
X757500Y107500D01*
Y105936D01*
G03X756976Y103208I1416J-1686D01*
G01X757000Y103164D01*
Y103000D01*
X776000Y84000D01*
X786000D01*
X786500Y83500D01*
Y74000D01*
G37*
G36*
G01X621400Y203602D02*
X619500Y205501D01*
Y206675D01*
X619513Y206709D01*
G03X619602Y207200I-1313J492D01*
G01Y208800D01*
G03X619513Y209291I-1402J-1D01*
G01X619500Y209325D01*
Y210000D01*
X620074Y210574D01*
X620091D01*
X624017Y214500D01*
X629500D01*
X629798Y214202D01*
Y204798D01*
X629052Y204052D01*
X623497D01*
X623047Y203602D01*
X621400D01*
G37*
G36*
G01X662000Y89000D02*
X661500Y89500D01*
Y100000D01*
X662000Y100500D01*
X676000D01*
X676500Y100000D01*
Y89500D01*
X676000Y89000D01*
X662000D01*
G37*
G36*
G01X697500Y92500D02*
X693500D01*
X684000Y102000D01*
X662000D01*
X661500Y102500D01*
Y113500D01*
X662000Y114000D01*
X665000D01*
X665500Y113500D01*
Y111000D01*
X668000Y108500D01*
X687000D01*
X690500Y112000D01*
X698000D01*
X698500Y111500D01*
Y93500D01*
X698305Y93305D01*
G03X698195Y93195I1784J-1894D01*
G01X697500Y92500D01*
G37*
G36*
G01X662000Y116000D02*
X661500Y116500D01*
Y128500D01*
X661748Y128748D01*
X666252D01*
X666500Y128500D01*
X676000D01*
X676500Y128000D01*
Y121500D01*
X672500Y117500D01*
X667000D01*
X665500Y116000D01*
X662000D01*
G37*
G36*
G01X694000Y121500D02*
X685500Y130000D01*
X666699D01*
X666498Y130202D01*
X661798D01*
X661500Y130500D01*
Y141000D01*
X662000Y141500D01*
X665000D01*
X665500Y141000D01*
Y139000D01*
X668000Y136500D01*
X687000D01*
X690500Y140000D01*
X697500D01*
X698000Y139500D01*
Y122000D01*
X697500Y121500D01*
X694000D01*
G37*
G36*
G01X669500Y151000D02*
X669000Y151500D01*
Y155500D01*
X669500Y156000D01*
Y156675D01*
X669513Y156709D01*
G03X669602Y157200I-1313J492D01*
G01Y158800D01*
G03X669513Y159291I-1402J-1D01*
G01X669500Y159325D01*
Y159675D01*
X669513Y159709D01*
G03X669602Y160200I-1313J492D01*
G01Y161800D01*
G03X669590Y161980I-1402J-3D01*
G01X669577Y162077D01*
X670000Y162500D01*
X673000D01*
X674000Y163500D01*
X677298D01*
Y152798D01*
X675500Y151000D01*
X669500D01*
G37*
G36*
G01X711800Y64398D02*
G03X712291Y64487I-1J1402D01*
G01X712325Y64500D01*
X718500D01*
X720500Y66500D01*
X723000D01*
X724000Y65500D01*
X727500D01*
X728500Y64500D01*
Y63000D01*
X728000Y62500D01*
X724000D01*
X723000Y61500D01*
Y61199D01*
X722798Y60998D01*
Y59298D01*
X722500Y59000D01*
X709000D01*
X708500Y59500D01*
Y64000D01*
X709000Y64500D01*
X709675D01*
X709709Y64487D01*
G03X710200Y64398I492J1313D01*
G01X711800D01*
G37*
G36*
G01X780000Y3000D02*
X779000Y4000D01*
Y14500D01*
X778500Y15000D01*
Y16798D01*
X779200D01*
G03X780602Y18200I0J1402D01*
G01Y19798D01*
X782600D01*
G03X783814Y20500I0J1401D01*
G01X806000D01*
X814500Y29000D01*
Y105500D01*
X808000Y112000D01*
Y127500D01*
X807695Y127805D01*
X807699Y127893D01*
G03X807517Y128884I-2199J108D01*
G01X807500Y128922D01*
Y129676D01*
G03X807702Y130400I-1200J725D01*
G01Y132200D01*
G03X807525Y132881I-1402J-1D01*
G01X807500Y132926D01*
Y133000D01*
X807000Y133500D01*
X806825D01*
X806791Y133513D01*
G03X806300Y133602I-492J-1313D01*
G01X804898D01*
X804500Y134000D01*
Y135500D01*
X805000Y136000D01*
X807000D01*
X808000Y137000D01*
Y140000D01*
X807500Y140500D01*
X806825D01*
X806791Y140513D01*
G03X806300Y140602I-492J-1313D01*
G01X804700D01*
G03X804209Y140513I1J-1402D01*
G01X804175Y140500D01*
X802116D01*
Y140532D01*
X782914D01*
Y140500D01*
X779500D01*
X778000Y142000D01*
Y145717D01*
G03X778160Y146125I-2334J1151D01*
G01X778174Y146174D01*
X778423Y146423D01*
X778520Y146410D01*
G03X778700Y146398I183J1390D01*
G01X780300D01*
G03X780791Y146487I-1J1402D01*
G01X780825Y146500D01*
X783000D01*
X783170Y146670D01*
X787516D01*
Y147016D01*
X788000Y147500D01*
Y151000D01*
X788169Y151169D01*
X802517D01*
Y151500D01*
X804500D01*
X807500Y154500D01*
X810500D01*
X812000Y156000D01*
Y164208D01*
G03Y164392I-2300J92D01*
G01Y176500D01*
X809000Y179500D01*
Y199500D01*
X802000Y206500D01*
Y234000D01*
X798600Y237400D01*
Y248600D01*
X803150Y253150D01*
Y258935D01*
G03X803152Y259000I-1599J82D01*
G01Y262200D01*
G03X803150Y262265I-1601J-17D01*
G01Y263935D01*
G03X803152Y264000I-1599J82D01*
G01Y267200D01*
G03X803150Y267265I-1601J-17D01*
G01Y268935D01*
G03X803152Y269000I-1599J82D01*
G01Y272200D01*
G03X803150Y272265I-1601J-17D01*
G01Y273350D01*
X802000Y274500D01*
X780000D01*
X776500Y271000D01*
Y252500D01*
X773150Y249150D01*
Y234050D01*
X775200Y232000D01*
X779800D01*
X780300Y231500D01*
Y185500D01*
X775500Y180700D01*
Y161500D01*
X767500Y153500D01*
X760000D01*
X756000Y157500D01*
X755825D01*
X755791Y157513D01*
G03X755300Y157602I-492J-1313D01*
G01X753700D01*
G03X753209Y157513I1J-1402D01*
G01X753175Y157500D01*
X752825D01*
X752791Y157513D01*
G03X752300Y157602I-492J-1313D01*
G01X750700D01*
G03X750209Y157513I1J-1402D01*
G01X750175Y157500D01*
X750000D01*
X749000Y156500D01*
Y154500D01*
X748500Y154000D01*
X747500D01*
X747077Y154423D01*
X747090Y154520D01*
G03X747102Y154700I-1390J183D01*
G01Y156300D01*
G03X747013Y156791I-1402J-1D01*
G01X747000Y156825D01*
Y157175D01*
X747013Y157209D01*
G03X747102Y157700I-1313J492D01*
G01Y159300D01*
G03X747013Y159791I-1402J-1D01*
G01X747000Y159825D01*
Y160000D01*
X746402Y160598D01*
Y161663D01*
X746202Y161863D01*
Y162700D01*
G03X746025Y163381I-1402J-1D01*
G01X746000Y163426D01*
Y163574D01*
X746025Y163619D01*
G03X746202Y164300I-1225J682D01*
G01Y166100D01*
G03X746025Y166781I-1402J-1D01*
G01X746000Y166826D01*
Y167000D01*
X745500Y167500D01*
X744861D01*
G03X744800Y167502I-76J-1399D01*
G01X743200D01*
G03X743139Y167500I15J-1401D01*
G01X739500D01*
X738000Y166000D01*
Y158000D01*
X737602Y157602D01*
X736200D01*
G03X735709Y157513I1J-1402D01*
G01X735675Y157500D01*
X735325D01*
X735291Y157513D01*
G03X734800Y157602I-492J-1313D01*
G01X733200D01*
G03X732709Y157513I1J-1402D01*
G01X732675Y157500D01*
X732325D01*
X732291Y157513D01*
G03X731800Y157602I-492J-1313D01*
G01X730200D01*
G03X729709Y157513I1J-1402D01*
G01X729675Y157500D01*
X729325D01*
X729291Y157513D01*
G03X728800Y157602I-492J-1313D01*
G01X727200D01*
G03X726709Y157513I1J-1402D01*
G01X726675Y157500D01*
X726500D01*
X725500Y158500D01*
Y163000D01*
X729298Y166798D01*
X731100D01*
G03X732502Y168200I0J1402D01*
G01Y169898D01*
X734300D01*
G03X734791Y169987I-1J1402D01*
G01X734825Y170000D01*
X736000D01*
X740500Y174500D01*
Y177676D01*
G03X740702Y178400I-1200J725D01*
G01Y180201D01*
X740898Y180398D01*
X742300D01*
G03X742791Y180487I-1J1402D01*
G01X742825Y180500D01*
X743000D01*
X743500Y181000D01*
Y181074D01*
X743525Y181119D01*
G03X743702Y181800I-1225J682D01*
G01Y183600D01*
G03X743500Y184324I-1402J-1D01*
G01Y190000D01*
X743898Y190398D01*
X745300D01*
G03X745791Y190487I-1J1402D01*
G01X745825Y190500D01*
X746000D01*
X746500Y191000D01*
Y191074D01*
X746525Y191119D01*
G03X746702Y191800I-1225J682D01*
G01Y193200D01*
G03X746500Y193924I-1402J-1D01*
G01Y198000D01*
X744500Y200000D01*
X741825D01*
X741791Y200013D01*
G03X741300Y200102I-492J-1313D01*
G01X739700D01*
G03X739520Y200090I3J-1402D01*
G01X739423Y200077D01*
X739202Y200299D01*
Y202100D01*
G03X739000Y202824I-1402J-1D01*
G01Y207500D01*
X730500Y216000D01*
X728861D01*
G03X728800Y216002I-76J-1399D01*
G01X727200D01*
G03X727139Y216000I15J-1401D01*
G01X724500D01*
X724200Y216300D01*
X724201Y216384D01*
G03X724202Y216400I-1396J95D01*
G01Y218201D01*
X724500Y218500D01*
X728000D01*
X730996Y221496D01*
X731031Y221511D01*
G03X732389Y222869I-1031J2389D01*
G01X732404Y222904D01*
X733500Y224000D01*
Y229906D01*
X738594Y235000D01*
X741500D01*
X743500Y237000D01*
X746500D01*
X747248Y237748D01*
X747636D01*
X752352Y242464D01*
Y242852D01*
X752500Y243000D01*
Y252500D01*
X761000Y261000D01*
Y270400D01*
X778100Y287500D01*
X822500D01*
X823500Y286500D01*
Y4000D01*
X822500Y3000D01*
X780000D01*
G37*
G36*
G01X754500Y35000D02*
X754000Y35500D01*
Y42500D01*
X753000Y43500D01*
X734000D01*
X729500Y48000D01*
Y61500D01*
X730000Y62000D01*
Y64000D01*
X731000Y65000D01*
X732642D01*
X733644Y63998D01*
X737002D01*
X738500Y62500D01*
X749500D01*
X750500Y61500D01*
Y60000D01*
X761000Y49500D01*
Y36000D01*
X760000Y35000D01*
X754500D01*
G37*
G36*
G01X753000Y3000D02*
X752500Y3500D01*
Y11007D01*
X755250Y13757D01*
X764757D01*
X767942Y16942D01*
X768002Y16954D01*
G03X769156Y17500I-502J2553D01*
G01X776186D01*
G03X777136Y16824I1214J700D01*
G01X777298Y16792D01*
Y14502D01*
X777500Y14301D01*
Y4000D01*
X776500Y3000D01*
X753000D01*
G37*
G36*
G01X764002Y122800D02*
G03X763686Y123686I-1402J-1D01*
G01X764000Y124000D01*
X765175D01*
X765209Y123987D01*
G03X765700Y123898I492J1313D01*
G01X767300D01*
G03X767791Y123987I-1J1402D01*
G01X767825Y124000D01*
X780500D01*
X780599Y124098D01*
X782570D01*
X785370Y126898D01*
X789102D01*
X789500Y126500D01*
Y111000D01*
X787000Y108500D01*
Y97500D01*
X786500Y97000D01*
X773500D01*
X769000Y101500D01*
Y112000D01*
X763902Y117098D01*
Y120679D01*
X763914Y120713D01*
G03X764002Y121200I-1314J489D01*
G01Y122800D01*
G37*
G36*
G01X798497Y74500D02*
X789000D01*
X787702Y75798D01*
Y83998D01*
X787500Y84199D01*
Y88500D01*
X788000Y89000D01*
X799000D01*
X799448Y88552D01*
Y75452D01*
X798497Y74500D01*
G37*
G36*
G01X804117Y101117D02*
X799000Y96000D01*
Y91000D01*
X798500Y90500D01*
X782000D01*
X781000Y91500D01*
Y94500D01*
X782000Y95500D01*
X787000D01*
X787898Y96398D01*
X787952D01*
Y96452D01*
X788500Y97000D01*
Y107000D01*
X791000Y109500D01*
Y125500D01*
X793000Y127500D01*
Y134500D01*
X792517Y134983D01*
Y135551D01*
X784449D01*
X784049Y135951D01*
G03X784024Y138096I-2049J1049D01*
G01X784000Y138141D01*
Y139000D01*
X784298Y139298D01*
X806702D01*
X806798Y139202D01*
Y137498D01*
X806502Y137202D01*
X804502D01*
X804301Y137000D01*
X803000D01*
X802500Y136500D01*
Y127500D01*
X806798Y123202D01*
Y113298D01*
X805060Y111560D01*
X805027Y111545D01*
G03X804500Y106773I1173J-2545D01*
G01Y105227D01*
G03X804006Y101257I1700J-2227D01*
G01X804117Y101117D01*
G37*
G36*
G01X807280Y156280D02*
X803702Y152702D01*
X788298D01*
X788000Y153000D01*
Y159000D01*
X783500Y163500D01*
Y176000D01*
X785500Y178000D01*
X786687D01*
G03X788913I1113J1900D01*
G01X805000D01*
X807750Y175250D01*
Y165523D01*
G03Y163077I1950J-1223D01*
G01Y161870D01*
G03X807714Y159180I1850J-1370D01*
G01X807750Y159129D01*
Y158397D01*
X807706Y158342D01*
G03X807256Y156388I1794J-1442D01*
G01X807280Y156280D01*
G37*
G36*
G01X804300Y186200D02*
X783800D01*
X782000Y188000D01*
Y232600D01*
X781100Y233500D01*
X776700D01*
X775100Y235100D01*
Y249100D01*
X778000Y252000D01*
Y270000D01*
X781000Y273000D01*
X801500D01*
X801900Y272600D01*
Y254000D01*
X797100Y249200D01*
Y236400D01*
X800500Y233000D01*
Y206200D01*
X806000Y200700D01*
Y187900D01*
X804300Y186200D01*
G37*
%LPC*%
G75*
G36*
G01X82885Y59468D02*
X79115D01*
G02Y62490I0J1511D01*
G01X82886D01*
G02X84396Y60989I-1J-1511D01*
G01Y60894D01*
X84387Y60810D01*
G02X82885Y59468I-1502J170D01*
G37*
G36*
G01X94006Y60889D02*
G03X93823Y61105I-199J17D01*
G02X92487Y61700I177J2195D01*
G03X92204Y61692I-138J-145D01*
G02X92113Y64800I-1604J1508D01*
G03X92396Y64808I138J145D01*
G02X96194Y63111I1604J-1508D01*
G03X96377Y62895I199J-17D01*
G02X94006Y60889I-177J-2195D01*
G37*
G36*
G01X103450Y52888D02*
X100050D01*
G02Y55912I0J1512D01*
G01X103451D01*
G02X104962Y54410I-1J-1512D01*
G01Y54315D01*
X104952Y54231D01*
G02X103450Y52888I-1502J168D01*
G37*
G36*
G01X88700D02*
X85299D01*
G02X85300Y55912I1J1512D01*
G01X88700D01*
G02X90212Y54410I0J-1512D01*
G01Y54315D01*
X90202Y54231D01*
G02X88700Y52888I-1502J168D01*
G37*
G36*
G01X16208Y71346D02*
G02X13815Y73491I-4708J-2846D01*
G03X14336Y74041I168J363D01*
G02X16698Y71925I4063J2159D01*
G03X16208Y71346I-148J-372D01*
G37*
G36*
G01X45845Y271808D02*
G02X44095Y273582I-3128J-1336D01*
G03X44648Y274032I162J365D01*
G02X46303Y272355I2152J468D01*
G03X45845Y271808I-90J-390D01*
G37*
G36*
G01X64900Y253900D02*
Y254900D01*
X65900D01*
X66900Y254200D01*
Y253200D01*
X65900D01*
X64900Y253900D01*
G37*
G36*
G01X72400Y140700D02*
Y139700D01*
X71400D01*
X71300Y139650D01*
X70300D01*
Y140650D01*
X71300D01*
X71400Y140700D01*
X72400D01*
G37*
G36*
G01X117000Y132900D02*
X118000D01*
Y131900D01*
X117000Y131150D01*
X116000D01*
Y132150D01*
X117000Y132900D01*
G37*
G36*
G01X153991Y238502D02*
Y228498D01*
X147987D01*
Y228798D01*
X146000D01*
G02X144500Y232611I0J2202D01*
G01Y235580D01*
G02X147897Y238202I2000J920D01*
G01X147987D01*
Y238502D01*
X153991D01*
G37*
G36*
G01X134962Y249898D02*
X130960D01*
Y249997D01*
G03X130670Y250176I-200J0D01*
G02Y254824I-1170J2324D01*
G03X130960Y255003I90J179D01*
G01Y255102D01*
X134962D01*
Y249898D01*
G37*
G36*
G01X167000Y198100D02*
Y197100D01*
X166000D01*
Y196900D01*
X165000D01*
Y197900D01*
X166000D01*
Y198100D01*
X167000D01*
G37*
G36*
G01X278583Y87504D02*
G03X277938Y87365I-275J-290D01*
G02X277417Y89796I-2038J835D01*
G03X278062Y89935I275J290D01*
G02X278583Y87504I2038J-835D01*
G37*
G36*
G01X366493Y137338D02*
X366425Y137330D01*
X365935Y136840D01*
X365922Y136782D01*
G02X364319Y138385I-1322J281D01*
G01X364377Y138398D01*
X365662Y139682D01*
X365745D01*
X365787Y139703D01*
G02X366493Y137338I555J-1122D01*
G37*
G36*
G01X367562Y153859D02*
X367615Y153873D01*
X368240Y154497D01*
X368251Y154558D01*
G02X368360Y154886I1231J-227D01*
G01X368380Y154928D01*
Y156884D01*
X368360Y156926D01*
G02X370604I1122J555D01*
G01X370584Y156884D01*
Y154928D01*
X370604Y154886D01*
G02Y153776I-1122J-555D01*
G01X370584Y153734D01*
Y153726D01*
X370572Y153714D01*
X370559Y153692D01*
G02X370121Y153254I-1077J639D01*
G01X370099Y153241D01*
X369843Y152985D01*
G03X369970Y152334I283J-283D01*
G02X369892Y149998I-488J-1153D01*
G01X369849Y149983D01*
X369584Y149718D01*
X370584Y148718D01*
Y148628D01*
X370604Y148586D01*
G02X368238Y147887I-1122J-555D01*
G01X368230Y147956D01*
X367803Y148383D01*
X367745Y148396D01*
G02X367184Y150775I281J1322D01*
G03X367155Y151422I-249J313D01*
G02X367562Y153859I745J1128D01*
G37*
G36*
G01X369449Y162292D02*
X369454Y162217D01*
X369839Y161832D01*
X369883Y161817D01*
G02X368296Y160230I-401J-1186D01*
G01X368281Y160274D01*
X367620Y160936D01*
X367583Y160951D01*
G02X369449Y162292I517J1249D01*
G37*
G36*
G01X375233Y193438D02*
X375506Y193166D01*
X375581Y193161D01*
G02X375677Y190971I-68J-1100D01*
G03X375341Y190524I60J-395D01*
G02X375351Y190396I-1341J-169D01*
G01X375354Y190317D01*
X375506Y190166D01*
X375581Y190161D01*
G02X374430Y188853I-69J-1100D01*
G03X374203Y189013I-196J-38D01*
G02X373134Y191389I-204J1337D01*
G03X373117Y192017I-256J307D01*
G02X375218Y193487I805J1086D01*
G01X375233Y193438D01*
G37*
G36*
G01X433834Y153964D02*
Y152731D01*
G02X431630I-1102J0D01*
G01Y153052D01*
X431397Y153285D01*
X431339Y153298D01*
G02X432942Y154901I281J1322D01*
G01X432955Y154843D01*
X433834Y153964D01*
G37*
G36*
G01X413634Y153593D02*
X412360Y152320D01*
X411902D01*
G02X411160Y154235I0J1101D01*
G01X411164Y154238D01*
X411967Y155042D01*
X411977Y155107D01*
G02X413684Y153608I1337J-199D01*
G01X413634Y153593D01*
G37*
G36*
G01X420123Y155402D02*
G02X421681Y156960I779J779D01*
G01X422610Y156030D01*
X422666Y156018D01*
G02X423685Y154981I-304J-1317D01*
G01X423698Y154923D01*
X424118Y154502D01*
X424172Y154489D01*
G02X423902Y152320I-270J-1068D01*
G01X423186D01*
X422140Y153365D01*
X422082Y153378D01*
G02X421041Y154419I281J1322D01*
G01X421028Y154477D01*
X420998Y154507D01*
Y154527D01*
X420123Y155402D01*
G37*
G36*
G01X410882Y156597D02*
X410868Y156587D01*
X409360Y155080D01*
X408902D01*
G02X408160Y156995I0J1101D01*
G01X408164Y156998D01*
X408750Y157585D01*
X408748Y157670D01*
G02X410882Y156597I1352J30D01*
G37*
G36*
G01X447500Y251100D02*
Y250100D01*
X446500D01*
X446100Y249800D01*
X445100D01*
Y250800D01*
X446100D01*
X446500Y251100D01*
X447500D01*
G37*
G36*
G01X475350Y248000D02*
X476350D01*
Y247000D01*
X475600Y246000D01*
X474600D01*
Y247000D01*
X475350Y248000D01*
G37*
G36*
G01X540300Y236600D02*
Y235600D01*
X539900D01*
Y234600D01*
X538900D01*
Y235600D01*
X539300D01*
Y236600D01*
X540300D01*
G37*
G36*
G01X606800Y231450D02*
Y232450D01*
X607800D01*
X608900Y231600D01*
Y230600D01*
X607900D01*
X606800Y231450D01*
G37*
G36*
G01Y237650D02*
X607800D01*
X608900Y236400D01*
Y235400D01*
X607900D01*
X606800Y236650D01*
Y237650D01*
G37*
G36*
G01X715500Y72800D02*
Y72400D01*
X716500D01*
Y71400D01*
X715500D01*
Y71800D01*
X714500D01*
Y72800D01*
X715500D01*
G37*
G36*
G01X671900Y160500D02*
Y159500D01*
X672300D01*
Y158500D01*
X671300D01*
Y159500D01*
X670900D01*
Y160500D01*
X671900D01*
G37*
G36*
G01X672300Y157500D02*
Y156500D01*
X672650Y156000D01*
Y155000D01*
X671650D01*
Y156000D01*
X671300Y156500D01*
Y157500D01*
X672300D01*
G37*
G36*
G01X714000Y63150D02*
Y62150D01*
X713000D01*
X712500Y61700D01*
X711500D01*
Y62700D01*
X712500D01*
X713000Y63150D01*
X714000D01*
G37*
G36*
G01X751000Y160300D02*
Y159300D01*
X750000D01*
X749800Y159000D01*
X748800D01*
Y160000D01*
X749800D01*
X750000Y160300D01*
X751000D01*
G37*
G36*
G01X735500D02*
Y159900D01*
X736500D01*
Y158900D01*
X735500D01*
Y159300D01*
X734500D01*
Y160300D01*
X735500D01*
G37*
G36*
G01X812558Y266484D02*
G03X812811Y265972I378J-132D01*
G02X809542Y264355I-812J-2472D01*
G03X809289Y264867I-378J132D01*
G02X809288Y269811I811J2472D01*
G03X809546Y270308I-124J380D01*
G02X809601Y271987I2489J759D01*
G03X809343Y272511I-374J141D01*
G02X810407Y277584I758J2489D01*
G03X810830Y278118I47J397D01*
G02X813295Y275209I5170J1882D01*
G03X812699Y274879I-197J-348D01*
G02X812534Y274080I-2599J120D01*
G03X812792Y273556I374J-141D01*
G02X812847Y268595I-757J-2489D01*
G03X812589Y268098I124J-380D01*
G02X812558Y266484I-2489J-759D01*
G37*
G36*
G01X742013Y213419D02*
G03X742490Y213142I384J112D01*
G02X740887Y210381I510J-2142D01*
G03X740410Y210658I-384J-112D01*
G02X738229Y214234I-510J2142D01*
G03X738214Y214772I-303J261D01*
G02X741632Y217522I1586J1527D01*
G03X742247Y217461I333J222D01*
G02X741968Y214678I1553J-1561D01*
G03X741353Y214739I-333J-222D01*
G03X741361Y214447I141J-142D01*
G02X742013Y213419I-1461J-1647D01*
G37*
G36*
G01X812548Y132296D02*
G03Y131704I269J-296D01*
G02X809452I-1548J-1704D01*
G03Y132296I-269J296D01*
G02Y135704I1548J1704D01*
G03Y136296I-269J296D01*
G02X809373Y139629I1548J1704D01*
G03X809403Y140162I-282J283D01*
G02X812827Y139971I1798J1438D01*
G03X812797Y139438I282J-283D01*
G02X812548Y136296I-1797J-1438D01*
G03Y135704I269J-296D01*
G02Y132296I-1548J-1704D01*
G37*
G36*
G01X789391Y13017D02*
G02X788201Y11112I1109J-2017D01*
G03X787609Y11483I-400J20D01*
G02X788799Y13388I-1109J2017D01*
G03X789391Y13017I400J-20D01*
G37*
G36*
G01X775100Y15500D02*
X776100D01*
Y14500D01*
X774850Y13500D01*
X773850D01*
Y14500D01*
X775100Y15500D01*
G37*
G36*
G01X800548Y123796D02*
G03Y123204I269J-296D01*
G02X797452I-1548J-1704D01*
G03Y123796I-269J296D01*
G02X800548I1548J1704D01*
G37*
G54D160*
X215100Y194200D03*
G54D156*
X37500Y264000D03*
X82000Y177500D03*
G54D152*
X79700Y67500D03*
X106100Y158700D03*
X128000Y203300D03*
X186300Y172400D03*
X169800Y181448D03*
X227000Y275500D03*
X744100Y221900D03*
X752500Y49007D03*
G54D165*
X809000Y149200D03*
X800400Y158500D03*
X799900Y168800D03*
G54D155*
X24000Y280000D03*
X799500Y10500D03*
G54D153*
X48600Y115000D03*
X37300Y118250D03*
X41300D03*
Y109950D03*
X37300D03*
X28100Y104650D03*
X24100D03*
X18000Y122850D03*
X17350Y158850D03*
X53700Y273500D03*
X25500Y211100D03*
X47100Y216500D03*
Y218500D03*
X27650Y153550D03*
X35100Y157000D03*
X27650Y158850D03*
X35100Y159000D03*
X39900Y157000D03*
Y159000D03*
X40000Y183000D03*
X59700Y268500D03*
X53700Y268700D03*
X55700D03*
X95500Y172900D03*
X97500D03*
X90000Y174650D03*
X94000D03*
X101500Y123350D03*
X116450Y136700D03*
X101500Y131650D03*
X114450Y136700D03*
X97500Y168100D03*
X95500D03*
X94000Y166350D03*
X90000D03*
X106550Y148150D03*
X111150Y266500D03*
Y270500D03*
X119000Y221650D03*
X112800Y189500D03*
X126000Y219800D03*
X149000Y168300D03*
X137300Y268000D03*
X160800Y151200D03*
X166400Y151700D03*
X168400D03*
X184000Y177000D03*
Y175000D03*
X188600Y150100D03*
X183500D03*
X188600Y192500D03*
Y194500D03*
X186850Y195500D03*
Y199500D03*
X182800Y199700D03*
X168450Y201300D03*
X187400Y202350D03*
X189400D03*
X200500Y260150D03*
X196500D03*
X183500Y60500D03*
X194500D03*
X196500Y251850D03*
X200500D03*
X214700Y158000D03*
X215000Y163600D03*
X211800Y191200D03*
X218700Y192400D03*
X253000Y227150D03*
X257000D03*
X225000Y211200D03*
X227000D03*
X257000Y218850D03*
X253000D03*
X256150Y205000D03*
X381500Y58300D03*
X449000Y250600D03*
X466500Y150963D03*
X464500D03*
X475100Y244500D03*
X519600Y214500D03*
X524500Y226150D03*
X533500Y206100D03*
X535500D03*
X539800Y238100D03*
X518850Y238000D03*
X539400Y233100D03*
X530500Y232700D03*
X595500Y79100D03*
X590500D03*
X586500D03*
X567500Y73200D03*
X565500D03*
X538500Y57100D03*
X536500D03*
X596500Y231100D03*
X598500D03*
X613500D03*
X618500D03*
X603300Y231950D03*
X620500Y231100D03*
X682150Y154500D03*
Y158500D03*
X685400Y177200D03*
X705900Y191500D03*
Y193500D03*
X716000Y203900D03*
X717500Y206000D03*
X656500Y222900D03*
X658500D03*
X568900Y226000D03*
X681500Y227800D03*
X568900Y228000D03*
X603300Y228850D03*
X607300D03*
X648300Y236500D03*
X558650Y238000D03*
X648300Y238500D03*
X596500Y235900D03*
X598500D03*
X613500D03*
X618500D03*
X620500D03*
X603300Y237150D03*
X672200Y45857D03*
X651800Y48107D03*
X649800D03*
X646300D03*
X644300D03*
X637800D03*
X632500D03*
X718000Y71900D03*
X781500Y46300D03*
X783500D03*
X724350Y52000D03*
X632500Y52907D03*
X637800D03*
X644300D03*
X646300D03*
X649800D03*
X651800D03*
X612800Y53007D03*
X672200Y54157D03*
X676200D03*
X713500Y54350D03*
X722500D03*
X749500Y67650D03*
X713000Y72300D03*
X743700Y73900D03*
X745700D03*
X717350Y83000D03*
X740500Y90900D03*
X742500D03*
X751800Y104150D03*
X621400Y207000D03*
Y209000D03*
X665150Y93000D03*
Y109500D03*
X664150Y117100D03*
Y121100D03*
X665150Y137500D03*
X673850Y154500D03*
Y158500D03*
X710000Y62200D03*
X782650Y5000D03*
Y14000D03*
X780400Y15000D03*
X782800Y18000D03*
X804500Y142400D03*
X806500D03*
X780500Y144200D03*
X762500Y156650D03*
X766500D03*
X727000Y159800D03*
X755500D03*
X734500Y168100D03*
X742500Y178200D03*
X745500Y188600D03*
X741500Y202300D03*
X738000Y231850D03*
X742000D03*
X743500Y235100D03*
X745500D03*
X807150Y258600D03*
X732650Y52000D03*
X740500Y59350D03*
X749500D03*
X732650Y61000D03*
X774350Y5000D03*
X767500Y121700D03*
X765500D03*
X798850Y258600D03*
G54D161*
X475850Y252000D03*
X518850Y233500D03*
X527150D03*
X724350Y56500D03*
X782650Y9500D03*
X807150Y263100D03*
X732650Y56500D03*
X774350Y9500D03*
X798850Y268100D03*
Y263100D03*
G54D158*
X151700Y216900D03*
X180300Y199700D03*
X186000Y60500D03*
X189000D03*
X192000D03*
X515000Y217850D03*
X520000Y226150D03*
X515000D03*
X593000Y79100D03*
X718000Y54350D03*
Y62650D03*
X729500Y159800D03*
X732500D03*
X753000D03*
X745000Y59350D03*
G54D159*
X186050Y150100D03*
X610950Y231100D03*
Y235900D03*
G54D163*
X635150Y48107D03*
Y52907D03*
G54D157*
X111750Y123350D03*
X106250D03*
X111750Y131650D03*
X106250D03*
X509750Y217850D03*
Y226150D03*
G54D164*
X612800Y47504D03*
G54D154*
X12000Y279000D03*
G54D151*
X45669Y77185D03*
Y172460D03*
G54D162*
X533299Y189496D03*
Y201504D03*
%LPD*%
G75*
G36*
G01X502953Y282316D02*
X503078Y282306D01*
X503203Y282266D01*
X503313Y282206D01*
X503413Y282126D01*
X503493Y282026D01*
X503553Y281916D01*
X503593Y281791D01*
X503603Y281666D01*
Y278236D01*
X503633Y278206D01*
X503733Y278066D01*
X503753Y278026D01*
X503768Y277991D01*
X503788Y277951D01*
X503803Y277911D01*
X503813Y277871D01*
X503828Y277826D01*
X503833Y277786D01*
X503843Y277746D01*
X503848Y277701D01*
Y277661D01*
X503853Y277616D01*
X503848Y277571D01*
Y277531D01*
X503843Y277486D01*
X503833Y277446D01*
X503828Y277406D01*
X503813Y277361D01*
X503803Y277321D01*
X503788Y277281D01*
X503768Y277241D01*
X503753Y277206D01*
X503733Y277166D01*
X503633Y277026D01*
X503603Y276996D01*
Y275866D01*
X503593Y275741D01*
X503553Y275616D01*
X503493Y275506D01*
X503413Y275406D01*
X503313Y275326D01*
X503203Y275266D01*
X503078Y275226D01*
X502953Y275216D01*
X502828Y275226D01*
X502703Y275266D01*
X502593Y275326D01*
X502493Y275406D01*
X502413Y275506D01*
X502353Y275616D01*
X502313Y275741D01*
X502303Y275866D01*
Y276996D01*
X502273Y277026D01*
X502173Y277166D01*
X502153Y277206D01*
X502138Y277241D01*
X502118Y277281D01*
X502103Y277321D01*
X502093Y277361D01*
X502078Y277406D01*
X502073Y277446D01*
X502063Y277486D01*
X502058Y277531D01*
Y277571D01*
X502053Y277616D01*
X502058Y277661D01*
Y277701D01*
X502063Y277746D01*
X502073Y277786D01*
X502078Y277826D01*
X502093Y277871D01*
X502103Y277911D01*
X502118Y277951D01*
X502138Y277991D01*
X502153Y278026D01*
X502173Y278066D01*
X502273Y278206D01*
X502303Y278236D01*
Y281666D01*
X502313Y281791D01*
X502353Y281916D01*
X502413Y282026D01*
X502493Y282126D01*
X502593Y282206D01*
X502703Y282266D01*
X502828Y282306D01*
X502953Y282316D01*
G37*
G36*
G01X507677D02*
X507802Y282306D01*
X507927Y282266D01*
X508037Y282206D01*
X508137Y282126D01*
X508217Y282026D01*
X508277Y281916D01*
X508317Y281791D01*
X508327Y281666D01*
Y278236D01*
X508357Y278206D01*
X508457Y278066D01*
X508477Y278026D01*
X508492Y277991D01*
X508512Y277951D01*
X508527Y277911D01*
X508537Y277871D01*
X508552Y277826D01*
X508557Y277786D01*
X508567Y277746D01*
X508572Y277701D01*
Y277661D01*
X508577Y277616D01*
X508572Y277571D01*
Y277531D01*
X508567Y277486D01*
X508557Y277446D01*
X508552Y277406D01*
X508537Y277361D01*
X508527Y277321D01*
X508512Y277281D01*
X508492Y277241D01*
X508477Y277206D01*
X508457Y277166D01*
X508357Y277026D01*
X508327Y276996D01*
Y275866D01*
X508317Y275741D01*
X508277Y275616D01*
X508217Y275506D01*
X508137Y275406D01*
X508037Y275326D01*
X507927Y275266D01*
X507802Y275226D01*
X507677Y275216D01*
X507552Y275226D01*
X507427Y275266D01*
X507317Y275326D01*
X507217Y275406D01*
X507137Y275506D01*
X507077Y275616D01*
X507037Y275741D01*
X507027Y275866D01*
Y276996D01*
X506997Y277026D01*
X506897Y277166D01*
X506877Y277206D01*
X506862Y277241D01*
X506842Y277281D01*
X506827Y277321D01*
X506817Y277361D01*
X506802Y277406D01*
X506797Y277446D01*
X506787Y277486D01*
X506782Y277531D01*
Y277571D01*
X506777Y277616D01*
X506782Y277661D01*
Y277701D01*
X506787Y277746D01*
X506797Y277786D01*
X506802Y277826D01*
X506817Y277871D01*
X506827Y277911D01*
X506842Y277951D01*
X506862Y277991D01*
X506877Y278026D01*
X506897Y278066D01*
X506997Y278206D01*
X507027Y278236D01*
Y281666D01*
X507037Y281791D01*
X507077Y281916D01*
X507137Y282026D01*
X507217Y282126D01*
X507317Y282206D01*
X507427Y282266D01*
X507552Y282306D01*
X507677Y282316D01*
G37*
G36*
G01X512402D02*
X512527Y282306D01*
X512652Y282266D01*
X512762Y282206D01*
X512862Y282126D01*
X512942Y282026D01*
X513002Y281916D01*
X513042Y281791D01*
X513052Y281666D01*
Y278236D01*
X513082Y278206D01*
X513182Y278066D01*
X513202Y278026D01*
X513217Y277991D01*
X513237Y277951D01*
X513252Y277911D01*
X513262Y277871D01*
X513277Y277826D01*
X513282Y277786D01*
X513292Y277746D01*
X513297Y277701D01*
Y277661D01*
X513302Y277616D01*
X513297Y277571D01*
Y277531D01*
X513292Y277486D01*
X513282Y277446D01*
X513277Y277406D01*
X513262Y277361D01*
X513252Y277321D01*
X513237Y277281D01*
X513217Y277241D01*
X513202Y277206D01*
X513182Y277166D01*
X513082Y277026D01*
X513052Y276996D01*
Y275866D01*
X513042Y275741D01*
X513002Y275616D01*
X512942Y275506D01*
X512862Y275406D01*
X512762Y275326D01*
X512652Y275266D01*
X512527Y275226D01*
X512402Y275216D01*
X512277Y275226D01*
X512152Y275266D01*
X512042Y275326D01*
X511942Y275406D01*
X511862Y275506D01*
X511802Y275616D01*
X511762Y275741D01*
X511752Y275866D01*
Y276996D01*
X511722Y277026D01*
X511622Y277166D01*
X511602Y277206D01*
X511587Y277241D01*
X511567Y277281D01*
X511552Y277321D01*
X511542Y277361D01*
X511527Y277406D01*
X511522Y277446D01*
X511512Y277486D01*
X511507Y277531D01*
Y277571D01*
X511502Y277616D01*
X511507Y277661D01*
Y277701D01*
X511512Y277746D01*
X511522Y277786D01*
X511527Y277826D01*
X511542Y277871D01*
X511552Y277911D01*
X511567Y277951D01*
X511587Y277991D01*
X511602Y278026D01*
X511622Y278066D01*
X511722Y278206D01*
X511752Y278236D01*
Y281666D01*
X511762Y281791D01*
X511802Y281916D01*
X511862Y282026D01*
X511942Y282126D01*
X512042Y282206D01*
X512152Y282266D01*
X512277Y282306D01*
X512402Y282316D01*
G37*
G36*
G01X517126D02*
X517251Y282306D01*
X517376Y282266D01*
X517486Y282206D01*
X517586Y282126D01*
X517666Y282026D01*
X517726Y281916D01*
X517766Y281791D01*
X517776Y281666D01*
Y278236D01*
X517806Y278206D01*
X517906Y278066D01*
X517926Y278026D01*
X517941Y277991D01*
X517961Y277951D01*
X517976Y277911D01*
X517986Y277871D01*
X518001Y277826D01*
X518006Y277786D01*
X518016Y277746D01*
X518021Y277701D01*
Y277661D01*
X518026Y277616D01*
X518021Y277571D01*
Y277531D01*
X518016Y277486D01*
X518006Y277446D01*
X518001Y277406D01*
X517986Y277361D01*
X517976Y277321D01*
X517961Y277281D01*
X517941Y277241D01*
X517926Y277206D01*
X517906Y277166D01*
X517806Y277026D01*
X517776Y276996D01*
Y275866D01*
X517766Y275741D01*
X517726Y275616D01*
X517666Y275506D01*
X517586Y275406D01*
X517486Y275326D01*
X517376Y275266D01*
X517251Y275226D01*
X517126Y275216D01*
X517001Y275226D01*
X516876Y275266D01*
X516766Y275326D01*
X516666Y275406D01*
X516586Y275506D01*
X516526Y275616D01*
X516486Y275741D01*
X516476Y275866D01*
Y276996D01*
X516446Y277026D01*
X516346Y277166D01*
X516326Y277206D01*
X516311Y277241D01*
X516291Y277281D01*
X516276Y277321D01*
X516266Y277361D01*
X516251Y277406D01*
X516246Y277446D01*
X516236Y277486D01*
X516231Y277531D01*
Y277571D01*
X516226Y277616D01*
X516231Y277661D01*
Y277701D01*
X516236Y277746D01*
X516246Y277786D01*
X516251Y277826D01*
X516266Y277871D01*
X516276Y277911D01*
X516291Y277951D01*
X516311Y277991D01*
X516326Y278026D01*
X516346Y278066D01*
X516446Y278206D01*
X516476Y278236D01*
Y281666D01*
X516486Y281791D01*
X516526Y281916D01*
X516586Y282026D01*
X516666Y282126D01*
X516766Y282206D01*
X516876Y282266D01*
X517001Y282306D01*
X517126Y282316D01*
G37*
G36*
G01X521851D02*
X521976Y282306D01*
X522101Y282266D01*
X522211Y282206D01*
X522311Y282126D01*
X522391Y282026D01*
X522451Y281916D01*
X522491Y281791D01*
X522501Y281666D01*
Y278236D01*
X522531Y278206D01*
X522631Y278066D01*
X522651Y278026D01*
X522666Y277991D01*
X522686Y277951D01*
X522701Y277911D01*
X522711Y277871D01*
X522726Y277826D01*
X522731Y277786D01*
X522741Y277746D01*
X522746Y277701D01*
Y277661D01*
X522751Y277616D01*
X522746Y277571D01*
Y277531D01*
X522741Y277486D01*
X522731Y277446D01*
X522726Y277406D01*
X522711Y277361D01*
X522701Y277321D01*
X522686Y277281D01*
X522666Y277241D01*
X522651Y277206D01*
X522631Y277166D01*
X522531Y277026D01*
X522501Y276996D01*
Y275866D01*
X522491Y275741D01*
X522451Y275616D01*
X522391Y275506D01*
X522311Y275406D01*
X522211Y275326D01*
X522101Y275266D01*
X521976Y275226D01*
X521851Y275216D01*
X521726Y275226D01*
X521601Y275266D01*
X521491Y275326D01*
X521391Y275406D01*
X521311Y275506D01*
X521251Y275616D01*
X521211Y275741D01*
X521201Y275866D01*
Y276996D01*
X521171Y277026D01*
X521071Y277166D01*
X521051Y277206D01*
X521036Y277241D01*
X521016Y277281D01*
X521001Y277321D01*
X520991Y277361D01*
X520976Y277406D01*
X520971Y277446D01*
X520961Y277486D01*
X520956Y277531D01*
Y277571D01*
X520951Y277616D01*
X520956Y277661D01*
Y277701D01*
X520961Y277746D01*
X520971Y277786D01*
X520976Y277826D01*
X520991Y277871D01*
X521001Y277911D01*
X521016Y277951D01*
X521036Y277991D01*
X521051Y278026D01*
X521071Y278066D01*
X521171Y278206D01*
X521201Y278236D01*
Y281666D01*
X521211Y281791D01*
X521251Y281916D01*
X521311Y282026D01*
X521391Y282126D01*
X521491Y282206D01*
X521601Y282266D01*
X521726Y282306D01*
X521851Y282316D01*
G37*
G36*
G01X526575D02*
X526700Y282306D01*
X526825Y282266D01*
X526935Y282206D01*
X527035Y282126D01*
X527115Y282026D01*
X527175Y281916D01*
X527215Y281791D01*
X527225Y281666D01*
Y278236D01*
X527255Y278206D01*
X527355Y278066D01*
X527375Y278026D01*
X527390Y277991D01*
X527410Y277951D01*
X527425Y277911D01*
X527435Y277871D01*
X527450Y277826D01*
X527455Y277786D01*
X527465Y277746D01*
X527470Y277701D01*
Y277661D01*
X527475Y277616D01*
X527470Y277571D01*
Y277531D01*
X527465Y277486D01*
X527455Y277446D01*
X527450Y277406D01*
X527435Y277361D01*
X527425Y277321D01*
X527410Y277281D01*
X527390Y277241D01*
X527375Y277206D01*
X527355Y277166D01*
X527255Y277026D01*
X527225Y276996D01*
Y275866D01*
X527215Y275741D01*
X527175Y275616D01*
X527115Y275506D01*
X527035Y275406D01*
X526935Y275326D01*
X526825Y275266D01*
X526700Y275226D01*
X526575Y275216D01*
X526450Y275226D01*
X526325Y275266D01*
X526215Y275326D01*
X526115Y275406D01*
X526035Y275506D01*
X525975Y275616D01*
X525935Y275741D01*
X525925Y275866D01*
Y276996D01*
X525895Y277026D01*
X525795Y277166D01*
X525775Y277206D01*
X525760Y277241D01*
X525740Y277281D01*
X525725Y277321D01*
X525715Y277361D01*
X525700Y277406D01*
X525695Y277446D01*
X525685Y277486D01*
X525680Y277531D01*
Y277571D01*
X525675Y277616D01*
X525680Y277661D01*
Y277701D01*
X525685Y277746D01*
X525695Y277786D01*
X525700Y277826D01*
X525715Y277871D01*
X525725Y277911D01*
X525740Y277951D01*
X525760Y277991D01*
X525775Y278026D01*
X525795Y278066D01*
X525895Y278206D01*
X525925Y278236D01*
Y281666D01*
X525935Y281791D01*
X525975Y281916D01*
X526035Y282026D01*
X526115Y282126D01*
X526215Y282206D01*
X526325Y282266D01*
X526450Y282306D01*
X526575Y282316D01*
G37*
G36*
G01X531299D02*
X531424Y282306D01*
X531549Y282266D01*
X531659Y282206D01*
X531759Y282126D01*
X531839Y282026D01*
X531899Y281916D01*
X531939Y281791D01*
X531949Y281666D01*
Y278236D01*
X531979Y278206D01*
X532079Y278066D01*
X532099Y278026D01*
X532114Y277991D01*
X532134Y277951D01*
X532149Y277911D01*
X532159Y277871D01*
X532174Y277826D01*
X532179Y277786D01*
X532189Y277746D01*
X532194Y277701D01*
Y277661D01*
X532199Y277616D01*
X532194Y277571D01*
Y277531D01*
X532189Y277486D01*
X532179Y277446D01*
X532174Y277406D01*
X532159Y277361D01*
X532149Y277321D01*
X532134Y277281D01*
X532114Y277241D01*
X532099Y277206D01*
X532079Y277166D01*
X531979Y277026D01*
X531949Y276996D01*
Y275866D01*
X531939Y275741D01*
X531899Y275616D01*
X531839Y275506D01*
X531759Y275406D01*
X531659Y275326D01*
X531549Y275266D01*
X531424Y275226D01*
X531299Y275216D01*
X531174Y275226D01*
X531049Y275266D01*
X530939Y275326D01*
X530839Y275406D01*
X530759Y275506D01*
X530699Y275616D01*
X530659Y275741D01*
X530649Y275866D01*
Y276996D01*
X530619Y277026D01*
X530519Y277166D01*
X530499Y277206D01*
X530484Y277241D01*
X530464Y277281D01*
X530449Y277321D01*
X530439Y277361D01*
X530424Y277406D01*
X530419Y277446D01*
X530409Y277486D01*
X530404Y277531D01*
Y277571D01*
X530399Y277616D01*
X530404Y277661D01*
Y277701D01*
X530409Y277746D01*
X530419Y277786D01*
X530424Y277826D01*
X530439Y277871D01*
X530449Y277911D01*
X530464Y277951D01*
X530484Y277991D01*
X530499Y278026D01*
X530519Y278066D01*
X530619Y278206D01*
X530649Y278236D01*
Y281666D01*
X530659Y281791D01*
X530699Y281916D01*
X530759Y282026D01*
X530839Y282126D01*
X530939Y282206D01*
X531049Y282266D01*
X531174Y282306D01*
X531299Y282316D01*
G37*
G36*
G01X536024D02*
X536149Y282306D01*
X536274Y282266D01*
X536384Y282206D01*
X536484Y282126D01*
X536564Y282026D01*
X536624Y281916D01*
X536664Y281791D01*
X536674Y281666D01*
Y278236D01*
X536704Y278206D01*
X536804Y278066D01*
X536824Y278026D01*
X536839Y277991D01*
X536859Y277951D01*
X536874Y277911D01*
X536884Y277871D01*
X536899Y277826D01*
X536904Y277786D01*
X536914Y277746D01*
X536919Y277701D01*
Y277661D01*
X536924Y277616D01*
X536919Y277571D01*
Y277531D01*
X536914Y277486D01*
X536904Y277446D01*
X536899Y277406D01*
X536884Y277361D01*
X536874Y277321D01*
X536859Y277281D01*
X536839Y277241D01*
X536824Y277206D01*
X536804Y277166D01*
X536704Y277026D01*
X536674Y276996D01*
Y275866D01*
X536664Y275741D01*
X536624Y275616D01*
X536564Y275506D01*
X536484Y275406D01*
X536384Y275326D01*
X536274Y275266D01*
X536149Y275226D01*
X536024Y275216D01*
X535899Y275226D01*
X535774Y275266D01*
X535664Y275326D01*
X535564Y275406D01*
X535484Y275506D01*
X535424Y275616D01*
X535384Y275741D01*
X535374Y275866D01*
Y276996D01*
X535344Y277026D01*
X535244Y277166D01*
X535224Y277206D01*
X535209Y277241D01*
X535189Y277281D01*
X535174Y277321D01*
X535164Y277361D01*
X535149Y277406D01*
X535144Y277446D01*
X535134Y277486D01*
X535129Y277531D01*
Y277571D01*
X535124Y277616D01*
X535129Y277661D01*
Y277701D01*
X535134Y277746D01*
X535144Y277786D01*
X535149Y277826D01*
X535164Y277871D01*
X535174Y277911D01*
X535189Y277951D01*
X535209Y277991D01*
X535224Y278026D01*
X535244Y278066D01*
X535344Y278206D01*
X535374Y278236D01*
Y281666D01*
X535384Y281791D01*
X535424Y281916D01*
X535484Y282026D01*
X535564Y282126D01*
X535664Y282206D01*
X535774Y282266D01*
X535899Y282306D01*
X536024Y282316D01*
G37*
G36*
G01X540748D02*
X540873Y282306D01*
X540998Y282266D01*
X541108Y282206D01*
X541208Y282126D01*
X541288Y282026D01*
X541348Y281916D01*
X541388Y281791D01*
X541398Y281666D01*
Y278236D01*
X541428Y278206D01*
X541528Y278066D01*
X541548Y278026D01*
X541563Y277991D01*
X541583Y277951D01*
X541598Y277911D01*
X541608Y277871D01*
X541623Y277826D01*
X541628Y277786D01*
X541638Y277746D01*
X541643Y277701D01*
Y277661D01*
X541648Y277616D01*
X541643Y277571D01*
Y277531D01*
X541638Y277486D01*
X541628Y277446D01*
X541623Y277406D01*
X541608Y277361D01*
X541598Y277321D01*
X541583Y277281D01*
X541563Y277241D01*
X541548Y277206D01*
X541528Y277166D01*
X541428Y277026D01*
X541398Y276996D01*
Y275866D01*
X541388Y275741D01*
X541348Y275616D01*
X541288Y275506D01*
X541208Y275406D01*
X541108Y275326D01*
X540998Y275266D01*
X540873Y275226D01*
X540748Y275216D01*
X540623Y275226D01*
X540498Y275266D01*
X540388Y275326D01*
X540288Y275406D01*
X540208Y275506D01*
X540148Y275616D01*
X540108Y275741D01*
X540098Y275866D01*
Y276996D01*
X540068Y277026D01*
X539968Y277166D01*
X539948Y277206D01*
X539933Y277241D01*
X539913Y277281D01*
X539898Y277321D01*
X539888Y277361D01*
X539873Y277406D01*
X539868Y277446D01*
X539858Y277486D01*
X539853Y277531D01*
Y277571D01*
X539848Y277616D01*
X539853Y277661D01*
Y277701D01*
X539858Y277746D01*
X539868Y277786D01*
X539873Y277826D01*
X539888Y277871D01*
X539898Y277911D01*
X539913Y277951D01*
X539933Y277991D01*
X539948Y278026D01*
X539968Y278066D01*
X540068Y278206D01*
X540098Y278236D01*
Y281666D01*
X540108Y281791D01*
X540148Y281916D01*
X540208Y282026D01*
X540288Y282126D01*
X540388Y282206D01*
X540498Y282266D01*
X540623Y282306D01*
X540748Y282316D01*
G37*
G36*
G01X545473D02*
X545598Y282306D01*
X545723Y282266D01*
X545833Y282206D01*
X545933Y282126D01*
X546013Y282026D01*
X546073Y281916D01*
X546113Y281791D01*
X546123Y281666D01*
Y278236D01*
X546153Y278206D01*
X546253Y278066D01*
X546273Y278026D01*
X546288Y277991D01*
X546308Y277951D01*
X546323Y277911D01*
X546333Y277871D01*
X546348Y277826D01*
X546353Y277786D01*
X546363Y277746D01*
X546368Y277701D01*
Y277661D01*
X546373Y277616D01*
X546368Y277571D01*
Y277531D01*
X546363Y277486D01*
X546353Y277446D01*
X546348Y277406D01*
X546333Y277361D01*
X546323Y277321D01*
X546308Y277281D01*
X546288Y277241D01*
X546273Y277206D01*
X546253Y277166D01*
X546153Y277026D01*
X546123Y276996D01*
Y275866D01*
X546113Y275741D01*
X546073Y275616D01*
X546013Y275506D01*
X545933Y275406D01*
X545833Y275326D01*
X545723Y275266D01*
X545598Y275226D01*
X545473Y275216D01*
X545348Y275226D01*
X545223Y275266D01*
X545113Y275326D01*
X545013Y275406D01*
X544933Y275506D01*
X544873Y275616D01*
X544833Y275741D01*
X544823Y275866D01*
Y276996D01*
X544793Y277026D01*
X544693Y277166D01*
X544673Y277206D01*
X544658Y277241D01*
X544638Y277281D01*
X544623Y277321D01*
X544613Y277361D01*
X544598Y277406D01*
X544593Y277446D01*
X544583Y277486D01*
X544578Y277531D01*
Y277571D01*
X544573Y277616D01*
X544578Y277661D01*
Y277701D01*
X544583Y277746D01*
X544593Y277786D01*
X544598Y277826D01*
X544613Y277871D01*
X544623Y277911D01*
X544638Y277951D01*
X544658Y277991D01*
X544673Y278026D01*
X544693Y278066D01*
X544793Y278206D01*
X544823Y278236D01*
Y281666D01*
X544833Y281791D01*
X544873Y281916D01*
X544933Y282026D01*
X545013Y282126D01*
X545113Y282206D01*
X545223Y282266D01*
X545348Y282306D01*
X545473Y282316D01*
G37*
G36*
G01X550197D02*
X550322Y282306D01*
X550447Y282266D01*
X550557Y282206D01*
X550657Y282126D01*
X550737Y282026D01*
X550797Y281916D01*
X550837Y281791D01*
X550847Y281666D01*
Y278236D01*
X550877Y278206D01*
X550977Y278066D01*
X550997Y278026D01*
X551012Y277991D01*
X551032Y277951D01*
X551047Y277911D01*
X551057Y277871D01*
X551072Y277826D01*
X551077Y277786D01*
X551087Y277746D01*
X551092Y277701D01*
Y277661D01*
X551097Y277616D01*
X551092Y277571D01*
Y277531D01*
X551087Y277486D01*
X551077Y277446D01*
X551072Y277406D01*
X551057Y277361D01*
X551047Y277321D01*
X551032Y277281D01*
X551012Y277241D01*
X550997Y277206D01*
X550977Y277166D01*
X550877Y277026D01*
X550847Y276996D01*
Y275866D01*
X550837Y275741D01*
X550797Y275616D01*
X550737Y275506D01*
X550657Y275406D01*
X550557Y275326D01*
X550447Y275266D01*
X550322Y275226D01*
X550197Y275216D01*
X550072Y275226D01*
X549947Y275266D01*
X549837Y275326D01*
X549737Y275406D01*
X549657Y275506D01*
X549597Y275616D01*
X549557Y275741D01*
X549547Y275866D01*
Y276996D01*
X549517Y277026D01*
X549417Y277166D01*
X549397Y277206D01*
X549382Y277241D01*
X549362Y277281D01*
X549347Y277321D01*
X549337Y277361D01*
X549322Y277406D01*
X549317Y277446D01*
X549307Y277486D01*
X549302Y277531D01*
Y277571D01*
X549297Y277616D01*
X549302Y277661D01*
Y277701D01*
X549307Y277746D01*
X549317Y277786D01*
X549322Y277826D01*
X549337Y277871D01*
X549347Y277911D01*
X549362Y277951D01*
X549382Y277991D01*
X549397Y278026D01*
X549417Y278066D01*
X549517Y278206D01*
X549547Y278236D01*
Y281666D01*
X549557Y281791D01*
X549597Y281916D01*
X549657Y282026D01*
X549737Y282126D01*
X549837Y282206D01*
X549947Y282266D01*
X550072Y282306D01*
X550197Y282316D01*
G37*
G36*
G01X554922D02*
X555047Y282306D01*
X555172Y282266D01*
X555282Y282206D01*
X555382Y282126D01*
X555462Y282026D01*
X555522Y281916D01*
X555562Y281791D01*
X555572Y281666D01*
Y278236D01*
X555602Y278206D01*
X555702Y278066D01*
X555722Y278026D01*
X555737Y277991D01*
X555757Y277951D01*
X555772Y277911D01*
X555782Y277871D01*
X555797Y277826D01*
X555802Y277786D01*
X555812Y277746D01*
X555817Y277701D01*
Y277661D01*
X555822Y277616D01*
X555817Y277571D01*
Y277531D01*
X555812Y277486D01*
X555802Y277446D01*
X555797Y277406D01*
X555782Y277361D01*
X555772Y277321D01*
X555757Y277281D01*
X555737Y277241D01*
X555722Y277206D01*
X555702Y277166D01*
X555602Y277026D01*
X555572Y276996D01*
Y275866D01*
X555562Y275741D01*
X555522Y275616D01*
X555462Y275506D01*
X555382Y275406D01*
X555282Y275326D01*
X555172Y275266D01*
X555047Y275226D01*
X554922Y275216D01*
X554797Y275226D01*
X554672Y275266D01*
X554562Y275326D01*
X554462Y275406D01*
X554382Y275506D01*
X554322Y275616D01*
X554282Y275741D01*
X554272Y275866D01*
Y276996D01*
X554242Y277026D01*
X554142Y277166D01*
X554122Y277206D01*
X554107Y277241D01*
X554087Y277281D01*
X554072Y277321D01*
X554062Y277361D01*
X554047Y277406D01*
X554042Y277446D01*
X554032Y277486D01*
X554027Y277531D01*
Y277571D01*
X554022Y277616D01*
X554027Y277661D01*
Y277701D01*
X554032Y277746D01*
X554042Y277786D01*
X554047Y277826D01*
X554062Y277871D01*
X554072Y277911D01*
X554087Y277951D01*
X554107Y277991D01*
X554122Y278026D01*
X554142Y278066D01*
X554242Y278206D01*
X554272Y278236D01*
Y281666D01*
X554282Y281791D01*
X554322Y281916D01*
X554382Y282026D01*
X554462Y282126D01*
X554562Y282206D01*
X554672Y282266D01*
X554797Y282306D01*
X554922Y282316D01*
G37*
G36*
G01X559646D02*
X559771Y282306D01*
X559896Y282266D01*
X560006Y282206D01*
X560106Y282126D01*
X560186Y282026D01*
X560246Y281916D01*
X560286Y281791D01*
X560296Y281666D01*
Y278236D01*
X560326Y278206D01*
X560426Y278066D01*
X560446Y278026D01*
X560461Y277991D01*
X560481Y277951D01*
X560496Y277911D01*
X560506Y277871D01*
X560521Y277826D01*
X560526Y277786D01*
X560536Y277746D01*
X560541Y277701D01*
Y277661D01*
X560546Y277616D01*
X560541Y277571D01*
Y277531D01*
X560536Y277486D01*
X560526Y277446D01*
X560521Y277406D01*
X560506Y277361D01*
X560496Y277321D01*
X560481Y277281D01*
X560461Y277241D01*
X560446Y277206D01*
X560426Y277166D01*
X560326Y277026D01*
X560296Y276996D01*
Y275866D01*
X560286Y275741D01*
X560246Y275616D01*
X560186Y275506D01*
X560106Y275406D01*
X560006Y275326D01*
X559896Y275266D01*
X559771Y275226D01*
X559646Y275216D01*
X559521Y275226D01*
X559396Y275266D01*
X559286Y275326D01*
X559186Y275406D01*
X559106Y275506D01*
X559046Y275616D01*
X559006Y275741D01*
X558996Y275866D01*
Y276996D01*
X558966Y277026D01*
X558866Y277166D01*
X558846Y277206D01*
X558831Y277241D01*
X558811Y277281D01*
X558796Y277321D01*
X558786Y277361D01*
X558771Y277406D01*
X558766Y277446D01*
X558756Y277486D01*
X558751Y277531D01*
Y277571D01*
X558746Y277616D01*
X558751Y277661D01*
Y277701D01*
X558756Y277746D01*
X558766Y277786D01*
X558771Y277826D01*
X558786Y277871D01*
X558796Y277911D01*
X558811Y277951D01*
X558831Y277991D01*
X558846Y278026D01*
X558866Y278066D01*
X558966Y278206D01*
X558996Y278236D01*
Y281666D01*
X559006Y281791D01*
X559046Y281916D01*
X559106Y282026D01*
X559186Y282126D01*
X559286Y282206D01*
X559396Y282266D01*
X559521Y282306D01*
X559646Y282316D01*
G37*
G36*
G01X564370D02*
X564495Y282306D01*
X564620Y282266D01*
X564730Y282206D01*
X564830Y282126D01*
X564910Y282026D01*
X564970Y281916D01*
X565010Y281791D01*
X565020Y281666D01*
Y278236D01*
X565050Y278206D01*
X565150Y278066D01*
X565170Y278026D01*
X565185Y277991D01*
X565205Y277951D01*
X565220Y277911D01*
X565230Y277871D01*
X565245Y277826D01*
X565250Y277786D01*
X565260Y277746D01*
X565265Y277701D01*
Y277661D01*
X565270Y277616D01*
X565265Y277571D01*
Y277531D01*
X565260Y277486D01*
X565250Y277446D01*
X565245Y277406D01*
X565230Y277361D01*
X565220Y277321D01*
X565205Y277281D01*
X565185Y277241D01*
X565170Y277206D01*
X565150Y277166D01*
X565050Y277026D01*
X565020Y276996D01*
Y275866D01*
X565010Y275741D01*
X564970Y275616D01*
X564910Y275506D01*
X564830Y275406D01*
X564730Y275326D01*
X564620Y275266D01*
X564495Y275226D01*
X564370Y275216D01*
X564245Y275226D01*
X564120Y275266D01*
X564010Y275326D01*
X563910Y275406D01*
X563830Y275506D01*
X563770Y275616D01*
X563730Y275741D01*
X563720Y275866D01*
Y276996D01*
X563690Y277026D01*
X563590Y277166D01*
X563570Y277206D01*
X563555Y277241D01*
X563535Y277281D01*
X563520Y277321D01*
X563510Y277361D01*
X563495Y277406D01*
X563490Y277446D01*
X563480Y277486D01*
X563475Y277531D01*
Y277571D01*
X563470Y277616D01*
X563475Y277661D01*
Y277701D01*
X563480Y277746D01*
X563490Y277786D01*
X563495Y277826D01*
X563510Y277871D01*
X563520Y277911D01*
X563535Y277951D01*
X563555Y277991D01*
X563570Y278026D01*
X563590Y278066D01*
X563690Y278206D01*
X563720Y278236D01*
Y281666D01*
X563730Y281791D01*
X563770Y281916D01*
X563830Y282026D01*
X563910Y282126D01*
X564010Y282206D01*
X564120Y282266D01*
X564245Y282306D01*
X564370Y282316D01*
G37*
G36*
G01X569095D02*
X569220Y282306D01*
X569345Y282266D01*
X569455Y282206D01*
X569555Y282126D01*
X569635Y282026D01*
X569695Y281916D01*
X569735Y281791D01*
X569745Y281666D01*
Y278236D01*
X569775Y278206D01*
X569875Y278066D01*
X569895Y278026D01*
X569910Y277991D01*
X569930Y277951D01*
X569945Y277911D01*
X569955Y277871D01*
X569970Y277826D01*
X569975Y277786D01*
X569985Y277746D01*
X569990Y277701D01*
Y277661D01*
X569995Y277616D01*
X569990Y277571D01*
Y277531D01*
X569985Y277486D01*
X569975Y277446D01*
X569970Y277406D01*
X569955Y277361D01*
X569945Y277321D01*
X569930Y277281D01*
X569910Y277241D01*
X569895Y277206D01*
X569875Y277166D01*
X569775Y277026D01*
X569745Y276996D01*
Y275866D01*
X569735Y275741D01*
X569695Y275616D01*
X569635Y275506D01*
X569555Y275406D01*
X569455Y275326D01*
X569345Y275266D01*
X569220Y275226D01*
X569095Y275216D01*
X568970Y275226D01*
X568845Y275266D01*
X568735Y275326D01*
X568635Y275406D01*
X568555Y275506D01*
X568495Y275616D01*
X568455Y275741D01*
X568445Y275866D01*
Y276996D01*
X568415Y277026D01*
X568315Y277166D01*
X568295Y277206D01*
X568280Y277241D01*
X568260Y277281D01*
X568245Y277321D01*
X568235Y277361D01*
X568220Y277406D01*
X568215Y277446D01*
X568205Y277486D01*
X568200Y277531D01*
Y277571D01*
X568195Y277616D01*
X568200Y277661D01*
Y277701D01*
X568205Y277746D01*
X568215Y277786D01*
X568220Y277826D01*
X568235Y277871D01*
X568245Y277911D01*
X568260Y277951D01*
X568280Y277991D01*
X568295Y278026D01*
X568315Y278066D01*
X568415Y278206D01*
X568445Y278236D01*
Y281666D01*
X568455Y281791D01*
X568495Y281916D01*
X568555Y282026D01*
X568635Y282126D01*
X568735Y282206D01*
X568845Y282266D01*
X568970Y282306D01*
X569095Y282316D01*
G37*
G36*
G01X573819D02*
X573944Y282306D01*
X574069Y282266D01*
X574179Y282206D01*
X574279Y282126D01*
X574359Y282026D01*
X574419Y281916D01*
X574459Y281791D01*
X574469Y281666D01*
Y278236D01*
X574499Y278206D01*
X574599Y278066D01*
X574619Y278026D01*
X574634Y277991D01*
X574654Y277951D01*
X574669Y277911D01*
X574679Y277871D01*
X574694Y277826D01*
X574699Y277786D01*
X574709Y277746D01*
X574714Y277701D01*
Y277661D01*
X574719Y277616D01*
X574714Y277571D01*
Y277531D01*
X574709Y277486D01*
X574699Y277446D01*
X574694Y277406D01*
X574679Y277361D01*
X574669Y277321D01*
X574654Y277281D01*
X574634Y277241D01*
X574619Y277206D01*
X574599Y277166D01*
X574499Y277026D01*
X574469Y276996D01*
Y275866D01*
X574459Y275741D01*
X574419Y275616D01*
X574359Y275506D01*
X574279Y275406D01*
X574179Y275326D01*
X574069Y275266D01*
X573944Y275226D01*
X573819Y275216D01*
X573694Y275226D01*
X573569Y275266D01*
X573459Y275326D01*
X573359Y275406D01*
X573279Y275506D01*
X573219Y275616D01*
X573179Y275741D01*
X573169Y275866D01*
Y276996D01*
X573139Y277026D01*
X573039Y277166D01*
X573019Y277206D01*
X573004Y277241D01*
X572984Y277281D01*
X572969Y277321D01*
X572959Y277361D01*
X572944Y277406D01*
X572939Y277446D01*
X572929Y277486D01*
X572924Y277531D01*
Y277571D01*
X572919Y277616D01*
X572924Y277661D01*
Y277701D01*
X572929Y277746D01*
X572939Y277786D01*
X572944Y277826D01*
X572959Y277871D01*
X572969Y277911D01*
X572984Y277951D01*
X573004Y277991D01*
X573019Y278026D01*
X573039Y278066D01*
X573139Y278206D01*
X573169Y278236D01*
Y281666D01*
X573179Y281791D01*
X573219Y281916D01*
X573279Y282026D01*
X573359Y282126D01*
X573459Y282206D01*
X573569Y282266D01*
X573694Y282306D01*
X573819Y282316D01*
G37*
G36*
G01X578544D02*
X578669Y282306D01*
X578794Y282266D01*
X578904Y282206D01*
X579004Y282126D01*
X579084Y282026D01*
X579144Y281916D01*
X579184Y281791D01*
X579194Y281666D01*
Y278236D01*
X579224Y278206D01*
X579324Y278066D01*
X579344Y278026D01*
X579359Y277991D01*
X579379Y277951D01*
X579394Y277911D01*
X579404Y277871D01*
X579419Y277826D01*
X579424Y277786D01*
X579434Y277746D01*
X579439Y277701D01*
Y277661D01*
X579444Y277616D01*
X579439Y277571D01*
Y277531D01*
X579434Y277486D01*
X579424Y277446D01*
X579419Y277406D01*
X579404Y277361D01*
X579394Y277321D01*
X579379Y277281D01*
X579359Y277241D01*
X579344Y277206D01*
X579324Y277166D01*
X579224Y277026D01*
X579194Y276996D01*
Y275866D01*
X579184Y275741D01*
X579144Y275616D01*
X579084Y275506D01*
X579004Y275406D01*
X578904Y275326D01*
X578794Y275266D01*
X578669Y275226D01*
X578544Y275216D01*
X578419Y275226D01*
X578294Y275266D01*
X578184Y275326D01*
X578084Y275406D01*
X578004Y275506D01*
X577944Y275616D01*
X577904Y275741D01*
X577894Y275866D01*
Y276996D01*
X577864Y277026D01*
X577764Y277166D01*
X577744Y277206D01*
X577729Y277241D01*
X577709Y277281D01*
X577694Y277321D01*
X577684Y277361D01*
X577669Y277406D01*
X577664Y277446D01*
X577654Y277486D01*
X577649Y277531D01*
Y277571D01*
X577644Y277616D01*
X577649Y277661D01*
Y277701D01*
X577654Y277746D01*
X577664Y277786D01*
X577669Y277826D01*
X577684Y277871D01*
X577694Y277911D01*
X577709Y277951D01*
X577729Y277991D01*
X577744Y278026D01*
X577764Y278066D01*
X577864Y278206D01*
X577894Y278236D01*
Y281666D01*
X577904Y281791D01*
X577944Y281916D01*
X578004Y282026D01*
X578084Y282126D01*
X578184Y282206D01*
X578294Y282266D01*
X578419Y282306D01*
X578544Y282316D01*
G37*
G36*
G01X583268D02*
X583393Y282306D01*
X583518Y282266D01*
X583628Y282206D01*
X583728Y282126D01*
X583808Y282026D01*
X583868Y281916D01*
X583908Y281791D01*
X583918Y281666D01*
Y278236D01*
X583948Y278206D01*
X584048Y278066D01*
X584068Y278026D01*
X584083Y277991D01*
X584103Y277951D01*
X584118Y277911D01*
X584128Y277871D01*
X584143Y277826D01*
X584148Y277786D01*
X584158Y277746D01*
X584163Y277701D01*
Y277661D01*
X584168Y277616D01*
X584163Y277571D01*
Y277531D01*
X584158Y277486D01*
X584148Y277446D01*
X584143Y277406D01*
X584128Y277361D01*
X584118Y277321D01*
X584103Y277281D01*
X584083Y277241D01*
X584068Y277206D01*
X584048Y277166D01*
X583948Y277026D01*
X583918Y276996D01*
Y275866D01*
X583908Y275741D01*
X583868Y275616D01*
X583808Y275506D01*
X583728Y275406D01*
X583628Y275326D01*
X583518Y275266D01*
X583393Y275226D01*
X583268Y275216D01*
X583143Y275226D01*
X583018Y275266D01*
X582908Y275326D01*
X582808Y275406D01*
X582728Y275506D01*
X582668Y275616D01*
X582628Y275741D01*
X582618Y275866D01*
Y276996D01*
X582588Y277026D01*
X582488Y277166D01*
X582468Y277206D01*
X582453Y277241D01*
X582433Y277281D01*
X582418Y277321D01*
X582408Y277361D01*
X582393Y277406D01*
X582388Y277446D01*
X582378Y277486D01*
X582373Y277531D01*
Y277571D01*
X582368Y277616D01*
X582373Y277661D01*
Y277701D01*
X582378Y277746D01*
X582388Y277786D01*
X582393Y277826D01*
X582408Y277871D01*
X582418Y277911D01*
X582433Y277951D01*
X582453Y277991D01*
X582468Y278026D01*
X582488Y278066D01*
X582588Y278206D01*
X582618Y278236D01*
Y281666D01*
X582628Y281791D01*
X582668Y281916D01*
X582728Y282026D01*
X582808Y282126D01*
X582908Y282206D01*
X583018Y282266D01*
X583143Y282306D01*
X583268Y282316D01*
G37*
G36*
G01X587992D02*
X588117Y282306D01*
X588242Y282266D01*
X588352Y282206D01*
X588452Y282126D01*
X588532Y282026D01*
X588592Y281916D01*
X588632Y281791D01*
X588642Y281666D01*
Y278236D01*
X588672Y278206D01*
X588772Y278066D01*
X588792Y278026D01*
X588807Y277991D01*
X588827Y277951D01*
X588842Y277911D01*
X588852Y277871D01*
X588867Y277826D01*
X588872Y277786D01*
X588882Y277746D01*
X588887Y277701D01*
Y277661D01*
X588892Y277616D01*
X588887Y277571D01*
Y277531D01*
X588882Y277486D01*
X588872Y277446D01*
X588867Y277406D01*
X588852Y277361D01*
X588842Y277321D01*
X588827Y277281D01*
X588807Y277241D01*
X588792Y277206D01*
X588772Y277166D01*
X588672Y277026D01*
X588642Y276996D01*
Y275866D01*
X588632Y275741D01*
X588592Y275616D01*
X588532Y275506D01*
X588452Y275406D01*
X588352Y275326D01*
X588242Y275266D01*
X588117Y275226D01*
X587992Y275216D01*
X587867Y275226D01*
X587742Y275266D01*
X587632Y275326D01*
X587532Y275406D01*
X587452Y275506D01*
X587392Y275616D01*
X587352Y275741D01*
X587342Y275866D01*
Y276996D01*
X587312Y277026D01*
X587212Y277166D01*
X587192Y277206D01*
X587177Y277241D01*
X587157Y277281D01*
X587142Y277321D01*
X587132Y277361D01*
X587117Y277406D01*
X587112Y277446D01*
X587102Y277486D01*
X587097Y277531D01*
Y277571D01*
X587092Y277616D01*
X587097Y277661D01*
Y277701D01*
X587102Y277746D01*
X587112Y277786D01*
X587117Y277826D01*
X587132Y277871D01*
X587142Y277911D01*
X587157Y277951D01*
X587177Y277991D01*
X587192Y278026D01*
X587212Y278066D01*
X587312Y278206D01*
X587342Y278236D01*
Y281666D01*
X587352Y281791D01*
X587392Y281916D01*
X587452Y282026D01*
X587532Y282126D01*
X587632Y282206D01*
X587742Y282266D01*
X587867Y282306D01*
X587992Y282316D01*
G37*
G36*
G01X592717D02*
X592842Y282306D01*
X592967Y282266D01*
X593077Y282206D01*
X593177Y282126D01*
X593257Y282026D01*
X593317Y281916D01*
X593357Y281791D01*
X593367Y281666D01*
Y278236D01*
X593397Y278206D01*
X593497Y278066D01*
X593517Y278026D01*
X593532Y277991D01*
X593552Y277951D01*
X593567Y277911D01*
X593577Y277871D01*
X593592Y277826D01*
X593597Y277786D01*
X593607Y277746D01*
X593612Y277701D01*
Y277661D01*
X593617Y277616D01*
X593612Y277571D01*
Y277531D01*
X593607Y277486D01*
X593597Y277446D01*
X593592Y277406D01*
X593577Y277361D01*
X593567Y277321D01*
X593552Y277281D01*
X593532Y277241D01*
X593517Y277206D01*
X593497Y277166D01*
X593397Y277026D01*
X593367Y276996D01*
Y275866D01*
X593357Y275741D01*
X593317Y275616D01*
X593257Y275506D01*
X593177Y275406D01*
X593077Y275326D01*
X592967Y275266D01*
X592842Y275226D01*
X592717Y275216D01*
X592592Y275226D01*
X592467Y275266D01*
X592357Y275326D01*
X592257Y275406D01*
X592177Y275506D01*
X592117Y275616D01*
X592077Y275741D01*
X592067Y275866D01*
Y276996D01*
X592037Y277026D01*
X591937Y277166D01*
X591917Y277206D01*
X591902Y277241D01*
X591882Y277281D01*
X591867Y277321D01*
X591857Y277361D01*
X591842Y277406D01*
X591837Y277446D01*
X591827Y277486D01*
X591822Y277531D01*
Y277571D01*
X591817Y277616D01*
X591822Y277661D01*
Y277701D01*
X591827Y277746D01*
X591837Y277786D01*
X591842Y277826D01*
X591857Y277871D01*
X591867Y277911D01*
X591882Y277951D01*
X591902Y277991D01*
X591917Y278026D01*
X591937Y278066D01*
X592037Y278206D01*
X592067Y278236D01*
Y281666D01*
X592077Y281791D01*
X592117Y281916D01*
X592177Y282026D01*
X592257Y282126D01*
X592357Y282206D01*
X592467Y282266D01*
X592592Y282306D01*
X592717Y282316D01*
G37*
G36*
G01X597441D02*
X597566Y282306D01*
X597691Y282266D01*
X597801Y282206D01*
X597901Y282126D01*
X597981Y282026D01*
X598041Y281916D01*
X598081Y281791D01*
X598091Y281666D01*
Y278236D01*
X598121Y278206D01*
X598221Y278066D01*
X598241Y278026D01*
X598256Y277991D01*
X598276Y277951D01*
X598291Y277911D01*
X598301Y277871D01*
X598316Y277826D01*
X598321Y277786D01*
X598331Y277746D01*
X598336Y277701D01*
Y277661D01*
X598341Y277616D01*
X598336Y277571D01*
Y277531D01*
X598331Y277486D01*
X598321Y277446D01*
X598316Y277406D01*
X598301Y277361D01*
X598291Y277321D01*
X598276Y277281D01*
X598256Y277241D01*
X598241Y277206D01*
X598221Y277166D01*
X598121Y277026D01*
X598091Y276996D01*
Y275866D01*
X598081Y275741D01*
X598041Y275616D01*
X597981Y275506D01*
X597901Y275406D01*
X597801Y275326D01*
X597691Y275266D01*
X597566Y275226D01*
X597441Y275216D01*
X597316Y275226D01*
X597191Y275266D01*
X597081Y275326D01*
X596981Y275406D01*
X596901Y275506D01*
X596841Y275616D01*
X596801Y275741D01*
X596791Y275866D01*
Y276996D01*
X596761Y277026D01*
X596661Y277166D01*
X596641Y277206D01*
X596626Y277241D01*
X596606Y277281D01*
X596591Y277321D01*
X596581Y277361D01*
X596566Y277406D01*
X596561Y277446D01*
X596551Y277486D01*
X596546Y277531D01*
Y277571D01*
X596541Y277616D01*
X596546Y277661D01*
Y277701D01*
X596551Y277746D01*
X596561Y277786D01*
X596566Y277826D01*
X596581Y277871D01*
X596591Y277911D01*
X596606Y277951D01*
X596626Y277991D01*
X596641Y278026D01*
X596661Y278066D01*
X596761Y278206D01*
X596791Y278236D01*
Y281666D01*
X596801Y281791D01*
X596841Y281916D01*
X596901Y282026D01*
X596981Y282126D01*
X597081Y282206D01*
X597191Y282266D01*
X597316Y282306D01*
X597441Y282316D01*
G37*
G36*
G01X602166D02*
X602291Y282306D01*
X602416Y282266D01*
X602526Y282206D01*
X602626Y282126D01*
X602706Y282026D01*
X602766Y281916D01*
X602806Y281791D01*
X602816Y281666D01*
Y278236D01*
X602846Y278206D01*
X602946Y278066D01*
X602966Y278026D01*
X602981Y277991D01*
X603001Y277951D01*
X603016Y277911D01*
X603026Y277871D01*
X603041Y277826D01*
X603046Y277786D01*
X603056Y277746D01*
X603061Y277701D01*
Y277661D01*
X603066Y277616D01*
X603061Y277571D01*
Y277531D01*
X603056Y277486D01*
X603046Y277446D01*
X603041Y277406D01*
X603026Y277361D01*
X603016Y277321D01*
X603001Y277281D01*
X602981Y277241D01*
X602966Y277206D01*
X602946Y277166D01*
X602846Y277026D01*
X602816Y276996D01*
Y275866D01*
X602806Y275741D01*
X602766Y275616D01*
X602706Y275506D01*
X602626Y275406D01*
X602526Y275326D01*
X602416Y275266D01*
X602291Y275226D01*
X602166Y275216D01*
X602041Y275226D01*
X601916Y275266D01*
X601806Y275326D01*
X601706Y275406D01*
X601626Y275506D01*
X601566Y275616D01*
X601526Y275741D01*
X601516Y275866D01*
Y276996D01*
X601486Y277026D01*
X601386Y277166D01*
X601366Y277206D01*
X601351Y277241D01*
X601331Y277281D01*
X601316Y277321D01*
X601306Y277361D01*
X601291Y277406D01*
X601286Y277446D01*
X601276Y277486D01*
X601271Y277531D01*
Y277571D01*
X601266Y277616D01*
X601271Y277661D01*
Y277701D01*
X601276Y277746D01*
X601286Y277786D01*
X601291Y277826D01*
X601306Y277871D01*
X601316Y277911D01*
X601331Y277951D01*
X601351Y277991D01*
X601366Y278026D01*
X601386Y278066D01*
X601486Y278206D01*
X601516Y278236D01*
Y281666D01*
X601526Y281791D01*
X601566Y281916D01*
X601626Y282026D01*
X601706Y282126D01*
X601806Y282206D01*
X601916Y282266D01*
X602041Y282306D01*
X602166Y282316D01*
G37*
G36*
G01X606890D02*
X607015Y282306D01*
X607140Y282266D01*
X607250Y282206D01*
X607350Y282126D01*
X607430Y282026D01*
X607490Y281916D01*
X607530Y281791D01*
X607540Y281666D01*
Y278236D01*
X607570Y278206D01*
X607670Y278066D01*
X607690Y278026D01*
X607705Y277991D01*
X607725Y277951D01*
X607740Y277911D01*
X607750Y277871D01*
X607765Y277826D01*
X607770Y277786D01*
X607780Y277746D01*
X607785Y277701D01*
Y277661D01*
X607790Y277616D01*
X607785Y277571D01*
Y277531D01*
X607780Y277486D01*
X607770Y277446D01*
X607765Y277406D01*
X607750Y277361D01*
X607740Y277321D01*
X607725Y277281D01*
X607705Y277241D01*
X607690Y277206D01*
X607670Y277166D01*
X607570Y277026D01*
X607540Y276996D01*
Y275866D01*
X607530Y275741D01*
X607490Y275616D01*
X607430Y275506D01*
X607350Y275406D01*
X607250Y275326D01*
X607140Y275266D01*
X607015Y275226D01*
X606890Y275216D01*
X606765Y275226D01*
X606640Y275266D01*
X606530Y275326D01*
X606430Y275406D01*
X606350Y275506D01*
X606290Y275616D01*
X606250Y275741D01*
X606240Y275866D01*
Y276996D01*
X606210Y277026D01*
X606110Y277166D01*
X606090Y277206D01*
X606075Y277241D01*
X606055Y277281D01*
X606040Y277321D01*
X606030Y277361D01*
X606015Y277406D01*
X606010Y277446D01*
X606000Y277486D01*
X605995Y277531D01*
Y277571D01*
X605990Y277616D01*
X605995Y277661D01*
Y277701D01*
X606000Y277746D01*
X606010Y277786D01*
X606015Y277826D01*
X606030Y277871D01*
X606040Y277911D01*
X606055Y277951D01*
X606075Y277991D01*
X606090Y278026D01*
X606110Y278066D01*
X606210Y278206D01*
X606240Y278236D01*
Y281666D01*
X606250Y281791D01*
X606290Y281916D01*
X606350Y282026D01*
X606430Y282126D01*
X606530Y282206D01*
X606640Y282266D01*
X606765Y282306D01*
X606890Y282316D01*
G37*
G36*
G01X611614D02*
X611739Y282306D01*
X611864Y282266D01*
X611974Y282206D01*
X612074Y282126D01*
X612154Y282026D01*
X612214Y281916D01*
X612254Y281791D01*
X612264Y281666D01*
Y278236D01*
X612294Y278206D01*
X612394Y278066D01*
X612414Y278026D01*
X612429Y277991D01*
X612449Y277951D01*
X612464Y277911D01*
X612474Y277871D01*
X612489Y277826D01*
X612494Y277786D01*
X612504Y277746D01*
X612509Y277701D01*
Y277661D01*
X612514Y277616D01*
X612509Y277571D01*
Y277531D01*
X612504Y277486D01*
X612494Y277446D01*
X612489Y277406D01*
X612474Y277361D01*
X612464Y277321D01*
X612449Y277281D01*
X612429Y277241D01*
X612414Y277206D01*
X612394Y277166D01*
X612294Y277026D01*
X612264Y276996D01*
Y275866D01*
X612254Y275741D01*
X612214Y275616D01*
X612154Y275506D01*
X612074Y275406D01*
X611974Y275326D01*
X611864Y275266D01*
X611739Y275226D01*
X611614Y275216D01*
X611489Y275226D01*
X611364Y275266D01*
X611254Y275326D01*
X611154Y275406D01*
X611074Y275506D01*
X611014Y275616D01*
X610974Y275741D01*
X610964Y275866D01*
Y276996D01*
X610934Y277026D01*
X610834Y277166D01*
X610814Y277206D01*
X610799Y277241D01*
X610779Y277281D01*
X610764Y277321D01*
X610754Y277361D01*
X610739Y277406D01*
X610734Y277446D01*
X610724Y277486D01*
X610719Y277531D01*
Y277571D01*
X610714Y277616D01*
X610719Y277661D01*
Y277701D01*
X610724Y277746D01*
X610734Y277786D01*
X610739Y277826D01*
X610754Y277871D01*
X610764Y277911D01*
X610779Y277951D01*
X610799Y277991D01*
X610814Y278026D01*
X610834Y278066D01*
X610934Y278206D01*
X610964Y278236D01*
Y281666D01*
X610974Y281791D01*
X611014Y281916D01*
X611074Y282026D01*
X611154Y282126D01*
X611254Y282206D01*
X611364Y282266D01*
X611489Y282306D01*
X611614Y282316D01*
G37*
G36*
G01X616339D02*
X616464Y282306D01*
X616589Y282266D01*
X616699Y282206D01*
X616799Y282126D01*
X616879Y282026D01*
X616939Y281916D01*
X616979Y281791D01*
X616989Y281666D01*
Y278236D01*
X617019Y278206D01*
X617119Y278066D01*
X617139Y278026D01*
X617154Y277991D01*
X617174Y277951D01*
X617189Y277911D01*
X617199Y277871D01*
X617214Y277826D01*
X617219Y277786D01*
X617229Y277746D01*
X617234Y277701D01*
Y277661D01*
X617239Y277616D01*
X617234Y277571D01*
Y277531D01*
X617229Y277486D01*
X617219Y277446D01*
X617214Y277406D01*
X617199Y277361D01*
X617189Y277321D01*
X617174Y277281D01*
X617154Y277241D01*
X617139Y277206D01*
X617119Y277166D01*
X617019Y277026D01*
X616989Y276996D01*
Y275866D01*
X616979Y275741D01*
X616939Y275616D01*
X616879Y275506D01*
X616799Y275406D01*
X616699Y275326D01*
X616589Y275266D01*
X616464Y275226D01*
X616339Y275216D01*
X616214Y275226D01*
X616089Y275266D01*
X615979Y275326D01*
X615879Y275406D01*
X615799Y275506D01*
X615739Y275616D01*
X615699Y275741D01*
X615689Y275866D01*
Y276996D01*
X615659Y277026D01*
X615559Y277166D01*
X615539Y277206D01*
X615524Y277241D01*
X615504Y277281D01*
X615489Y277321D01*
X615479Y277361D01*
X615464Y277406D01*
X615459Y277446D01*
X615449Y277486D01*
X615444Y277531D01*
Y277571D01*
X615439Y277616D01*
X615444Y277661D01*
Y277701D01*
X615449Y277746D01*
X615459Y277786D01*
X615464Y277826D01*
X615479Y277871D01*
X615489Y277911D01*
X615504Y277951D01*
X615524Y277991D01*
X615539Y278026D01*
X615559Y278066D01*
X615659Y278206D01*
X615689Y278236D01*
Y281666D01*
X615699Y281791D01*
X615739Y281916D01*
X615799Y282026D01*
X615879Y282126D01*
X615979Y282206D01*
X616089Y282266D01*
X616214Y282306D01*
X616339Y282316D01*
G37*
G36*
G01X621063D02*
X621188Y282306D01*
X621313Y282266D01*
X621423Y282206D01*
X621523Y282126D01*
X621603Y282026D01*
X621663Y281916D01*
X621703Y281791D01*
X621713Y281666D01*
Y278236D01*
X621743Y278206D01*
X621843Y278066D01*
X621863Y278026D01*
X621878Y277991D01*
X621898Y277951D01*
X621913Y277911D01*
X621923Y277871D01*
X621938Y277826D01*
X621943Y277786D01*
X621953Y277746D01*
X621958Y277701D01*
Y277661D01*
X621963Y277616D01*
X621958Y277571D01*
Y277531D01*
X621953Y277486D01*
X621943Y277446D01*
X621938Y277406D01*
X621923Y277361D01*
X621913Y277321D01*
X621898Y277281D01*
X621878Y277241D01*
X621863Y277206D01*
X621843Y277166D01*
X621743Y277026D01*
X621713Y276996D01*
Y275866D01*
X621703Y275741D01*
X621663Y275616D01*
X621603Y275506D01*
X621523Y275406D01*
X621423Y275326D01*
X621313Y275266D01*
X621188Y275226D01*
X621063Y275216D01*
X620938Y275226D01*
X620813Y275266D01*
X620703Y275326D01*
X620603Y275406D01*
X620523Y275506D01*
X620463Y275616D01*
X620423Y275741D01*
X620413Y275866D01*
Y276996D01*
X620383Y277026D01*
X620283Y277166D01*
X620263Y277206D01*
X620248Y277241D01*
X620228Y277281D01*
X620213Y277321D01*
X620203Y277361D01*
X620188Y277406D01*
X620183Y277446D01*
X620173Y277486D01*
X620168Y277531D01*
Y277571D01*
X620163Y277616D01*
X620168Y277661D01*
Y277701D01*
X620173Y277746D01*
X620183Y277786D01*
X620188Y277826D01*
X620203Y277871D01*
X620213Y277911D01*
X620228Y277951D01*
X620248Y277991D01*
X620263Y278026D01*
X620283Y278066D01*
X620383Y278206D01*
X620413Y278236D01*
Y281666D01*
X620423Y281791D01*
X620463Y281916D01*
X620523Y282026D01*
X620603Y282126D01*
X620703Y282206D01*
X620813Y282266D01*
X620938Y282306D01*
X621063Y282316D01*
G37*
G36*
G01X625788D02*
X625913Y282306D01*
X626038Y282266D01*
X626148Y282206D01*
X626248Y282126D01*
X626328Y282026D01*
X626388Y281916D01*
X626428Y281791D01*
X626438Y281666D01*
Y278236D01*
X626468Y278206D01*
X626568Y278066D01*
X626588Y278026D01*
X626603Y277991D01*
X626623Y277951D01*
X626638Y277911D01*
X626648Y277871D01*
X626663Y277826D01*
X626668Y277786D01*
X626678Y277746D01*
X626683Y277701D01*
Y277661D01*
X626688Y277616D01*
X626683Y277571D01*
Y277531D01*
X626678Y277486D01*
X626668Y277446D01*
X626663Y277406D01*
X626648Y277361D01*
X626638Y277321D01*
X626623Y277281D01*
X626603Y277241D01*
X626588Y277206D01*
X626568Y277166D01*
X626468Y277026D01*
X626438Y276996D01*
Y275866D01*
X626428Y275741D01*
X626388Y275616D01*
X626328Y275506D01*
X626248Y275406D01*
X626148Y275326D01*
X626038Y275266D01*
X625913Y275226D01*
X625788Y275216D01*
X625663Y275226D01*
X625538Y275266D01*
X625428Y275326D01*
X625328Y275406D01*
X625248Y275506D01*
X625188Y275616D01*
X625148Y275741D01*
X625138Y275866D01*
Y276996D01*
X625108Y277026D01*
X625008Y277166D01*
X624988Y277206D01*
X624973Y277241D01*
X624953Y277281D01*
X624938Y277321D01*
X624928Y277361D01*
X624913Y277406D01*
X624908Y277446D01*
X624898Y277486D01*
X624893Y277531D01*
Y277571D01*
X624888Y277616D01*
X624893Y277661D01*
Y277701D01*
X624898Y277746D01*
X624908Y277786D01*
X624913Y277826D01*
X624928Y277871D01*
X624938Y277911D01*
X624953Y277951D01*
X624973Y277991D01*
X624988Y278026D01*
X625008Y278066D01*
X625108Y278206D01*
X625138Y278236D01*
Y281666D01*
X625148Y281791D01*
X625188Y281916D01*
X625248Y282026D01*
X625328Y282126D01*
X625428Y282206D01*
X625538Y282266D01*
X625663Y282306D01*
X625788Y282316D01*
G37*
G36*
G01X630512D02*
X630637Y282306D01*
X630762Y282266D01*
X630872Y282206D01*
X630972Y282126D01*
X631052Y282026D01*
X631112Y281916D01*
X631152Y281791D01*
X631162Y281666D01*
Y278236D01*
X631192Y278206D01*
X631292Y278066D01*
X631312Y278026D01*
X631327Y277991D01*
X631347Y277951D01*
X631362Y277911D01*
X631372Y277871D01*
X631387Y277826D01*
X631392Y277786D01*
X631402Y277746D01*
X631407Y277701D01*
Y277661D01*
X631412Y277616D01*
X631407Y277571D01*
Y277531D01*
X631402Y277486D01*
X631392Y277446D01*
X631387Y277406D01*
X631372Y277361D01*
X631362Y277321D01*
X631347Y277281D01*
X631327Y277241D01*
X631312Y277206D01*
X631292Y277166D01*
X631192Y277026D01*
X631162Y276996D01*
Y275866D01*
X631152Y275741D01*
X631112Y275616D01*
X631052Y275506D01*
X630972Y275406D01*
X630872Y275326D01*
X630762Y275266D01*
X630637Y275226D01*
X630512Y275216D01*
X630387Y275226D01*
X630262Y275266D01*
X630152Y275326D01*
X630052Y275406D01*
X629972Y275506D01*
X629912Y275616D01*
X629872Y275741D01*
X629862Y275866D01*
Y276996D01*
X629832Y277026D01*
X629732Y277166D01*
X629712Y277206D01*
X629697Y277241D01*
X629677Y277281D01*
X629662Y277321D01*
X629652Y277361D01*
X629637Y277406D01*
X629632Y277446D01*
X629622Y277486D01*
X629617Y277531D01*
Y277571D01*
X629612Y277616D01*
X629617Y277661D01*
Y277701D01*
X629622Y277746D01*
X629632Y277786D01*
X629637Y277826D01*
X629652Y277871D01*
X629662Y277911D01*
X629677Y277951D01*
X629697Y277991D01*
X629712Y278026D01*
X629732Y278066D01*
X629832Y278206D01*
X629862Y278236D01*
Y281666D01*
X629872Y281791D01*
X629912Y281916D01*
X629972Y282026D01*
X630052Y282126D01*
X630152Y282206D01*
X630262Y282266D01*
X630387Y282306D01*
X630512Y282316D01*
G37*
G36*
G01X635236D02*
X635361Y282306D01*
X635486Y282266D01*
X635596Y282206D01*
X635696Y282126D01*
X635776Y282026D01*
X635836Y281916D01*
X635876Y281791D01*
X635886Y281666D01*
Y278236D01*
X635916Y278206D01*
X636016Y278066D01*
X636036Y278026D01*
X636051Y277991D01*
X636071Y277951D01*
X636086Y277911D01*
X636096Y277871D01*
X636111Y277826D01*
X636116Y277786D01*
X636126Y277746D01*
X636131Y277701D01*
Y277661D01*
X636136Y277616D01*
X636131Y277571D01*
Y277531D01*
X636126Y277486D01*
X636116Y277446D01*
X636111Y277406D01*
X636096Y277361D01*
X636086Y277321D01*
X636071Y277281D01*
X636051Y277241D01*
X636036Y277206D01*
X636016Y277166D01*
X635916Y277026D01*
X635886Y276996D01*
Y275866D01*
X635876Y275741D01*
X635836Y275616D01*
X635776Y275506D01*
X635696Y275406D01*
X635596Y275326D01*
X635486Y275266D01*
X635361Y275226D01*
X635236Y275216D01*
X635111Y275226D01*
X634986Y275266D01*
X634876Y275326D01*
X634776Y275406D01*
X634696Y275506D01*
X634636Y275616D01*
X634596Y275741D01*
X634586Y275866D01*
Y276996D01*
X634556Y277026D01*
X634456Y277166D01*
X634436Y277206D01*
X634421Y277241D01*
X634401Y277281D01*
X634386Y277321D01*
X634376Y277361D01*
X634361Y277406D01*
X634356Y277446D01*
X634346Y277486D01*
X634341Y277531D01*
Y277571D01*
X634336Y277616D01*
X634341Y277661D01*
Y277701D01*
X634346Y277746D01*
X634356Y277786D01*
X634361Y277826D01*
X634376Y277871D01*
X634386Y277911D01*
X634401Y277951D01*
X634421Y277991D01*
X634436Y278026D01*
X634456Y278066D01*
X634556Y278206D01*
X634586Y278236D01*
Y281666D01*
X634596Y281791D01*
X634636Y281916D01*
X634696Y282026D01*
X634776Y282126D01*
X634876Y282206D01*
X634986Y282266D01*
X635111Y282306D01*
X635236Y282316D01*
G37*
G36*
G01X639961D02*
X640086Y282306D01*
X640211Y282266D01*
X640321Y282206D01*
X640421Y282126D01*
X640501Y282026D01*
X640561Y281916D01*
X640601Y281791D01*
X640611Y281666D01*
Y278236D01*
X640641Y278206D01*
X640741Y278066D01*
X640761Y278026D01*
X640776Y277991D01*
X640796Y277951D01*
X640811Y277911D01*
X640821Y277871D01*
X640836Y277826D01*
X640841Y277786D01*
X640851Y277746D01*
X640856Y277701D01*
Y277661D01*
X640861Y277616D01*
X640856Y277571D01*
Y277531D01*
X640851Y277486D01*
X640841Y277446D01*
X640836Y277406D01*
X640821Y277361D01*
X640811Y277321D01*
X640796Y277281D01*
X640776Y277241D01*
X640761Y277206D01*
X640741Y277166D01*
X640641Y277026D01*
X640611Y276996D01*
Y275866D01*
X640601Y275741D01*
X640561Y275616D01*
X640501Y275506D01*
X640421Y275406D01*
X640321Y275326D01*
X640211Y275266D01*
X640086Y275226D01*
X639961Y275216D01*
X639836Y275226D01*
X639711Y275266D01*
X639601Y275326D01*
X639501Y275406D01*
X639421Y275506D01*
X639361Y275616D01*
X639321Y275741D01*
X639311Y275866D01*
Y276996D01*
X639281Y277026D01*
X639181Y277166D01*
X639161Y277206D01*
X639146Y277241D01*
X639126Y277281D01*
X639111Y277321D01*
X639101Y277361D01*
X639086Y277406D01*
X639081Y277446D01*
X639071Y277486D01*
X639066Y277531D01*
Y277571D01*
X639061Y277616D01*
X639066Y277661D01*
Y277701D01*
X639071Y277746D01*
X639081Y277786D01*
X639086Y277826D01*
X639101Y277871D01*
X639111Y277911D01*
X639126Y277951D01*
X639146Y277991D01*
X639161Y278026D01*
X639181Y278066D01*
X639281Y278206D01*
X639311Y278236D01*
Y281666D01*
X639321Y281791D01*
X639361Y281916D01*
X639421Y282026D01*
X639501Y282126D01*
X639601Y282206D01*
X639711Y282266D01*
X639836Y282306D01*
X639961Y282316D01*
G37*
G36*
G01X644685D02*
X644810Y282306D01*
X644935Y282266D01*
X645045Y282206D01*
X645145Y282126D01*
X645225Y282026D01*
X645285Y281916D01*
X645325Y281791D01*
X645335Y281666D01*
Y278236D01*
X645365Y278206D01*
X645465Y278066D01*
X645485Y278026D01*
X645500Y277991D01*
X645520Y277951D01*
X645535Y277911D01*
X645545Y277871D01*
X645560Y277826D01*
X645565Y277786D01*
X645575Y277746D01*
X645580Y277701D01*
Y277661D01*
X645585Y277616D01*
X645580Y277571D01*
Y277531D01*
X645575Y277486D01*
X645565Y277446D01*
X645560Y277406D01*
X645545Y277361D01*
X645535Y277321D01*
X645520Y277281D01*
X645500Y277241D01*
X645485Y277206D01*
X645465Y277166D01*
X645365Y277026D01*
X645335Y276996D01*
Y275866D01*
X645325Y275741D01*
X645285Y275616D01*
X645225Y275506D01*
X645145Y275406D01*
X645045Y275326D01*
X644935Y275266D01*
X644810Y275226D01*
X644685Y275216D01*
X644560Y275226D01*
X644435Y275266D01*
X644325Y275326D01*
X644225Y275406D01*
X644145Y275506D01*
X644085Y275616D01*
X644045Y275741D01*
X644035Y275866D01*
Y276996D01*
X644005Y277026D01*
X643905Y277166D01*
X643885Y277206D01*
X643870Y277241D01*
X643850Y277281D01*
X643835Y277321D01*
X643825Y277361D01*
X643810Y277406D01*
X643805Y277446D01*
X643795Y277486D01*
X643790Y277531D01*
Y277571D01*
X643785Y277616D01*
X643790Y277661D01*
Y277701D01*
X643795Y277746D01*
X643805Y277786D01*
X643810Y277826D01*
X643825Y277871D01*
X643835Y277911D01*
X643850Y277951D01*
X643870Y277991D01*
X643885Y278026D01*
X643905Y278066D01*
X644005Y278206D01*
X644035Y278236D01*
Y281666D01*
X644045Y281791D01*
X644085Y281916D01*
X644145Y282026D01*
X644225Y282126D01*
X644325Y282206D01*
X644435Y282266D01*
X644560Y282306D01*
X644685Y282316D01*
G37*
G36*
G01X649410D02*
X649535Y282306D01*
X649660Y282266D01*
X649770Y282206D01*
X649870Y282126D01*
X649950Y282026D01*
X650010Y281916D01*
X650050Y281791D01*
X650060Y281666D01*
Y278236D01*
X650090Y278206D01*
X650190Y278066D01*
X650210Y278026D01*
X650225Y277991D01*
X650245Y277951D01*
X650260Y277911D01*
X650270Y277871D01*
X650285Y277826D01*
X650290Y277786D01*
X650300Y277746D01*
X650305Y277701D01*
Y277661D01*
X650310Y277616D01*
X650305Y277571D01*
Y277531D01*
X650300Y277486D01*
X650290Y277446D01*
X650285Y277406D01*
X650270Y277361D01*
X650260Y277321D01*
X650245Y277281D01*
X650225Y277241D01*
X650210Y277206D01*
X650190Y277166D01*
X650090Y277026D01*
X650060Y276996D01*
Y275866D01*
X650050Y275741D01*
X650010Y275616D01*
X649950Y275506D01*
X649870Y275406D01*
X649770Y275326D01*
X649660Y275266D01*
X649535Y275226D01*
X649410Y275216D01*
X649285Y275226D01*
X649160Y275266D01*
X649050Y275326D01*
X648950Y275406D01*
X648870Y275506D01*
X648810Y275616D01*
X648770Y275741D01*
X648760Y275866D01*
Y276996D01*
X648730Y277026D01*
X648630Y277166D01*
X648610Y277206D01*
X648595Y277241D01*
X648575Y277281D01*
X648560Y277321D01*
X648550Y277361D01*
X648535Y277406D01*
X648530Y277446D01*
X648520Y277486D01*
X648515Y277531D01*
Y277571D01*
X648510Y277616D01*
X648515Y277661D01*
Y277701D01*
X648520Y277746D01*
X648530Y277786D01*
X648535Y277826D01*
X648550Y277871D01*
X648560Y277911D01*
X648575Y277951D01*
X648595Y277991D01*
X648610Y278026D01*
X648630Y278066D01*
X648730Y278206D01*
X648760Y278236D01*
Y281666D01*
X648770Y281791D01*
X648810Y281916D01*
X648870Y282026D01*
X648950Y282126D01*
X649050Y282206D01*
X649160Y282266D01*
X649285Y282306D01*
X649410Y282316D01*
G37*
G36*
G01X654134D02*
X654259Y282306D01*
X654384Y282266D01*
X654494Y282206D01*
X654594Y282126D01*
X654674Y282026D01*
X654734Y281916D01*
X654774Y281791D01*
X654784Y281666D01*
Y278236D01*
X654814Y278206D01*
X654914Y278066D01*
X654934Y278026D01*
X654949Y277991D01*
X654969Y277951D01*
X654984Y277911D01*
X654994Y277871D01*
X655009Y277826D01*
X655014Y277786D01*
X655024Y277746D01*
X655029Y277701D01*
Y277661D01*
X655034Y277616D01*
X655029Y277571D01*
Y277531D01*
X655024Y277486D01*
X655014Y277446D01*
X655009Y277406D01*
X654994Y277361D01*
X654984Y277321D01*
X654969Y277281D01*
X654949Y277241D01*
X654934Y277206D01*
X654914Y277166D01*
X654814Y277026D01*
X654784Y276996D01*
Y275866D01*
X654774Y275741D01*
X654734Y275616D01*
X654674Y275506D01*
X654594Y275406D01*
X654494Y275326D01*
X654384Y275266D01*
X654259Y275226D01*
X654134Y275216D01*
X654009Y275226D01*
X653884Y275266D01*
X653774Y275326D01*
X653674Y275406D01*
X653594Y275506D01*
X653534Y275616D01*
X653494Y275741D01*
X653484Y275866D01*
Y276996D01*
X653454Y277026D01*
X653354Y277166D01*
X653334Y277206D01*
X653319Y277241D01*
X653299Y277281D01*
X653284Y277321D01*
X653274Y277361D01*
X653259Y277406D01*
X653254Y277446D01*
X653244Y277486D01*
X653239Y277531D01*
Y277571D01*
X653234Y277616D01*
X653239Y277661D01*
Y277701D01*
X653244Y277746D01*
X653254Y277786D01*
X653259Y277826D01*
X653274Y277871D01*
X653284Y277911D01*
X653299Y277951D01*
X653319Y277991D01*
X653334Y278026D01*
X653354Y278066D01*
X653454Y278206D01*
X653484Y278236D01*
Y281666D01*
X653494Y281791D01*
X653534Y281916D01*
X653594Y282026D01*
X653674Y282126D01*
X653774Y282206D01*
X653884Y282266D01*
X654009Y282306D01*
X654134Y282316D01*
G37*
G36*
G01X668307D02*
X668432Y282306D01*
X668557Y282266D01*
X668667Y282206D01*
X668767Y282126D01*
X668847Y282026D01*
X668907Y281916D01*
X668947Y281791D01*
X668957Y281666D01*
Y278236D01*
X668987Y278206D01*
X669087Y278066D01*
X669107Y278026D01*
X669122Y277991D01*
X669142Y277951D01*
X669157Y277911D01*
X669167Y277871D01*
X669182Y277826D01*
X669187Y277786D01*
X669197Y277746D01*
X669202Y277701D01*
Y277661D01*
X669207Y277616D01*
X669202Y277571D01*
Y277531D01*
X669197Y277486D01*
X669187Y277446D01*
X669182Y277406D01*
X669167Y277361D01*
X669157Y277321D01*
X669142Y277281D01*
X669122Y277241D01*
X669107Y277206D01*
X669087Y277166D01*
X668987Y277026D01*
X668957Y276996D01*
Y275866D01*
X668947Y275741D01*
X668907Y275616D01*
X668847Y275506D01*
X668767Y275406D01*
X668667Y275326D01*
X668557Y275266D01*
X668432Y275226D01*
X668307Y275216D01*
X668182Y275226D01*
X668057Y275266D01*
X667947Y275326D01*
X667847Y275406D01*
X667767Y275506D01*
X667707Y275616D01*
X667667Y275741D01*
X667657Y275866D01*
Y276996D01*
X667627Y277026D01*
X667527Y277166D01*
X667507Y277206D01*
X667492Y277241D01*
X667472Y277281D01*
X667457Y277321D01*
X667447Y277361D01*
X667432Y277406D01*
X667427Y277446D01*
X667417Y277486D01*
X667412Y277531D01*
Y277571D01*
X667407Y277616D01*
X667412Y277661D01*
Y277701D01*
X667417Y277746D01*
X667427Y277786D01*
X667432Y277826D01*
X667447Y277871D01*
X667457Y277911D01*
X667472Y277951D01*
X667492Y277991D01*
X667507Y278026D01*
X667527Y278066D01*
X667627Y278206D01*
X667657Y278236D01*
Y281666D01*
X667667Y281791D01*
X667707Y281916D01*
X667767Y282026D01*
X667847Y282126D01*
X667947Y282206D01*
X668057Y282266D01*
X668182Y282306D01*
X668307Y282316D01*
G37*
G36*
G01X673032D02*
X673157Y282306D01*
X673282Y282266D01*
X673392Y282206D01*
X673492Y282126D01*
X673572Y282026D01*
X673632Y281916D01*
X673672Y281791D01*
X673682Y281666D01*
Y278236D01*
X673712Y278206D01*
X673812Y278066D01*
X673832Y278026D01*
X673847Y277991D01*
X673867Y277951D01*
X673882Y277911D01*
X673892Y277871D01*
X673907Y277826D01*
X673912Y277786D01*
X673922Y277746D01*
X673927Y277701D01*
Y277661D01*
X673932Y277616D01*
X673927Y277571D01*
Y277531D01*
X673922Y277486D01*
X673912Y277446D01*
X673907Y277406D01*
X673892Y277361D01*
X673882Y277321D01*
X673867Y277281D01*
X673847Y277241D01*
X673832Y277206D01*
X673812Y277166D01*
X673712Y277026D01*
X673682Y276996D01*
Y275866D01*
X673672Y275741D01*
X673632Y275616D01*
X673572Y275506D01*
X673492Y275406D01*
X673392Y275326D01*
X673282Y275266D01*
X673157Y275226D01*
X673032Y275216D01*
X672907Y275226D01*
X672782Y275266D01*
X672672Y275326D01*
X672572Y275406D01*
X672492Y275506D01*
X672432Y275616D01*
X672392Y275741D01*
X672382Y275866D01*
Y276996D01*
X672352Y277026D01*
X672252Y277166D01*
X672232Y277206D01*
X672217Y277241D01*
X672197Y277281D01*
X672182Y277321D01*
X672172Y277361D01*
X672157Y277406D01*
X672152Y277446D01*
X672142Y277486D01*
X672137Y277531D01*
Y277571D01*
X672132Y277616D01*
X672137Y277661D01*
Y277701D01*
X672142Y277746D01*
X672152Y277786D01*
X672157Y277826D01*
X672172Y277871D01*
X672182Y277911D01*
X672197Y277951D01*
X672217Y277991D01*
X672232Y278026D01*
X672252Y278066D01*
X672352Y278206D01*
X672382Y278236D01*
Y281666D01*
X672392Y281791D01*
X672432Y281916D01*
X672492Y282026D01*
X672572Y282126D01*
X672672Y282206D01*
X672782Y282266D01*
X672907Y282306D01*
X673032Y282316D01*
G37*
G36*
G01X677756D02*
X677881Y282306D01*
X678006Y282266D01*
X678116Y282206D01*
X678216Y282126D01*
X678296Y282026D01*
X678356Y281916D01*
X678396Y281791D01*
X678406Y281666D01*
Y278236D01*
X678436Y278206D01*
X678536Y278066D01*
X678556Y278026D01*
X678571Y277991D01*
X678591Y277951D01*
X678606Y277911D01*
X678616Y277871D01*
X678631Y277826D01*
X678636Y277786D01*
X678646Y277746D01*
X678651Y277701D01*
Y277661D01*
X678656Y277616D01*
X678651Y277571D01*
Y277531D01*
X678646Y277486D01*
X678636Y277446D01*
X678631Y277406D01*
X678616Y277361D01*
X678606Y277321D01*
X678591Y277281D01*
X678571Y277241D01*
X678556Y277206D01*
X678536Y277166D01*
X678436Y277026D01*
X678406Y276996D01*
Y275866D01*
X678396Y275741D01*
X678356Y275616D01*
X678296Y275506D01*
X678216Y275406D01*
X678116Y275326D01*
X678006Y275266D01*
X677881Y275226D01*
X677756Y275216D01*
X677631Y275226D01*
X677506Y275266D01*
X677396Y275326D01*
X677296Y275406D01*
X677216Y275506D01*
X677156Y275616D01*
X677116Y275741D01*
X677106Y275866D01*
Y276996D01*
X677076Y277026D01*
X676976Y277166D01*
X676956Y277206D01*
X676941Y277241D01*
X676921Y277281D01*
X676906Y277321D01*
X676896Y277361D01*
X676881Y277406D01*
X676876Y277446D01*
X676866Y277486D01*
X676861Y277531D01*
Y277571D01*
X676856Y277616D01*
X676861Y277661D01*
Y277701D01*
X676866Y277746D01*
X676876Y277786D01*
X676881Y277826D01*
X676896Y277871D01*
X676906Y277911D01*
X676921Y277951D01*
X676941Y277991D01*
X676956Y278026D01*
X676976Y278066D01*
X677076Y278206D01*
X677106Y278236D01*
Y281666D01*
X677116Y281791D01*
X677156Y281916D01*
X677216Y282026D01*
X677296Y282126D01*
X677396Y282206D01*
X677506Y282266D01*
X677631Y282306D01*
X677756Y282316D01*
G37*
G36*
G01X682481D02*
X682606Y282306D01*
X682731Y282266D01*
X682841Y282206D01*
X682941Y282126D01*
X683021Y282026D01*
X683081Y281916D01*
X683121Y281791D01*
X683131Y281666D01*
Y278236D01*
X683161Y278206D01*
X683261Y278066D01*
X683281Y278026D01*
X683296Y277991D01*
X683316Y277951D01*
X683331Y277911D01*
X683341Y277871D01*
X683356Y277826D01*
X683361Y277786D01*
X683371Y277746D01*
X683376Y277701D01*
Y277661D01*
X683381Y277616D01*
X683376Y277571D01*
Y277531D01*
X683371Y277486D01*
X683361Y277446D01*
X683356Y277406D01*
X683341Y277361D01*
X683331Y277321D01*
X683316Y277281D01*
X683296Y277241D01*
X683281Y277206D01*
X683261Y277166D01*
X683161Y277026D01*
X683131Y276996D01*
Y275866D01*
X683121Y275741D01*
X683081Y275616D01*
X683021Y275506D01*
X682941Y275406D01*
X682841Y275326D01*
X682731Y275266D01*
X682606Y275226D01*
X682481Y275216D01*
X682356Y275226D01*
X682231Y275266D01*
X682121Y275326D01*
X682021Y275406D01*
X681941Y275506D01*
X681881Y275616D01*
X681841Y275741D01*
X681831Y275866D01*
Y276996D01*
X681801Y277026D01*
X681701Y277166D01*
X681681Y277206D01*
X681666Y277241D01*
X681646Y277281D01*
X681631Y277321D01*
X681621Y277361D01*
X681606Y277406D01*
X681601Y277446D01*
X681591Y277486D01*
X681586Y277531D01*
Y277571D01*
X681581Y277616D01*
X681586Y277661D01*
Y277701D01*
X681591Y277746D01*
X681601Y277786D01*
X681606Y277826D01*
X681621Y277871D01*
X681631Y277911D01*
X681646Y277951D01*
X681666Y277991D01*
X681681Y278026D01*
X681701Y278066D01*
X681801Y278206D01*
X681831Y278236D01*
Y281666D01*
X681841Y281791D01*
X681881Y281916D01*
X681941Y282026D01*
X682021Y282126D01*
X682121Y282206D01*
X682231Y282266D01*
X682356Y282306D01*
X682481Y282316D01*
G37*
G36*
G01X687205D02*
X687330Y282306D01*
X687455Y282266D01*
X687565Y282206D01*
X687665Y282126D01*
X687745Y282026D01*
X687805Y281916D01*
X687845Y281791D01*
X687855Y281666D01*
Y278236D01*
X687885Y278206D01*
X687985Y278066D01*
X688005Y278026D01*
X688020Y277991D01*
X688040Y277951D01*
X688055Y277911D01*
X688065Y277871D01*
X688080Y277826D01*
X688085Y277786D01*
X688095Y277746D01*
X688100Y277701D01*
Y277661D01*
X688105Y277616D01*
X688100Y277571D01*
Y277531D01*
X688095Y277486D01*
X688085Y277446D01*
X688080Y277406D01*
X688065Y277361D01*
X688055Y277321D01*
X688040Y277281D01*
X688020Y277241D01*
X688005Y277206D01*
X687985Y277166D01*
X687885Y277026D01*
X687855Y276996D01*
Y275866D01*
X687845Y275741D01*
X687805Y275616D01*
X687745Y275506D01*
X687665Y275406D01*
X687565Y275326D01*
X687455Y275266D01*
X687330Y275226D01*
X687205Y275216D01*
X687080Y275226D01*
X686955Y275266D01*
X686845Y275326D01*
X686745Y275406D01*
X686665Y275506D01*
X686605Y275616D01*
X686565Y275741D01*
X686555Y275866D01*
Y276996D01*
X686525Y277026D01*
X686425Y277166D01*
X686405Y277206D01*
X686390Y277241D01*
X686370Y277281D01*
X686355Y277321D01*
X686345Y277361D01*
X686330Y277406D01*
X686325Y277446D01*
X686315Y277486D01*
X686310Y277531D01*
Y277571D01*
X686305Y277616D01*
X686310Y277661D01*
Y277701D01*
X686315Y277746D01*
X686325Y277786D01*
X686330Y277826D01*
X686345Y277871D01*
X686355Y277911D01*
X686370Y277951D01*
X686390Y277991D01*
X686405Y278026D01*
X686425Y278066D01*
X686525Y278206D01*
X686555Y278236D01*
Y281666D01*
X686565Y281791D01*
X686605Y281916D01*
X686665Y282026D01*
X686745Y282126D01*
X686845Y282206D01*
X686955Y282266D01*
X687080Y282306D01*
X687205Y282316D01*
G37*
G36*
G01X691929D02*
X692054Y282306D01*
X692179Y282266D01*
X692289Y282206D01*
X692389Y282126D01*
X692469Y282026D01*
X692529Y281916D01*
X692569Y281791D01*
X692579Y281666D01*
Y278236D01*
X692609Y278206D01*
X692709Y278066D01*
X692729Y278026D01*
X692744Y277991D01*
X692764Y277951D01*
X692779Y277911D01*
X692789Y277871D01*
X692804Y277826D01*
X692809Y277786D01*
X692819Y277746D01*
X692824Y277701D01*
Y277661D01*
X692829Y277616D01*
X692824Y277571D01*
Y277531D01*
X692819Y277486D01*
X692809Y277446D01*
X692804Y277406D01*
X692789Y277361D01*
X692779Y277321D01*
X692764Y277281D01*
X692744Y277241D01*
X692729Y277206D01*
X692709Y277166D01*
X692609Y277026D01*
X692579Y276996D01*
Y275866D01*
X692569Y275741D01*
X692529Y275616D01*
X692469Y275506D01*
X692389Y275406D01*
X692289Y275326D01*
X692179Y275266D01*
X692054Y275226D01*
X691929Y275216D01*
X691804Y275226D01*
X691679Y275266D01*
X691569Y275326D01*
X691469Y275406D01*
X691389Y275506D01*
X691329Y275616D01*
X691289Y275741D01*
X691279Y275866D01*
Y276996D01*
X691249Y277026D01*
X691149Y277166D01*
X691129Y277206D01*
X691114Y277241D01*
X691094Y277281D01*
X691079Y277321D01*
X691069Y277361D01*
X691054Y277406D01*
X691049Y277446D01*
X691039Y277486D01*
X691034Y277531D01*
Y277571D01*
X691029Y277616D01*
X691034Y277661D01*
Y277701D01*
X691039Y277746D01*
X691049Y277786D01*
X691054Y277826D01*
X691069Y277871D01*
X691079Y277911D01*
X691094Y277951D01*
X691114Y277991D01*
X691129Y278026D01*
X691149Y278066D01*
X691249Y278206D01*
X691279Y278236D01*
Y281666D01*
X691289Y281791D01*
X691329Y281916D01*
X691389Y282026D01*
X691469Y282126D01*
X691569Y282206D01*
X691679Y282266D01*
X691804Y282306D01*
X691929Y282316D01*
G37*
G36*
G01X696654D02*
X696779Y282306D01*
X696904Y282266D01*
X697014Y282206D01*
X697114Y282126D01*
X697194Y282026D01*
X697254Y281916D01*
X697294Y281791D01*
X697304Y281666D01*
Y278236D01*
X697334Y278206D01*
X697434Y278066D01*
X697454Y278026D01*
X697469Y277991D01*
X697489Y277951D01*
X697504Y277911D01*
X697514Y277871D01*
X697529Y277826D01*
X697534Y277786D01*
X697544Y277746D01*
X697549Y277701D01*
Y277661D01*
X697554Y277616D01*
X697549Y277571D01*
Y277531D01*
X697544Y277486D01*
X697534Y277446D01*
X697529Y277406D01*
X697514Y277361D01*
X697504Y277321D01*
X697489Y277281D01*
X697469Y277241D01*
X697454Y277206D01*
X697434Y277166D01*
X697334Y277026D01*
X697304Y276996D01*
Y275866D01*
X697294Y275741D01*
X697254Y275616D01*
X697194Y275506D01*
X697114Y275406D01*
X697014Y275326D01*
X696904Y275266D01*
X696779Y275226D01*
X696654Y275216D01*
X696529Y275226D01*
X696404Y275266D01*
X696294Y275326D01*
X696194Y275406D01*
X696114Y275506D01*
X696054Y275616D01*
X696014Y275741D01*
X696004Y275866D01*
Y276996D01*
X695974Y277026D01*
X695874Y277166D01*
X695854Y277206D01*
X695839Y277241D01*
X695819Y277281D01*
X695804Y277321D01*
X695794Y277361D01*
X695779Y277406D01*
X695774Y277446D01*
X695764Y277486D01*
X695759Y277531D01*
Y277571D01*
X695754Y277616D01*
X695759Y277661D01*
Y277701D01*
X695764Y277746D01*
X695774Y277786D01*
X695779Y277826D01*
X695794Y277871D01*
X695804Y277911D01*
X695819Y277951D01*
X695839Y277991D01*
X695854Y278026D01*
X695874Y278066D01*
X695974Y278206D01*
X696004Y278236D01*
Y281666D01*
X696014Y281791D01*
X696054Y281916D01*
X696114Y282026D01*
X696194Y282126D01*
X696294Y282206D01*
X696404Y282266D01*
X696529Y282306D01*
X696654Y282316D01*
G37*
G36*
G01X701378D02*
X701503Y282306D01*
X701628Y282266D01*
X701738Y282206D01*
X701838Y282126D01*
X701918Y282026D01*
X701978Y281916D01*
X702018Y281791D01*
X702028Y281666D01*
Y278236D01*
X702058Y278206D01*
X702158Y278066D01*
X702178Y278026D01*
X702193Y277991D01*
X702213Y277951D01*
X702228Y277911D01*
X702238Y277871D01*
X702253Y277826D01*
X702258Y277786D01*
X702268Y277746D01*
X702273Y277701D01*
Y277661D01*
X702278Y277616D01*
X702273Y277571D01*
Y277531D01*
X702268Y277486D01*
X702258Y277446D01*
X702253Y277406D01*
X702238Y277361D01*
X702228Y277321D01*
X702213Y277281D01*
X702193Y277241D01*
X702178Y277206D01*
X702158Y277166D01*
X702058Y277026D01*
X702028Y276996D01*
Y275866D01*
X702018Y275741D01*
X701978Y275616D01*
X701918Y275506D01*
X701838Y275406D01*
X701738Y275326D01*
X701628Y275266D01*
X701503Y275226D01*
X701378Y275216D01*
X701253Y275226D01*
X701128Y275266D01*
X701018Y275326D01*
X700918Y275406D01*
X700838Y275506D01*
X700778Y275616D01*
X700738Y275741D01*
X700728Y275866D01*
Y276996D01*
X700698Y277026D01*
X700598Y277166D01*
X700578Y277206D01*
X700563Y277241D01*
X700543Y277281D01*
X700528Y277321D01*
X700518Y277361D01*
X700503Y277406D01*
X700498Y277446D01*
X700488Y277486D01*
X700483Y277531D01*
Y277571D01*
X700478Y277616D01*
X700483Y277661D01*
Y277701D01*
X700488Y277746D01*
X700498Y277786D01*
X700503Y277826D01*
X700518Y277871D01*
X700528Y277911D01*
X700543Y277951D01*
X700563Y277991D01*
X700578Y278026D01*
X700598Y278066D01*
X700698Y278206D01*
X700728Y278236D01*
Y281666D01*
X700738Y281791D01*
X700778Y281916D01*
X700838Y282026D01*
X700918Y282126D01*
X701018Y282206D01*
X701128Y282266D01*
X701253Y282306D01*
X701378Y282316D01*
G37*
G36*
G01X706103D02*
X706228Y282306D01*
X706353Y282266D01*
X706463Y282206D01*
X706563Y282126D01*
X706643Y282026D01*
X706703Y281916D01*
X706743Y281791D01*
X706753Y281666D01*
Y278236D01*
X706783Y278206D01*
X706883Y278066D01*
X706903Y278026D01*
X706918Y277991D01*
X706938Y277951D01*
X706953Y277911D01*
X706963Y277871D01*
X706978Y277826D01*
X706983Y277786D01*
X706993Y277746D01*
X706998Y277701D01*
Y277661D01*
X707003Y277616D01*
X706998Y277571D01*
Y277531D01*
X706993Y277486D01*
X706983Y277446D01*
X706978Y277406D01*
X706963Y277361D01*
X706953Y277321D01*
X706938Y277281D01*
X706918Y277241D01*
X706903Y277206D01*
X706883Y277166D01*
X706783Y277026D01*
X706753Y276996D01*
Y275866D01*
X706743Y275741D01*
X706703Y275616D01*
X706643Y275506D01*
X706563Y275406D01*
X706463Y275326D01*
X706353Y275266D01*
X706228Y275226D01*
X706103Y275216D01*
X705978Y275226D01*
X705853Y275266D01*
X705743Y275326D01*
X705643Y275406D01*
X705563Y275506D01*
X705503Y275616D01*
X705463Y275741D01*
X705453Y275866D01*
Y276996D01*
X705423Y277026D01*
X705323Y277166D01*
X705303Y277206D01*
X705288Y277241D01*
X705268Y277281D01*
X705253Y277321D01*
X705243Y277361D01*
X705228Y277406D01*
X705223Y277446D01*
X705213Y277486D01*
X705208Y277531D01*
Y277571D01*
X705203Y277616D01*
X705208Y277661D01*
Y277701D01*
X705213Y277746D01*
X705223Y277786D01*
X705228Y277826D01*
X705243Y277871D01*
X705253Y277911D01*
X705268Y277951D01*
X705288Y277991D01*
X705303Y278026D01*
X705323Y278066D01*
X705423Y278206D01*
X705453Y278236D01*
Y281666D01*
X705463Y281791D01*
X705503Y281916D01*
X705563Y282026D01*
X705643Y282126D01*
X705743Y282206D01*
X705853Y282266D01*
X705978Y282306D01*
X706103Y282316D01*
G37*
G36*
G01X710827D02*
X710952Y282306D01*
X711077Y282266D01*
X711187Y282206D01*
X711287Y282126D01*
X711367Y282026D01*
X711427Y281916D01*
X711467Y281791D01*
X711477Y281666D01*
Y278236D01*
X711507Y278206D01*
X711607Y278066D01*
X711627Y278026D01*
X711642Y277991D01*
X711662Y277951D01*
X711677Y277911D01*
X711687Y277871D01*
X711702Y277826D01*
X711707Y277786D01*
X711717Y277746D01*
X711722Y277701D01*
Y277661D01*
X711727Y277616D01*
X711722Y277571D01*
Y277531D01*
X711717Y277486D01*
X711707Y277446D01*
X711702Y277406D01*
X711687Y277361D01*
X711677Y277321D01*
X711662Y277281D01*
X711642Y277241D01*
X711627Y277206D01*
X711607Y277166D01*
X711507Y277026D01*
X711477Y276996D01*
Y275866D01*
X711467Y275741D01*
X711427Y275616D01*
X711367Y275506D01*
X711287Y275406D01*
X711187Y275326D01*
X711077Y275266D01*
X710952Y275226D01*
X710827Y275216D01*
X710702Y275226D01*
X710577Y275266D01*
X710467Y275326D01*
X710367Y275406D01*
X710287Y275506D01*
X710227Y275616D01*
X710187Y275741D01*
X710177Y275866D01*
Y276996D01*
X710147Y277026D01*
X710047Y277166D01*
X710027Y277206D01*
X710012Y277241D01*
X709992Y277281D01*
X709977Y277321D01*
X709967Y277361D01*
X709952Y277406D01*
X709947Y277446D01*
X709937Y277486D01*
X709932Y277531D01*
Y277571D01*
X709927Y277616D01*
X709932Y277661D01*
Y277701D01*
X709937Y277746D01*
X709947Y277786D01*
X709952Y277826D01*
X709967Y277871D01*
X709977Y277911D01*
X709992Y277951D01*
X710012Y277991D01*
X710027Y278026D01*
X710047Y278066D01*
X710147Y278206D01*
X710177Y278236D01*
Y281666D01*
X710187Y281791D01*
X710227Y281916D01*
X710287Y282026D01*
X710367Y282126D01*
X710467Y282206D01*
X710577Y282266D01*
X710702Y282306D01*
X710827Y282316D01*
G37*
G36*
G01X715551D02*
X715676Y282306D01*
X715801Y282266D01*
X715911Y282206D01*
X716011Y282126D01*
X716091Y282026D01*
X716151Y281916D01*
X716191Y281791D01*
X716201Y281666D01*
Y278236D01*
X716231Y278206D01*
X716331Y278066D01*
X716351Y278026D01*
X716366Y277991D01*
X716386Y277951D01*
X716401Y277911D01*
X716411Y277871D01*
X716426Y277826D01*
X716431Y277786D01*
X716441Y277746D01*
X716446Y277701D01*
Y277661D01*
X716451Y277616D01*
X716446Y277571D01*
Y277531D01*
X716441Y277486D01*
X716431Y277446D01*
X716426Y277406D01*
X716411Y277361D01*
X716401Y277321D01*
X716386Y277281D01*
X716366Y277241D01*
X716351Y277206D01*
X716331Y277166D01*
X716231Y277026D01*
X716201Y276996D01*
Y275866D01*
X716191Y275741D01*
X716151Y275616D01*
X716091Y275506D01*
X716011Y275406D01*
X715911Y275326D01*
X715801Y275266D01*
X715676Y275226D01*
X715551Y275216D01*
X715426Y275226D01*
X715301Y275266D01*
X715191Y275326D01*
X715091Y275406D01*
X715011Y275506D01*
X714951Y275616D01*
X714911Y275741D01*
X714901Y275866D01*
Y276996D01*
X714871Y277026D01*
X714771Y277166D01*
X714751Y277206D01*
X714736Y277241D01*
X714716Y277281D01*
X714701Y277321D01*
X714691Y277361D01*
X714676Y277406D01*
X714671Y277446D01*
X714661Y277486D01*
X714656Y277531D01*
Y277571D01*
X714651Y277616D01*
X714656Y277661D01*
Y277701D01*
X714661Y277746D01*
X714671Y277786D01*
X714676Y277826D01*
X714691Y277871D01*
X714701Y277911D01*
X714716Y277951D01*
X714736Y277991D01*
X714751Y278026D01*
X714771Y278066D01*
X714871Y278206D01*
X714901Y278236D01*
Y281666D01*
X714911Y281791D01*
X714951Y281916D01*
X715011Y282026D01*
X715091Y282126D01*
X715191Y282206D01*
X715301Y282266D01*
X715426Y282306D01*
X715551Y282316D01*
G37*
G36*
G01X720276D02*
X720401Y282306D01*
X720526Y282266D01*
X720636Y282206D01*
X720736Y282126D01*
X720816Y282026D01*
X720876Y281916D01*
X720916Y281791D01*
X720926Y281666D01*
Y278236D01*
X720956Y278206D01*
X721056Y278066D01*
X721076Y278026D01*
X721091Y277991D01*
X721111Y277951D01*
X721126Y277911D01*
X721136Y277871D01*
X721151Y277826D01*
X721156Y277786D01*
X721166Y277746D01*
X721171Y277701D01*
Y277661D01*
X721176Y277616D01*
X721171Y277571D01*
Y277531D01*
X721166Y277486D01*
X721156Y277446D01*
X721151Y277406D01*
X721136Y277361D01*
X721126Y277321D01*
X721111Y277281D01*
X721091Y277241D01*
X721076Y277206D01*
X721056Y277166D01*
X720956Y277026D01*
X720926Y276996D01*
Y275866D01*
X720916Y275741D01*
X720876Y275616D01*
X720816Y275506D01*
X720736Y275406D01*
X720636Y275326D01*
X720526Y275266D01*
X720401Y275226D01*
X720276Y275216D01*
X720151Y275226D01*
X720026Y275266D01*
X719916Y275326D01*
X719816Y275406D01*
X719736Y275506D01*
X719676Y275616D01*
X719636Y275741D01*
X719626Y275866D01*
Y276996D01*
X719596Y277026D01*
X719496Y277166D01*
X719476Y277206D01*
X719461Y277241D01*
X719441Y277281D01*
X719426Y277321D01*
X719416Y277361D01*
X719401Y277406D01*
X719396Y277446D01*
X719386Y277486D01*
X719381Y277531D01*
Y277571D01*
X719376Y277616D01*
X719381Y277661D01*
Y277701D01*
X719386Y277746D01*
X719396Y277786D01*
X719401Y277826D01*
X719416Y277871D01*
X719426Y277911D01*
X719441Y277951D01*
X719461Y277991D01*
X719476Y278026D01*
X719496Y278066D01*
X719596Y278206D01*
X719626Y278236D01*
Y281666D01*
X719636Y281791D01*
X719676Y281916D01*
X719736Y282026D01*
X719816Y282126D01*
X719916Y282206D01*
X720026Y282266D01*
X720151Y282306D01*
X720276Y282316D01*
G37*
G36*
G01X725000D02*
X725125Y282306D01*
X725250Y282266D01*
X725360Y282206D01*
X725460Y282126D01*
X725540Y282026D01*
X725600Y281916D01*
X725640Y281791D01*
X725650Y281666D01*
Y278236D01*
X725680Y278206D01*
X725780Y278066D01*
X725800Y278026D01*
X725815Y277991D01*
X725835Y277951D01*
X725850Y277911D01*
X725860Y277871D01*
X725875Y277826D01*
X725880Y277786D01*
X725890Y277746D01*
X725895Y277701D01*
Y277661D01*
X725900Y277616D01*
X725895Y277571D01*
Y277531D01*
X725890Y277486D01*
X725880Y277446D01*
X725875Y277406D01*
X725860Y277361D01*
X725850Y277321D01*
X725835Y277281D01*
X725815Y277241D01*
X725800Y277206D01*
X725780Y277166D01*
X725680Y277026D01*
X725650Y276996D01*
Y275866D01*
X725640Y275741D01*
X725600Y275616D01*
X725540Y275506D01*
X725460Y275406D01*
X725360Y275326D01*
X725250Y275266D01*
X725125Y275226D01*
X725000Y275216D01*
X724875Y275226D01*
X724750Y275266D01*
X724640Y275326D01*
X724540Y275406D01*
X724460Y275506D01*
X724400Y275616D01*
X724360Y275741D01*
X724350Y275866D01*
Y276996D01*
X724320Y277026D01*
X724220Y277166D01*
X724200Y277206D01*
X724185Y277241D01*
X724165Y277281D01*
X724150Y277321D01*
X724140Y277361D01*
X724125Y277406D01*
X724120Y277446D01*
X724110Y277486D01*
X724105Y277531D01*
Y277571D01*
X724100Y277616D01*
X724105Y277661D01*
Y277701D01*
X724110Y277746D01*
X724120Y277786D01*
X724125Y277826D01*
X724140Y277871D01*
X724150Y277911D01*
X724165Y277951D01*
X724185Y277991D01*
X724200Y278026D01*
X724220Y278066D01*
X724320Y278206D01*
X724350Y278236D01*
Y281666D01*
X724360Y281791D01*
X724400Y281916D01*
X724460Y282026D01*
X724540Y282126D01*
X724640Y282206D01*
X724750Y282266D01*
X724875Y282306D01*
X725000Y282316D01*
G37*
G36*
G01X729725D02*
X729850Y282306D01*
X729975Y282266D01*
X730085Y282206D01*
X730185Y282126D01*
X730265Y282026D01*
X730325Y281916D01*
X730365Y281791D01*
X730375Y281666D01*
Y278236D01*
X730405Y278206D01*
X730505Y278066D01*
X730525Y278026D01*
X730540Y277991D01*
X730560Y277951D01*
X730575Y277911D01*
X730585Y277871D01*
X730600Y277826D01*
X730605Y277786D01*
X730615Y277746D01*
X730620Y277701D01*
Y277661D01*
X730625Y277616D01*
X730620Y277571D01*
Y277531D01*
X730615Y277486D01*
X730605Y277446D01*
X730600Y277406D01*
X730585Y277361D01*
X730575Y277321D01*
X730560Y277281D01*
X730540Y277241D01*
X730525Y277206D01*
X730505Y277166D01*
X730405Y277026D01*
X730375Y276996D01*
Y275866D01*
X730365Y275741D01*
X730325Y275616D01*
X730265Y275506D01*
X730185Y275406D01*
X730085Y275326D01*
X729975Y275266D01*
X729850Y275226D01*
X729725Y275216D01*
X729600Y275226D01*
X729475Y275266D01*
X729365Y275326D01*
X729265Y275406D01*
X729185Y275506D01*
X729125Y275616D01*
X729085Y275741D01*
X729075Y275866D01*
Y276996D01*
X729045Y277026D01*
X728945Y277166D01*
X728925Y277206D01*
X728910Y277241D01*
X728890Y277281D01*
X728875Y277321D01*
X728865Y277361D01*
X728850Y277406D01*
X728845Y277446D01*
X728835Y277486D01*
X728830Y277531D01*
Y277571D01*
X728825Y277616D01*
X728830Y277661D01*
Y277701D01*
X728835Y277746D01*
X728845Y277786D01*
X728850Y277826D01*
X728865Y277871D01*
X728875Y277911D01*
X728890Y277951D01*
X728910Y277991D01*
X728925Y278026D01*
X728945Y278066D01*
X729045Y278206D01*
X729075Y278236D01*
Y281666D01*
X729085Y281791D01*
X729125Y281916D01*
X729185Y282026D01*
X729265Y282126D01*
X729365Y282206D01*
X729475Y282266D01*
X729600Y282306D01*
X729725Y282316D01*
G37*
G36*
G01X734449D02*
X734574Y282306D01*
X734699Y282266D01*
X734809Y282206D01*
X734909Y282126D01*
X734989Y282026D01*
X735049Y281916D01*
X735089Y281791D01*
X735099Y281666D01*
Y278236D01*
X735129Y278206D01*
X735229Y278066D01*
X735249Y278026D01*
X735264Y277991D01*
X735284Y277951D01*
X735299Y277911D01*
X735309Y277871D01*
X735324Y277826D01*
X735329Y277786D01*
X735339Y277746D01*
X735344Y277701D01*
Y277661D01*
X735349Y277616D01*
X735344Y277571D01*
Y277531D01*
X735339Y277486D01*
X735329Y277446D01*
X735324Y277406D01*
X735309Y277361D01*
X735299Y277321D01*
X735284Y277281D01*
X735264Y277241D01*
X735249Y277206D01*
X735229Y277166D01*
X735129Y277026D01*
X735099Y276996D01*
Y275866D01*
X735089Y275741D01*
X735049Y275616D01*
X734989Y275506D01*
X734909Y275406D01*
X734809Y275326D01*
X734699Y275266D01*
X734574Y275226D01*
X734449Y275216D01*
X734324Y275226D01*
X734199Y275266D01*
X734089Y275326D01*
X733989Y275406D01*
X733909Y275506D01*
X733849Y275616D01*
X733809Y275741D01*
X733799Y275866D01*
Y276996D01*
X733769Y277026D01*
X733669Y277166D01*
X733649Y277206D01*
X733634Y277241D01*
X733614Y277281D01*
X733599Y277321D01*
X733589Y277361D01*
X733574Y277406D01*
X733569Y277446D01*
X733559Y277486D01*
X733554Y277531D01*
Y277571D01*
X733549Y277616D01*
X733554Y277661D01*
Y277701D01*
X733559Y277746D01*
X733569Y277786D01*
X733574Y277826D01*
X733589Y277871D01*
X733599Y277911D01*
X733614Y277951D01*
X733634Y277991D01*
X733649Y278026D01*
X733669Y278066D01*
X733769Y278206D01*
X733799Y278236D01*
Y281666D01*
X733809Y281791D01*
X733849Y281916D01*
X733909Y282026D01*
X733989Y282126D01*
X734089Y282206D01*
X734199Y282266D01*
X734324Y282306D01*
X734449Y282316D01*
G37*
G36*
G01X739173D02*
X739298Y282306D01*
X739423Y282266D01*
X739533Y282206D01*
X739633Y282126D01*
X739713Y282026D01*
X739773Y281916D01*
X739813Y281791D01*
X739823Y281666D01*
Y278236D01*
X739853Y278206D01*
X739953Y278066D01*
X739973Y278026D01*
X739988Y277991D01*
X740008Y277951D01*
X740023Y277911D01*
X740033Y277871D01*
X740048Y277826D01*
X740053Y277786D01*
X740063Y277746D01*
X740068Y277701D01*
Y277661D01*
X740073Y277616D01*
X740068Y277571D01*
Y277531D01*
X740063Y277486D01*
X740053Y277446D01*
X740048Y277406D01*
X740033Y277361D01*
X740023Y277321D01*
X740008Y277281D01*
X739988Y277241D01*
X739973Y277206D01*
X739953Y277166D01*
X739853Y277026D01*
X739823Y276996D01*
Y275866D01*
X739813Y275741D01*
X739773Y275616D01*
X739713Y275506D01*
X739633Y275406D01*
X739533Y275326D01*
X739423Y275266D01*
X739298Y275226D01*
X739173Y275216D01*
X739048Y275226D01*
X738923Y275266D01*
X738813Y275326D01*
X738713Y275406D01*
X738633Y275506D01*
X738573Y275616D01*
X738533Y275741D01*
X738523Y275866D01*
Y276996D01*
X738493Y277026D01*
X738393Y277166D01*
X738373Y277206D01*
X738358Y277241D01*
X738338Y277281D01*
X738323Y277321D01*
X738313Y277361D01*
X738298Y277406D01*
X738293Y277446D01*
X738283Y277486D01*
X738278Y277531D01*
Y277571D01*
X738273Y277616D01*
X738278Y277661D01*
Y277701D01*
X738283Y277746D01*
X738293Y277786D01*
X738298Y277826D01*
X738313Y277871D01*
X738323Y277911D01*
X738338Y277951D01*
X738358Y277991D01*
X738373Y278026D01*
X738393Y278066D01*
X738493Y278206D01*
X738523Y278236D01*
Y281666D01*
X738533Y281791D01*
X738573Y281916D01*
X738633Y282026D01*
X738713Y282126D01*
X738813Y282206D01*
X738923Y282266D01*
X739048Y282306D01*
X739173Y282316D01*
G37*
G36*
G01X743898D02*
X744023Y282306D01*
X744148Y282266D01*
X744258Y282206D01*
X744358Y282126D01*
X744438Y282026D01*
X744498Y281916D01*
X744538Y281791D01*
X744548Y281666D01*
Y278236D01*
X744578Y278206D01*
X744678Y278066D01*
X744698Y278026D01*
X744713Y277991D01*
X744733Y277951D01*
X744748Y277911D01*
X744758Y277871D01*
X744773Y277826D01*
X744778Y277786D01*
X744788Y277746D01*
X744793Y277701D01*
Y277661D01*
X744798Y277616D01*
X744793Y277571D01*
Y277531D01*
X744788Y277486D01*
X744778Y277446D01*
X744773Y277406D01*
X744758Y277361D01*
X744748Y277321D01*
X744733Y277281D01*
X744713Y277241D01*
X744698Y277206D01*
X744678Y277166D01*
X744578Y277026D01*
X744548Y276996D01*
Y275866D01*
X744538Y275741D01*
X744498Y275616D01*
X744438Y275506D01*
X744358Y275406D01*
X744258Y275326D01*
X744148Y275266D01*
X744023Y275226D01*
X743898Y275216D01*
X743773Y275226D01*
X743648Y275266D01*
X743538Y275326D01*
X743438Y275406D01*
X743358Y275506D01*
X743298Y275616D01*
X743258Y275741D01*
X743248Y275866D01*
Y276996D01*
X743218Y277026D01*
X743118Y277166D01*
X743098Y277206D01*
X743083Y277241D01*
X743063Y277281D01*
X743048Y277321D01*
X743038Y277361D01*
X743023Y277406D01*
X743018Y277446D01*
X743008Y277486D01*
X743003Y277531D01*
Y277571D01*
X742998Y277616D01*
X743003Y277661D01*
Y277701D01*
X743008Y277746D01*
X743018Y277786D01*
X743023Y277826D01*
X743038Y277871D01*
X743048Y277911D01*
X743063Y277951D01*
X743083Y277991D01*
X743098Y278026D01*
X743118Y278066D01*
X743218Y278206D01*
X743248Y278236D01*
Y281666D01*
X743258Y281791D01*
X743298Y281916D01*
X743358Y282026D01*
X743438Y282126D01*
X743538Y282206D01*
X743648Y282266D01*
X743773Y282306D01*
X743898Y282316D01*
G37*
G36*
G01X748622D02*
X748747Y282306D01*
X748872Y282266D01*
X748982Y282206D01*
X749082Y282126D01*
X749162Y282026D01*
X749222Y281916D01*
X749262Y281791D01*
X749272Y281666D01*
Y278236D01*
X749302Y278206D01*
X749402Y278066D01*
X749422Y278026D01*
X749437Y277991D01*
X749457Y277951D01*
X749472Y277911D01*
X749482Y277871D01*
X749497Y277826D01*
X749502Y277786D01*
X749512Y277746D01*
X749517Y277701D01*
Y277661D01*
X749522Y277616D01*
X749517Y277571D01*
Y277531D01*
X749512Y277486D01*
X749502Y277446D01*
X749497Y277406D01*
X749482Y277361D01*
X749472Y277321D01*
X749457Y277281D01*
X749437Y277241D01*
X749422Y277206D01*
X749402Y277166D01*
X749302Y277026D01*
X749272Y276996D01*
Y275866D01*
X749262Y275741D01*
X749222Y275616D01*
X749162Y275506D01*
X749082Y275406D01*
X748982Y275326D01*
X748872Y275266D01*
X748747Y275226D01*
X748622Y275216D01*
X748497Y275226D01*
X748372Y275266D01*
X748262Y275326D01*
X748162Y275406D01*
X748082Y275506D01*
X748022Y275616D01*
X747982Y275741D01*
X747972Y275866D01*
Y276996D01*
X747942Y277026D01*
X747842Y277166D01*
X747822Y277206D01*
X747807Y277241D01*
X747787Y277281D01*
X747772Y277321D01*
X747762Y277361D01*
X747747Y277406D01*
X747742Y277446D01*
X747732Y277486D01*
X747727Y277531D01*
Y277571D01*
X747722Y277616D01*
X747727Y277661D01*
Y277701D01*
X747732Y277746D01*
X747742Y277786D01*
X747747Y277826D01*
X747762Y277871D01*
X747772Y277911D01*
X747787Y277951D01*
X747807Y277991D01*
X747822Y278026D01*
X747842Y278066D01*
X747942Y278206D01*
X747972Y278236D01*
Y281666D01*
X747982Y281791D01*
X748022Y281916D01*
X748082Y282026D01*
X748162Y282126D01*
X748262Y282206D01*
X748372Y282266D01*
X748497Y282306D01*
X748622Y282316D01*
G37*
G54D110*
X583700Y194750D03*
G54D101*
X520200Y105490D03*
Y103520D03*
Y101550D03*
Y121235D03*
Y119270D03*
Y117300D03*
Y115330D03*
Y113360D03*
Y111395D03*
Y109425D03*
Y107455D03*
Y135015D03*
Y133045D03*
Y131080D03*
Y129110D03*
Y127140D03*
Y125175D03*
Y123205D03*
Y150765D03*
Y148795D03*
Y146825D03*
Y144860D03*
Y142890D03*
Y140920D03*
Y138955D03*
Y136985D03*
Y166510D03*
Y164545D03*
Y162575D03*
Y160605D03*
Y158640D03*
Y156670D03*
Y154700D03*
Y152730D03*
Y170450D03*
Y168480D03*
X603800Y101550D03*
Y103520D03*
Y105490D03*
Y107455D03*
Y109425D03*
Y111395D03*
Y113360D03*
Y115330D03*
Y117300D03*
Y119270D03*
Y121235D03*
Y123205D03*
Y125175D03*
Y127140D03*
Y129110D03*
Y131080D03*
Y133045D03*
Y135015D03*
Y136985D03*
Y138955D03*
Y140920D03*
Y142890D03*
Y144860D03*
Y146825D03*
Y148795D03*
Y150765D03*
Y152730D03*
Y154700D03*
Y156670D03*
Y158640D03*
Y160605D03*
Y162575D03*
Y164545D03*
Y166510D03*
Y168480D03*
Y170450D03*
G54D111*
X617931Y133000D03*
X623069D03*
X634431Y167500D03*
X639569D03*
G54D102*
X527550Y94200D03*
X529520D03*
X531490D03*
X533455D03*
X535425D03*
X537395D03*
X539360D03*
X541330D03*
Y177800D03*
X539360D03*
X537395D03*
X535425D03*
X533455D03*
X531490D03*
X529520D03*
X527550D03*
X543300Y94200D03*
X545270D03*
X547235D03*
X549205D03*
X551175D03*
X553140D03*
X555110D03*
Y177800D03*
X553140D03*
X551175D03*
X549205D03*
X547235D03*
X545270D03*
X543300D03*
X557080Y94200D03*
X559045D03*
X561015D03*
X562985D03*
X564955D03*
X566920D03*
X568890D03*
X570860D03*
Y177800D03*
X568890D03*
X566920D03*
X564955D03*
X562985D03*
X561015D03*
X559045D03*
X557080D03*
X572825Y94200D03*
X574795D03*
X576765D03*
X578730D03*
X580700D03*
X582670D03*
X584640D03*
X586605D03*
Y177800D03*
X584640D03*
X582670D03*
X580700D03*
X578730D03*
X576765D03*
X574795D03*
X572825D03*
X588575Y94200D03*
X590545D03*
X592510D03*
X594480D03*
X596450D03*
Y177800D03*
X594480D03*
X592510D03*
X590545D03*
X588575D03*
G54D120*
X731340Y73615D03*
G54D112*
X631500Y83177D03*
Y117823D03*
G54D130*
X785015Y152121D03*
G54D121*
X735277Y67865D03*
X733309D03*
X731340D03*
X729371D03*
X727403D03*
Y79365D03*
X729371D03*
X731340D03*
X733309D03*
X735277D03*
G54D103*
X540960Y222285D03*
G54D10*
G01X17500Y190200D02*
X14550Y187250D01*
Y173350D01*
X18600Y169300D01*
G01X17500Y190200D02*
X16900Y190800D01*
Y195600D01*
X18000Y196700D01*
G01X27900Y84500D02*
Y81900D01*
X28400Y81400D01*
G01X27900Y87500D02*
Y84500D01*
G01X31300D02*
X33000D01*
X34800Y86300D01*
X34900D01*
G01X31300Y87500D02*
X32288D01*
X33407Y88608D01*
X33699Y88900D01*
X35700D01*
X38400Y91600D01*
Y92753D01*
X39142Y93495D01*
G01X27200Y127700D02*
Y128997D01*
X29651Y131448D01*
G01X34357Y135626D02*
X32611D01*
X29651Y132666D01*
Y131448D01*
G01X27200Y124300D02*
X24000D01*
G01X27200D02*
X30200D01*
G01D02*
X34000D01*
X36700Y121600D01*
X44300D01*
X47600Y124900D01*
Y126000D01*
G01X34357Y133657D02*
Y132357D01*
X30200Y128200D01*
Y127700D01*
G01D02*
X33400D01*
X33900Y127200D01*
G01X34357Y137594D02*
X32094D01*
X30500Y136000D01*
X30000D01*
G01X24000Y127700D02*
Y130900D01*
X24800Y131700D01*
G01D02*
X26416Y133316D01*
X27316D01*
X30000Y136000D01*
G01X18000Y196700D02*
Y196800D01*
X21900Y200700D01*
G01X18000Y196700D02*
X20200Y194500D01*
X21500D01*
X23089Y192911D01*
Y190832D01*
G01X25000Y203800D02*
Y200800D01*
X24900Y200700D01*
G01X21900Y205400D02*
X23500Y203800D01*
X25000D01*
G01Y206900D02*
X23512D01*
X22811Y207601D01*
X20989D01*
X19699Y206311D01*
Y202901D01*
X21900Y200700D01*
G01X45857Y91657D02*
X42557D01*
X41200Y90300D01*
G01X34900Y86300D02*
X36212D01*
X40212Y90300D01*
X41200D01*
G01X45857Y95594D02*
X42806D01*
X42400Y96000D01*
X42000D01*
G01X45857Y93626D02*
X39273D01*
X39142Y93495D01*
G01X51000Y123800D02*
X48800Y126000D01*
X47600D01*
G01X37500Y127700D02*
X37000Y127200D01*
X33900D01*
G01X38900Y187000D02*
Y188100D01*
X33500Y193500D01*
Y196100D01*
G01X49200Y247400D02*
X45505D01*
X41100Y242995D01*
Y240370D01*
X42300Y239170D01*
Y237430D01*
X41600Y236730D01*
Y232870D01*
X44861Y229609D01*
Y227261D01*
G01X49500Y234800D02*
Y231900D01*
X44861Y227261D01*
G01X63100Y84300D02*
Y80100D01*
X62900Y79900D01*
G01X63100Y84300D02*
X65500D01*
X67000Y82800D01*
G01X54000Y123700D02*
Y120900D01*
X53500Y120400D01*
G01X54000Y123700D02*
X53900Y123800D01*
X51000D01*
G01X57000D02*
X56900Y123700D01*
X54000D01*
G01X52643Y133657D02*
Y130800D01*
G01D02*
X51000Y129157D01*
Y127200D01*
G01D02*
X53900D01*
X54000Y127300D01*
G01X52643Y135626D02*
X54874D01*
X56100Y134400D01*
Y130700D01*
G01X60000Y127200D02*
X57000D01*
G01D02*
X56100Y128100D01*
Y130700D01*
G01X52643Y141531D02*
X57781D01*
X58000Y141750D01*
G01X52643Y137594D02*
X56906D01*
X57600Y136900D01*
G01X60700Y226800D02*
X57800D01*
X57600Y226600D01*
G01X54000Y220900D02*
X55082Y219818D01*
X57282D01*
X57294Y219806D01*
G01X57287D02*
X57294D01*
G01X60700Y220800D02*
X59718Y219818D01*
X57318D01*
X57300Y219800D01*
X57294Y219806D01*
G01X50500Y221500D02*
X51100Y220900D01*
X54000D01*
G01X52600Y250400D02*
X53400D01*
X56900Y253900D01*
X57800D01*
G01X61300Y253300D02*
X58400D01*
X57800Y253900D01*
G01X67000Y82800D02*
X70500Y79300D01*
X83800D01*
X89800Y85300D01*
Y87300D01*
G01X67000Y86200D02*
X64200Y89000D01*
X64143D01*
Y91657D01*
G01X76800Y82000D02*
X76700Y82100D01*
Y85000D01*
G01X76800Y82000D02*
X72000D01*
G01X67000Y86200D02*
X68000Y85200D01*
X68800D01*
X72000Y82000D01*
G01X64143Y95594D02*
X67506D01*
X68200Y94900D01*
G01X64143Y93626D02*
X66374D01*
X68200Y91800D01*
Y91500D01*
G01X64143Y99531D02*
X69031D01*
X69235Y99735D01*
G01X76000Y132300D02*
X78700D01*
X79000Y132600D01*
G01D02*
X81800Y135400D01*
X85500D01*
G01X76000Y128700D02*
X78500D01*
X79000Y129200D01*
G01X73000Y128700D02*
X76000D01*
G01X73000D02*
X68419D01*
X67719Y128000D01*
X66500D01*
G01X73000Y132300D02*
Y133700D01*
X75000Y135700D01*
G01X76400Y139200D02*
Y137100D01*
X75000Y135700D01*
G01X76400Y139200D02*
X79100D01*
G01X67813Y227987D02*
X66813D01*
X65000Y229800D01*
X64100D01*
G01Y226800D02*
Y223800D01*
G01Y229800D02*
Y226800D01*
G01X80300Y85000D02*
X81418D01*
X86100Y89682D01*
Y97700D01*
G01X90000Y91000D02*
Y90470D01*
X87600Y88070D01*
Y86788D01*
X85906Y85094D01*
G01X80200Y82000D02*
X82812D01*
X85906Y85094D01*
G01X112550Y142800D02*
X111150Y141400D01*
X108550D01*
G01X153100Y170900D02*
X153000Y170800D01*
Y167200D01*
G01D02*
X154880Y165320D01*
X157940D01*
G01X149400Y177700D02*
X151720Y180020D01*
X155740D01*
G01X160500Y172680D02*
Y175260D01*
X155740Y180020D01*
G01X186900Y119900D02*
X186140Y119140D01*
Y111960D01*
X192229Y105871D01*
G01X183500Y188800D02*
X187600D01*
G01X178240Y189000D02*
X178440Y188800D01*
X183500D01*
G01X216261Y74846D02*
Y85339D01*
X212100Y89500D01*
X202200D01*
G01X192229Y105871D02*
X194197D01*
G01X203500Y107500D02*
Y108700D01*
X203750Y108950D01*
Y112070D01*
X203589Y112231D01*
Y127089D01*
X207390Y130890D01*
Y135196D01*
X207362Y135238D01*
X202734Y139866D01*
X200382D01*
X199716Y139200D01*
X197300D01*
G01X195600Y177000D02*
Y174900D01*
X201500Y169000D01*
X206750D01*
G01X187600Y188800D02*
X189219D01*
X193900Y184119D01*
Y181882D01*
X195782Y180000D01*
X197330D01*
X198499Y178831D01*
Y176006D01*
X201655Y172850D01*
X207615D01*
X209060Y174295D01*
Y174440D01*
G01X200000Y180800D02*
X201300D01*
X203000Y179100D01*
X205500D01*
X206500Y178100D01*
Y175750D01*
G01X196518Y182800D02*
X198000D01*
X200000Y180800D01*
G01Y184200D02*
Y184500D01*
X202311Y186811D01*
X202761D01*
G01X212268Y166850D02*
X212618Y167200D01*
X215400D01*
X216000Y167800D01*
G01X206750Y169000D02*
X210200D01*
X212209Y166991D01*
Y166909D01*
X212268Y166850D01*
G01X219940Y168750D02*
X218990Y167800D01*
X216000D01*
G01X206500Y182250D02*
Y184700D01*
X207500Y185700D01*
G01X203940Y182250D02*
Y184940D01*
X204700Y185700D01*
X207500D01*
G01X209060Y174440D02*
X212500Y171000D01*
X214000D01*
G01X209060Y174440D02*
Y175750D01*
G01X217300Y180500D02*
Y174300D01*
X214000Y171000D01*
G01X207500Y185700D02*
X210202D01*
X211202Y186700D01*
Y186727D01*
G01X217300Y183500D02*
X214073Y186727D01*
X211202D01*
G01X212100Y210500D02*
Y206900D01*
X209800Y204600D01*
G01X218795Y206921D02*
Y208793D01*
X215500Y212088D01*
Y212300D01*
G01D02*
X213900D01*
X212100Y210500D01*
G01X218795Y202984D02*
X215384D01*
G01X218795Y201016D02*
X216716D01*
X215100Y199400D01*
G01X216000Y219500D02*
X215500Y219000D01*
Y215700D01*
G01D02*
X218400D01*
X218500Y215800D01*
G01X232600Y95300D02*
Y89931D01*
X232791Y89740D01*
G01X241209Y86000D02*
X231700D01*
X230100Y87600D01*
Y100600D01*
X231500Y102000D01*
X232300D01*
G01Y99000D02*
X232600Y98700D01*
Y95300D01*
G01X239000Y123400D02*
X225700Y110100D01*
Y99725D01*
X227850Y97575D01*
G01X232300Y102000D02*
X232975Y102675D01*
Y108111D01*
X233452Y108588D01*
G01X222500Y162250D02*
Y159990D01*
X223190Y159300D01*
X224460D01*
X225060Y159900D01*
Y162250D01*
G01X229500Y160900D02*
X229400Y161000D01*
X228100D01*
X226850Y162250D01*
X225060D01*
G01X229800Y164500D02*
Y161200D01*
X229500Y160900D01*
G01X227870Y170252D02*
X227871Y170251D01*
X227910D01*
X229800Y168361D01*
Y164500D01*
G01X222500Y177200D02*
X225700D01*
X227000Y178500D01*
G01D02*
X225300Y180200D01*
X224200D01*
G01X222500Y168750D02*
Y173800D01*
G01D02*
X226244D01*
X226292Y173752D01*
G01X219500Y173800D02*
X219940Y173360D01*
Y168750D01*
G01X229205Y204953D02*
X231857D01*
X232560Y204250D01*
G01X218500Y212200D02*
X218600Y212300D01*
X221500D01*
G01X226000Y215700D02*
X225015D01*
X221615Y212300D01*
X221500D01*
G01Y215700D02*
X221400Y215800D01*
X218500D01*
G01X234100Y215700D02*
X226000D01*
G01X245300Y88500D02*
X236700D01*
G01X248700D02*
Y91500D01*
G01X239000Y102200D02*
Y102559D01*
X241741Y105300D01*
G01X248591Y109540D02*
X244351Y105300D01*
X241741D01*
G01X248591Y102060D02*
Y96209D01*
X248700Y96100D01*
G01D02*
Y91500D01*
G01X248500Y116200D02*
X252900D01*
X253100Y116000D01*
G01X244100Y110560D02*
Y113100D01*
X247200Y116200D01*
X248500D01*
G01X239000Y123400D02*
X243600D01*
X244500Y122500D01*
G01X241000Y128600D02*
X242400D01*
X244000Y127000D01*
X247500D01*
G01D02*
X251300D01*
G01X255500Y96700D02*
X257009Y98209D01*
Y105800D01*
G01D02*
Y112291D01*
X253300Y116000D01*
X253100D01*
G01X264500Y73100D02*
Y72700D01*
X266852Y70348D01*
X267121D01*
G01X279300Y121000D02*
Y117700D01*
X278075Y116475D01*
G01X280950Y232945D02*
X278455D01*
X275400Y236000D01*
Y237900D01*
G01X323532Y102711D02*
X326732D01*
G01X320332D02*
X323532D01*
G01X324822Y121201D02*
X325134D01*
X326313Y122380D01*
G01X322572Y110771D02*
X323771D01*
X325300Y112300D01*
G01X326592Y110771D02*
Y111008D01*
X325300Y112300D01*
G01X325350Y114500D02*
X326923D01*
X327822Y113601D01*
G01X321992Y138211D02*
Y138209D01*
X322800Y137401D01*
Y136132D01*
X322691Y136023D01*
G01X321992Y134181D02*
X322000Y134189D01*
Y135332D01*
X322691Y136023D01*
G01X326313Y122380D02*
X324822Y123871D01*
Y123961D01*
G01X313392Y124131D02*
X314770Y125509D01*
X315792D01*
Y125511D01*
G01X321442Y128751D02*
Y129407D01*
X320321Y130528D01*
G01X322192Y131421D02*
Y131419D01*
X321212D01*
X320321Y130528D01*
G01X323007Y127672D02*
X321442Y126107D01*
Y125991D01*
G01D02*
X321082Y125631D01*
X318702D01*
G01X319282Y133521D02*
X318962Y133201D01*
X315132D01*
G01D02*
X314893Y133440D01*
X312917D01*
G01X313392Y124131D02*
X312000Y122739D01*
Y122600D01*
G01X326322Y144661D02*
X325361D01*
X323550Y142850D01*
Y142104D01*
G01X321922Y140991D02*
Y140989D01*
X319292D01*
X319252Y140949D01*
G01X317352Y140951D02*
X318448D01*
X318450Y140949D01*
X319252D01*
G01X321442Y146481D02*
X320251Y147672D01*
Y148504D01*
X319401Y149354D01*
G01X317332Y149271D02*
X317415Y149354D01*
X319401D01*
G01X313392Y141861D02*
X313262Y141731D01*
X311000D01*
G01X320112Y153921D02*
X320342Y153691D01*
Y153324D01*
X321755Y151911D01*
X321992D01*
G01X323550Y142104D02*
Y142008D01*
X323682Y141876D01*
Y140741D01*
X324822Y139601D01*
G01X313392Y165991D02*
Y165989D01*
X313532D01*
X313559Y166016D01*
X314667D01*
X315384Y166733D01*
G01X317332Y166991D02*
Y166989D01*
X315640D01*
X315384Y166733D01*
G01X313390Y159589D02*
X313392Y159591D01*
G01X313390Y159589D02*
X312707D01*
X311850Y158732D01*
X311242D01*
G01X313392Y153921D02*
X311600D01*
X311500Y153821D01*
X311417D01*
G01X324200Y157800D02*
X324100D01*
X323978Y157922D01*
X322721D01*
X321922Y158721D01*
G01X320112Y153921D02*
Y153919D01*
X319473D01*
X317865Y152311D01*
X317698D01*
G01X317112Y154121D02*
Y152897D01*
X317698Y152311D01*
G01X326322Y160301D02*
Y160299D01*
X324953Y161668D01*
Y161722D01*
G01X326322Y163061D02*
X326320Y163059D01*
X326290D01*
X324953Y161722D01*
G01X324200Y157800D02*
X324100Y157700D01*
X323978D01*
X322209Y155931D01*
X321992D01*
G01X324822Y168121D02*
X326102Y169401D01*
X326399D01*
G01X326322Y175941D02*
X324672D01*
X324436Y175705D01*
G01X321442Y179181D02*
X320099Y180524D01*
X320037D01*
G01X317112Y171851D02*
X316922Y172041D01*
X313784D01*
X313392Y171649D01*
G01X321442Y181931D02*
Y181929D01*
X320037Y180524D01*
G01D02*
X319942D01*
G01X315782Y182341D02*
X314414Y183709D01*
X313392D01*
G01D02*
X312829Y183146D01*
Y181940D01*
G01X321992Y173661D02*
Y173110D01*
X323165Y171937D01*
G01X313392Y171649D02*
Y171651D01*
G01X311460Y172078D02*
X311889Y171649D01*
X313392D01*
G01X321992Y169641D02*
X323165Y170814D01*
Y171937D01*
G01X324822Y186521D02*
Y187084D01*
X323789Y188117D01*
G01X323800Y192150D02*
X323041Y191391D01*
X321992D01*
G01X313392Y183711D02*
Y183709D01*
G01X321992Y187371D02*
X323043D01*
X323789Y188117D01*
G01X326831Y196119D02*
X326505D01*
X325160Y194774D01*
Y194679D01*
X324822Y194341D01*
G01X321922Y194171D02*
X324652D01*
X324822Y194341D01*
G01X319282Y192051D02*
X321332D01*
X321992Y191391D01*
G01X315132Y186391D02*
X315442Y186701D01*
X319282D01*
G01D02*
Y185047D01*
X320029Y184300D01*
G01X311900Y188070D02*
X312080D01*
X313392Y189381D01*
G01X320300Y245800D02*
X316800D01*
X315300Y244300D01*
X314500D01*
G01X320300Y245800D02*
X322800Y248300D01*
Y251000D01*
G01D02*
Y251400D01*
X325500Y254100D01*
X326000D01*
G01X330252Y102171D02*
X331829D01*
X332600Y101400D01*
G01X335272Y104571D02*
Y107361D01*
X335152Y107481D01*
G01X326732Y102711D02*
X327100Y102343D01*
Y98000D01*
X328000Y97100D01*
G01X334782Y110221D02*
X334738D01*
X333416Y108899D01*
G01X337522Y110711D02*
X335272D01*
X334782Y110221D01*
G01X335152Y107481D02*
X333734Y108899D01*
X333416D01*
G01X326592Y110771D02*
Y108731D01*
X327262Y108061D01*
G01X341322Y131781D02*
X340783Y132320D01*
Y135125D01*
X341309Y135651D01*
G01X332322Y129021D02*
X332320D01*
X330870Y130470D01*
Y130540D01*
G01X330822Y136841D02*
Y136622D01*
X329693Y135493D01*
Y134428D01*
G01X327822Y123961D02*
Y123889D01*
X326313Y122380D01*
G01X332322Y131781D02*
X332241D01*
X331000Y130540D01*
X330870D01*
G01X341309Y135651D02*
X341010D01*
X339822Y136839D01*
Y136841D01*
G01X341322Y147421D02*
X342563Y146180D01*
X342880D01*
G01X332322Y147421D02*
X331122Y146221D01*
X330796D01*
G01X335322Y144661D02*
Y142838D01*
X336190Y141970D01*
G01D02*
X335390Y141170D01*
Y141169D01*
X333822Y139601D01*
G01X335322Y163061D02*
Y163295D01*
X334950Y163667D01*
Y164280D01*
X334470Y164760D01*
G01X339822Y152481D02*
Y152479D01*
X339644D01*
X338421Y153702D01*
Y153802D01*
G01X339822Y155241D02*
Y155239D01*
X339558D01*
X338421Y154102D01*
Y153802D01*
G01X330822Y152481D02*
X330824D01*
X332149Y153806D01*
G01X330822Y155241D02*
X332149Y153914D01*
Y153806D01*
G01D02*
X332185D01*
G01X335322Y160301D02*
X335065D01*
X333742Y161624D01*
G01X334715Y180900D02*
X334720Y180905D01*
Y181020D01*
X336600Y182900D01*
Y183539D01*
X336822Y183761D01*
G01X339822Y170881D02*
X340019D01*
X341300Y169600D01*
G01X333822Y168121D02*
X333921D01*
X335400Y169600D01*
G01X341322Y178701D02*
X340723Y178102D01*
X340674D01*
X339875Y177303D01*
G01X341322Y175941D02*
X341237D01*
X339875Y177303D01*
G01X332300Y173900D02*
X330822Y172422D01*
Y170881D01*
G01X326500Y187900D02*
X326600Y187800D01*
Y187743D01*
X327822Y186521D01*
G01X339492Y197891D02*
Y197692D01*
X338050Y196250D01*
X338048D01*
G01X336412Y193561D02*
Y193712D01*
X338048Y195348D01*
Y196250D01*
G01X331352Y189061D02*
X332713Y187700D01*
X332800D01*
G01X328562Y197951D02*
X328462Y198051D01*
Y199365D01*
X329028Y199931D01*
G01X338000Y185700D02*
Y186389D01*
X339172Y187561D01*
G01X333822Y183761D02*
Y184322D01*
X335000Y185500D01*
G01X330822Y183761D02*
X332100Y185039D01*
Y185600D01*
G01X335832Y206491D02*
X334800Y207523D01*
Y208942D01*
X333000Y210742D01*
Y210848D01*
X332974Y210874D01*
G01X341502Y206491D02*
Y206560D01*
X340662Y207400D01*
X339800D01*
G01X331302Y198441D02*
X329812Y199931D01*
X329028D01*
G01X334052Y198441D02*
X331302D01*
G01X326200Y251000D02*
X333852Y258652D01*
X381443D01*
X405395Y234700D01*
X415800D01*
X425500Y225000D01*
Y222500D01*
X427392Y220608D01*
Y208799D01*
X426292Y207699D01*
Y205246D01*
X426311Y205227D01*
Y204399D01*
G01X350800Y138300D02*
X350750D01*
X349449Y139601D01*
X348822D01*
G01X356882Y151181D02*
Y150632D01*
X355760Y149510D01*
X355460D01*
G01X356882Y141731D02*
Y141967D01*
X355425Y143424D01*
X355342D01*
G01X353742Y144881D02*
X353968D01*
X355342Y143507D01*
Y143424D01*
G01X348822Y136841D02*
Y139601D01*
G01X350422Y150171D02*
X349351Y149100D01*
X348743D01*
G01X344322Y144661D02*
X344320Y144663D01*
Y144740D01*
X342880Y146180D01*
G01X348822Y152481D02*
Y152479D01*
X348500Y152157D01*
Y149343D01*
X348743Y149100D01*
G01X353742Y148031D02*
X353824D01*
X355303Y149510D01*
X355460D01*
G01X350082Y147421D02*
X351068D01*
X351093Y147446D01*
X353157D01*
X353742Y148031D01*
G01X344322Y144661D02*
X342750Y143089D01*
Y139673D01*
X342822Y139601D01*
G01X356882Y148029D02*
Y147963D01*
X355447Y146528D01*
G01X344322Y160301D02*
X344048D01*
X342825Y161524D01*
X342785D01*
X342716Y161593D01*
G01X353742Y163781D02*
X356882D01*
G01X345822Y168121D02*
Y164561D01*
X344322Y163061D01*
G01X350422Y157541D02*
X353682D01*
X353742Y157481D01*
G01X344322Y163061D02*
X344320Y163059D01*
X344182D01*
X342716Y161593D01*
G01X356882Y154331D02*
Y154478D01*
X355560Y155800D01*
Y155903D01*
X355413Y156050D01*
G01X356882Y157481D02*
X355598Y156197D01*
X355560D01*
X355413Y156050D01*
G01X353742Y157481D02*
X353889D01*
X355320Y156050D01*
X355413D01*
G01X350982Y175991D02*
X353742D01*
G01X350000Y177700D02*
Y176973D01*
X350982Y175991D01*
G01X346992Y180061D02*
X346990Y180059D01*
X346920D01*
X346430Y179569D01*
Y179568D01*
X345562Y178700D01*
G01X344232Y177061D02*
Y177370D01*
X345562Y178700D01*
G01X346992Y177061D02*
Y177270D01*
X345562Y178700D01*
G01X356882Y175991D02*
X354812Y178061D01*
Y178561D01*
G01X355300Y174600D02*
X355513D01*
X356882Y173231D01*
G01X354812Y178561D02*
Y178637D01*
X353321Y180128D01*
G01X350882Y173231D02*
Y173118D01*
X352200Y171800D01*
G01X353742Y173231D02*
X353731D01*
X352300Y171800D01*
X352200D01*
G01X346292Y197951D02*
Y199432D01*
X345837Y199887D01*
G01X344232Y195061D02*
X343395D01*
X342029Y196427D01*
G01X343512Y197891D02*
Y197889D01*
X342050Y196427D01*
X342029D01*
G01X354812Y187561D02*
X356800Y189549D01*
Y191000D01*
G01X346992Y189061D02*
X348812Y187241D01*
X349751D01*
G01X352052Y184561D02*
X349900Y186713D01*
Y187092D01*
X349751Y187241D01*
G01X351782Y198441D02*
Y197845D01*
X351600Y197663D01*
Y194013D01*
X352052Y193561D01*
G01X354452Y197691D02*
X352532D01*
X351782Y198441D01*
G01X342760Y187810D02*
X344232Y186338D01*
Y186061D01*
G01X349022Y198441D02*
X349095D01*
X350409Y199755D01*
G01X351782Y198441D02*
X351723D01*
X350409Y199755D01*
G01X354572Y202551D02*
Y200177D01*
X354700Y200049D01*
Y199900D01*
G01X357212Y197891D02*
X356668D01*
X354700Y199859D01*
Y199900D01*
G01X353562Y206491D02*
Y208236D01*
X353792Y208466D01*
G01X391000Y265000D02*
X390000Y266000D01*
X372000D01*
X371000Y267000D01*
X353100D01*
X349900Y263800D01*
G01X360042Y135431D02*
X359236Y136237D01*
Y136264D01*
X358500Y137000D01*
G01X356882Y135431D02*
X356931D01*
X358500Y137000D01*
G01X361700Y146549D02*
X363182Y148031D01*
G01X360042Y141731D02*
X360263D01*
X361726Y140268D01*
G01X360042Y138581D02*
Y138584D01*
X361726Y140268D01*
G01X360042Y151181D02*
X361500Y149723D01*
Y149500D01*
G01X363182Y151181D02*
Y151174D01*
X361508Y149500D01*
X361500D01*
G01X356882Y148031D02*
Y148029D01*
G01X360042Y148031D02*
X360040Y148029D01*
X356882D01*
G01X358576Y162090D02*
X356885Y163781D01*
X356882D01*
G01Y160631D02*
X357117D01*
X358576Y162090D01*
G01X358342Y165324D02*
X358617D01*
X360042Y166749D01*
Y166931D01*
G01Y160631D02*
X360035D01*
X358576Y162090D01*
G01X369482Y166931D02*
X368000Y168413D01*
Y168500D01*
G01X360042Y166931D02*
X360223Y166750D01*
X363001D01*
X363182Y166931D01*
G01X366342D02*
X366441D01*
X366442Y166930D01*
Y166942D01*
X368000Y168500D01*
G01X372642Y166931D02*
X369482D01*
G01X360042Y157481D02*
X358600Y158923D01*
Y159177D01*
X358477Y159300D01*
G01X359872Y180061D02*
Y180183D01*
X361089Y181400D01*
X361283D01*
X361292Y181409D01*
G01X356882Y173231D02*
Y170081D01*
G01X361292Y181409D02*
X361444Y181561D01*
X364692D01*
X367692Y178561D01*
G01X363182Y170081D02*
X363081D01*
X361500Y168500D01*
G01X359872Y177061D02*
Y177172D01*
X361200Y178500D01*
G01X361242Y197891D02*
X362632Y196501D01*
Y195061D01*
G01X370452Y184561D02*
X370440D01*
X369009Y185992D01*
Y186191D01*
G01X367692Y187561D02*
Y187309D01*
X368810Y186191D01*
X369009D01*
G01X359222Y197700D02*
X361051D01*
X361242Y197891D01*
G01X359222Y199771D02*
Y197700D01*
G01X359872Y189061D02*
X359835Y189024D01*
X359976D01*
X361400Y187600D01*
G01X362632Y186061D02*
X361300Y184729D01*
Y184500D01*
G01X364892Y206491D02*
X365307Y206906D01*
X365250Y206963D01*
Y208600D01*
G01X377772Y102171D02*
X377572Y102371D01*
Y105889D01*
G01X383432Y102171D02*
X382210Y100950D01*
X381950D01*
G01X379526Y106396D02*
X379019Y105889D01*
X377572D01*
G01D02*
Y105891D01*
G01X385212Y110221D02*
Y110161D01*
X386561Y108812D01*
G01X382542Y110971D02*
X384462D01*
X385212Y110221D01*
G01X387972D02*
X387970D01*
X386561Y108812D01*
G01X387972Y110221D02*
X387000Y111193D01*
Y112300D01*
G01X385242Y135431D02*
Y135652D01*
X386708Y137118D01*
G01X385632Y132671D02*
Y132669D01*
X388382D01*
G01X385750Y128517D02*
X385661Y128606D01*
Y128634D01*
X384272Y130023D01*
Y130101D01*
G01X387032Y127101D02*
X385750Y128383D01*
Y128517D01*
G01X382082Y135431D02*
Y135429D01*
X381352Y136159D01*
X381332D01*
X380475Y137016D01*
G01X382082Y138581D02*
X383567Y137096D01*
G01X385242Y138581D02*
Y138579D01*
X386703Y137118D01*
X386708D01*
G01X378942Y151181D02*
Y151154D01*
X377476Y149688D01*
G01X372642Y166931D02*
X375782D01*
G01X382082D02*
X382089D01*
X383548Y168390D01*
G01X385242Y166931D02*
X383783Y168390D01*
X383548D01*
G01X388382Y166931D02*
X388013Y167300D01*
X385611D01*
X385242Y166931D01*
G01X380500Y168500D02*
X379500Y167500D01*
Y167489D01*
X378942Y166931D01*
G01X376830Y175640D02*
X376950Y175520D01*
X379567D01*
X381856Y173231D01*
X382082D01*
G01X378942Y170081D02*
X378953D01*
X380477Y171605D01*
G01X378942Y173231D02*
Y173140D01*
X380477Y171605D01*
G01X385242Y170081D02*
X385800Y170639D01*
Y172673D01*
X385242Y173231D01*
G01D02*
X386600Y174589D01*
Y174900D01*
G01X382082Y170081D02*
Y170079D01*
X383427Y171424D01*
X383693D01*
G01X386092Y190561D02*
X386073D01*
X384684Y191950D01*
G01X397900Y272800D02*
Y275100D01*
X395600Y277400D01*
X381400D01*
X379300Y275300D01*
G01X387000Y270000D02*
Y274400D01*
X386100Y275300D01*
G01X379500Y270000D02*
Y272100D01*
X382700Y275300D01*
G01X395502Y102171D02*
X395431Y102100D01*
X392431D01*
X392382Y102149D01*
G01X390702Y110711D02*
Y108061D01*
X390683Y108042D01*
G01X392862Y107891D02*
X390834D01*
X390683Y108042D01*
G01X397512Y110771D02*
Y111551D01*
X396600Y112463D01*
G01X393482Y110771D02*
X394908D01*
X396600Y112463D01*
G01X400272Y110971D02*
Y109228D01*
X400700Y108800D01*
G01D02*
X401521D01*
X402942Y110221D01*
G01X401500Y122600D02*
X401411D01*
X399912Y121101D01*
G01X402672D02*
Y121428D01*
X401500Y122600D01*
G01X392092Y119601D02*
X393613Y121122D01*
X393653D01*
G01X394852Y119601D02*
Y119923D01*
X393653Y121122D01*
G01X388382Y135431D02*
Y135652D01*
X389848Y137118D01*
G01X397842Y132671D02*
X398159D01*
X399452Y133964D01*
G01X400982Y132671D02*
X400745D01*
X399452Y133964D01*
G01X388382Y132669D02*
Y132671D01*
G01X389380Y130100D02*
Y131671D01*
X388382Y132669D01*
G01X397800Y130000D02*
X399811D01*
X399912Y130101D01*
G01X401256Y128755D02*
X402602Y130101D01*
X402672D01*
G01X393561Y127130D02*
X394852Y128421D01*
Y128601D01*
G01X392092D02*
Y128599D01*
X393561Y127130D01*
G01X388382Y138581D02*
Y138579D01*
X389843Y137118D01*
X389848D01*
G01X393077Y168455D02*
X394603Y166929D01*
X394682D01*
Y166931D01*
G01X400982Y163781D02*
Y163779D01*
X400759D01*
X399298Y165240D01*
G01X397842Y163781D02*
Y163784D01*
X399298Y165240D01*
G01X401732Y178561D02*
Y178761D01*
X400352Y180141D01*
G01D02*
Y180171D01*
G01X398972Y178561D02*
Y178761D01*
X400352Y180141D01*
G01X391152Y189061D02*
Y188985D01*
X392596Y187541D01*
G01X401732Y187561D02*
X402962Y188791D01*
Y189014D01*
G01X398972Y190561D02*
X397728Y189317D01*
Y189053D01*
G01X395641Y188045D02*
Y187790D01*
X393912Y186061D01*
G01X394400Y263100D02*
X392900D01*
X391000Y265000D01*
G01X407562Y102171D02*
Y100862D01*
X407550Y100850D01*
Y100196D01*
G01X413222Y102171D02*
Y100769D01*
X412650Y100197D01*
G01X418892Y102171D02*
Y101492D01*
X417800Y100400D01*
G01X408432Y110711D02*
X411152D01*
X411212Y110771D01*
G01X405702Y110221D02*
X402942D01*
G01X408432Y110711D02*
X406192D01*
X405702Y110221D01*
G01X408472Y106131D02*
Y110671D01*
X408432Y110711D01*
G01X418002Y110971D02*
Y111869D01*
X419596Y113463D01*
G01X415232Y110771D02*
X417802D01*
X418002Y110971D01*
G01X407732Y119601D02*
X407801D01*
X409110Y120910D01*
G01X415552Y115101D02*
Y115243D01*
X416922Y116613D01*
G01X418312Y115101D02*
Y115223D01*
X416922Y116613D01*
G01X410492Y119601D02*
X410399D01*
X409110Y120890D01*
Y120910D01*
G01X403742Y132671D02*
X405350Y131063D01*
X405500D01*
G01X407732Y131601D02*
X407194Y131063D01*
X405500D01*
G01X416402Y132721D02*
Y132719D01*
X417753Y131368D01*
Y131322D01*
G01X419402Y129961D02*
Y129959D01*
X418039Y131322D01*
X417753D01*
G01X404400Y128900D02*
X404813Y129313D01*
X406225D01*
X406262Y129350D01*
X406983D01*
X407732Y128601D01*
G01X417902Y124901D02*
X418401D01*
X419901Y126401D01*
X422199D01*
X422300Y126300D01*
G01X412600Y124100D02*
X414101D01*
X414902Y124901D01*
G01X410492Y128601D02*
X410205Y128314D01*
X408019D01*
X407732Y128601D01*
G01X416402Y148361D02*
Y148498D01*
X415100Y149800D01*
G01X419402Y145601D02*
X418951Y145150D01*
X418073D01*
X416023Y143100D01*
X415700D01*
G01D02*
Y142325D01*
X417484Y140541D01*
X417902D01*
G01X407402Y161241D02*
X407678D01*
X408900Y162463D01*
G01X404642Y161241D02*
X406000Y162599D01*
Y162663D01*
G01X404642Y164001D02*
X405151Y163492D01*
X405171D01*
X406000Y162663D01*
G01X407402Y164001D02*
X406764Y163363D01*
X406700D01*
X406000Y162663D01*
G01X410402Y161241D02*
X409840Y161803D01*
X409560D01*
X408900Y162463D01*
G01X419402Y164001D02*
X419400Y163999D01*
X419162D01*
X417785Y162622D01*
G01X416402Y161241D02*
Y161239D01*
X417785Y162622D01*
G01X406792Y177061D02*
Y177300D01*
X408158Y178666D01*
G01X409552Y180061D02*
Y180059D01*
X408159Y178666D01*
X408158D01*
G01X405902Y169061D02*
X406189D01*
X407552Y170424D01*
G01X405902Y171821D02*
X405904Y171819D01*
X406157D01*
X407552Y170424D01*
G01X411902Y171821D02*
Y171755D01*
X410408Y170261D01*
G01X408902Y171821D02*
Y171819D01*
X410408Y170313D01*
Y170261D01*
G01X408902Y169061D02*
X409208D01*
X410408Y170261D01*
G01X419402Y179641D02*
X419340D01*
X418062Y178363D01*
X417900D01*
G01X419340Y170500D02*
X417902Y169062D01*
Y169061D01*
G01X405100Y178500D02*
X405231D01*
X406792Y180061D01*
G01X409552Y183061D02*
X411342Y184851D01*
Y185024D01*
G01X417372Y190561D02*
Y190774D01*
X416139Y192007D01*
G01X417902Y184701D02*
X417797D01*
X416315Y183219D01*
G01X414612Y184561D02*
X414973D01*
X416315Y183219D01*
G01X414612Y193561D02*
Y193534D01*
X416139Y192007D01*
G01X406792Y189061D02*
X405605Y187874D01*
X405102D01*
G01X409552Y186061D02*
X410991Y187500D01*
X412000D01*
G01X417202Y197931D02*
X417569D01*
X418800Y196700D01*
G01X409552Y195061D02*
X412339D01*
X412500Y194900D01*
G01X415252Y204541D02*
X415300Y204589D01*
Y206196D01*
X416353Y207249D01*
G01D02*
X417312D01*
X418072Y206489D01*
Y206491D01*
G01X423912Y104569D02*
Y104571D01*
G01X425292Y102171D02*
X423912Y103551D01*
Y104569D01*
G01X423792Y107479D02*
Y107481D01*
G01X430952Y105891D02*
X431212D01*
X434392Y102711D01*
G01X423792Y107481D02*
Y109849D01*
X423422Y110219D01*
Y110221D01*
G01X419596Y113463D02*
X422838Y110221D01*
X423422D01*
G01X430302Y112098D02*
X432945D01*
X433282Y111761D01*
G01X430302Y112098D02*
X430952Y111448D01*
Y108891D01*
G01X433282Y111761D02*
X435562D01*
X436022Y112221D01*
G01X431188Y116105D02*
X430838D01*
X429902Y115169D01*
Y114321D01*
G01X432802Y114491D02*
X431188Y116105D01*
G01X423372Y119601D02*
X424150Y118823D01*
X425200D01*
G01X426162Y110711D02*
Y110753D01*
X427500Y112091D01*
G01X428942Y110771D02*
X428820D01*
X427500Y112091D01*
G01X432802Y132211D02*
X434289D01*
X434700Y131800D01*
G01X424982Y126500D02*
Y126082D01*
X423902Y125002D01*
Y124901D01*
G01X432732Y135001D02*
Y136708D01*
X432542Y136898D01*
G01X432532Y124061D02*
X432509D01*
X431509Y125061D01*
Y126056D01*
X431504Y126061D01*
G01X433282Y129481D02*
X433881Y128882D01*
X434018D01*
X434700Y128200D01*
G01X433282Y126731D02*
X432612Y126061D01*
X431504D01*
G01X420902Y137781D02*
X420900D01*
X419618Y139063D01*
X419501D01*
X419500Y139064D01*
X419499D01*
G01X434612Y137011D02*
X434499Y136898D01*
X432542D01*
G01X432732Y139021D02*
Y139019D01*
X432653Y138940D01*
Y137009D01*
X432542Y136898D01*
G01X433282Y147211D02*
X436022Y147571D01*
G01X433282Y144461D02*
X435004Y142110D01*
G01X432532Y141791D02*
X435004Y142110D01*
G01X426902Y140541D02*
X428117Y141756D01*
X428363D01*
G01X426900Y160040D02*
X426880Y160060D01*
X426631D01*
X425450Y161241D01*
X425402D01*
G01X433282Y162181D02*
X432664Y161563D01*
X431352D01*
X430542Y160753D01*
G01X432532Y159511D02*
X431784D01*
X430542Y160753D01*
G01X432802Y167671D02*
Y167669D01*
X433282Y167189D01*
Y164941D01*
G01X430600Y164513D02*
X431936D01*
X432204Y164781D01*
X433122D01*
X433282Y164941D01*
G01X426000Y167370D02*
Y168160D01*
X426902Y169061D01*
G01X432732Y170451D02*
Y170281D01*
X435453Y167560D01*
G01X433282Y182671D02*
Y182669D01*
X433643D01*
X435105Y181207D01*
G01X433282Y179911D02*
Y179909D01*
X433807D01*
X435105Y181207D01*
G01X434612Y172471D02*
Y172469D01*
X432712D01*
G01X432732Y174481D02*
Y174479D01*
G01X420902Y171821D02*
X421697Y172616D01*
Y174049D01*
G01X432532Y177241D02*
Y174679D01*
X432732Y174479D01*
G01D02*
Y172489D01*
X432712Y172469D01*
G01X423910Y175700D02*
X425091Y176881D01*
X425402D01*
G01X432802Y185401D02*
Y185399D01*
X434700D01*
X434702Y185397D01*
X435453D01*
G01X432732Y188181D02*
Y188143D01*
X435453Y185422D01*
Y185397D01*
G01X423800Y196500D02*
X424245D01*
X425362Y197617D01*
Y197691D01*
G01X436022Y197261D02*
X434082D01*
X433842Y197021D01*
G01X423902Y184701D02*
X422053Y186550D01*
X421848D01*
G01X429902Y184701D02*
X428703Y185900D01*
X428400D01*
G01X430142Y199771D02*
X430272D01*
X432152Y197891D01*
G01D02*
X432972D01*
X433842Y197021D01*
G01X419942Y198441D02*
Y197842D01*
X418800Y196700D01*
G01X425402Y192521D02*
X423966Y191085D01*
Y190846D01*
G01X422692Y198441D02*
X422634D01*
X421253Y199822D01*
G01X424472Y206491D02*
Y208538D01*
X425458Y209524D01*
X425642D01*
G01X425482Y202551D02*
Y203570D01*
X426311Y204399D01*
G01X447200Y119800D02*
X446341D01*
X443567Y122574D01*
X443517D01*
X442492Y123599D01*
Y123791D01*
X441332Y124951D01*
G01X444900Y117600D02*
X443940Y118560D01*
X442040D01*
X441332Y119268D01*
Y119281D01*
G01X437592Y109111D02*
X440792D01*
G01X438932Y129971D02*
X436142D01*
X436022Y129851D01*
G01X434700Y131800D02*
X436022Y130478D01*
Y129851D01*
G01X437392Y123941D02*
X439019D01*
X439275Y124197D01*
G01X441332Y149071D02*
X441603Y148800D01*
X443300D01*
X443400Y148900D01*
G01X438932Y147701D02*
Y147699D01*
X437490Y146257D01*
X437398D01*
G01X436022Y147571D02*
Y147569D01*
X437334Y146257D01*
X437398D01*
G01X441332Y142671D02*
X441761Y143100D01*
X441786D01*
X443443Y144757D01*
G01X437392Y141671D02*
X435004Y142110D01*
G01X437392Y159391D02*
Y159389D01*
X439020D01*
X439276Y159645D01*
G01X441332Y160401D02*
Y160399D01*
X440030D01*
X439276Y159645D01*
G01X439592Y175461D02*
X439590Y175459D01*
X435762D01*
X435442Y175139D01*
G01D02*
X434482Y176099D01*
Y177021D01*
G01X435442Y175139D02*
Y175141D01*
G01X434392Y205951D02*
Y207302D01*
X436957Y209867D01*
G01X434392Y202751D02*
Y205951D01*
G01X508859Y246430D02*
Y251206D01*
X507817Y252248D01*
G01X510040Y278766D02*
Y275096D01*
X509244Y274300D01*
Y272796D01*
G01X513582Y38966D02*
Y32989D01*
X513005Y32412D01*
G01X529000Y215500D02*
X523800D01*
G01D02*
Y218100D01*
X522500Y219400D01*
G01X523032Y246430D02*
Y249768D01*
X521800Y251000D01*
Y252875D01*
G01X515945Y246430D02*
Y251545D01*
X516600Y252200D01*
G01X517126Y278766D02*
Y273521D01*
X516727Y273122D01*
G01X519488Y278766D02*
Y275442D01*
X521790Y273140D01*
G01X531299Y6630D02*
Y10256D01*
X532500Y11457D01*
Y13407D01*
G01X534500Y210300D02*
X540800D01*
X543274Y212774D01*
G01X535210Y218348D02*
X534348D01*
X531500Y215500D01*
X529000D01*
G01X535210Y226222D02*
X535200Y226232D01*
Y230400D01*
G01D02*
Y234100D01*
G01X531500Y237200D02*
X535200D01*
X535300Y237100D01*
G01D02*
Y234200D01*
X535200Y234100D01*
G01X539567Y246430D02*
Y250967D01*
X540900Y252300D01*
G01X537205Y246430D02*
Y250587D01*
X535192Y252600D01*
X535098D01*
G01X530118Y246430D02*
Y249382D01*
X527400Y252100D01*
G01X533662Y278766D02*
Y275493D01*
X534905Y274250D01*
Y273097D01*
G01X526575Y278766D02*
Y275380D01*
X528330Y273625D01*
Y273140D01*
G01X552559Y6630D02*
Y10846D01*
X553720Y12007D01*
Y12297D01*
G01X545472Y6630D02*
Y9879D01*
X547500Y11907D01*
Y12507D01*
G01X556102Y38966D02*
Y36059D01*
X553250Y33207D01*
G01X549015Y38966D02*
Y35422D01*
X547306Y33713D01*
Y33134D01*
G01X546710Y218348D02*
Y216210D01*
X543274Y212774D01*
G01X546710Y224254D02*
X548890D01*
X550836Y226200D01*
X550860D01*
G01D02*
X551360Y226700D01*
X554500D01*
G01D02*
Y223700D01*
G01X546710Y220316D02*
X550029D01*
X550915Y219430D01*
G01X554500Y220700D02*
X553230Y219430D01*
X550915D01*
G01X553740Y246430D02*
Y251760D01*
X553485Y252015D01*
Y252332D01*
G01X546654Y246430D02*
Y251446D01*
X545500Y252600D01*
G01X558464Y38966D02*
X558463Y38965D01*
Y35436D01*
X560635Y33264D01*
G01X565551Y38966D02*
Y33368D01*
X565470Y33287D01*
G01X557900Y223700D02*
X560000D01*
X561000Y222700D01*
G01X557900Y220700D02*
X560030D01*
X560130Y220600D01*
X562500D01*
X564200Y222300D01*
Y224000D01*
G01X575000Y246430D02*
Y249500D01*
X572300Y252200D01*
X572150D01*
G01X567914Y246430D02*
Y249800D01*
X566300Y251414D01*
Y251966D01*
X566151Y252115D01*
G01X560827Y246430D02*
Y252231D01*
X560555Y252503D01*
G01X571457Y278766D02*
Y275683D01*
X572600Y274540D01*
Y273300D01*
X572700Y273200D01*
Y273100D01*
G01X564370Y278766D02*
Y275329D01*
X565700Y273999D01*
Y273050D01*
G01X583267Y6630D02*
Y10254D01*
X585280Y12267D01*
G01X572638Y38966D02*
Y35269D01*
X573242Y34665D01*
Y32462D01*
G01X586811Y38966D02*
Y34601D01*
X585550Y33340D01*
G01X579724Y38966D02*
Y33831D01*
X579100Y33207D01*
G01X586800Y213200D02*
X585850Y212250D01*
Y204150D01*
X586655Y203345D01*
Y202450D01*
G01X577362Y246430D02*
Y250762D01*
X578800Y252200D01*
G01X578544Y278766D02*
Y273855D01*
X577636Y272947D01*
G01X603346Y38966D02*
Y38940D01*
G01X632000Y202350D02*
X624202D01*
X623752Y201900D01*
X620695D01*
X617200Y205395D01*
Y208000D01*
G01X714000Y118500D02*
X710500Y115000D01*
Y95030D01*
X702270Y86800D01*
X644500D01*
X642823Y88477D01*
G01X675393Y6630D02*
Y11760D01*
X675990Y12357D01*
G01X676575Y38966D02*
Y33872D01*
X675970Y33267D01*
G01X678937Y38966D02*
Y35683D01*
X681280Y33340D01*
G01X675839Y166000D02*
X671100D01*
G01X667200Y161000D02*
Y164500D01*
X667500Y164800D01*
G01X667300Y158000D02*
X667200Y158100D01*
Y161000D01*
G01X667500Y164800D02*
X669400D01*
X670600Y166000D01*
X671100D01*
G01X674213Y246430D02*
Y249791D01*
X674636Y250214D01*
Y252406D01*
G01X667126Y246430D02*
Y249346D01*
X669930Y252150D01*
G01X670670Y278766D02*
Y275560D01*
X668000Y272890D01*
G01X677756Y278766D02*
Y275256D01*
X675600Y273100D01*
X675400D01*
G01X680118Y278766D02*
Y273482D01*
X680400Y273200D01*
Y273100D01*
G01X696653Y6630D02*
Y11054D01*
X694200Y13507D01*
G01X689567Y6630D02*
Y10420D01*
X688252Y11735D01*
Y11789D01*
X687602Y12439D01*
G01X682480Y6630D02*
Y9697D01*
X681280Y10897D01*
Y12457D01*
G01X686023Y38966D02*
Y35204D01*
X687900Y33327D01*
G01X693110Y38966D02*
Y33697D01*
X693700Y33107D01*
G01X688386Y246430D02*
Y251716D01*
X688720Y252050D01*
Y252090D01*
G01X681299Y246430D02*
Y251899D01*
X681900Y252500D01*
G01X695473Y246430D02*
X695474Y246431D01*
Y250596D01*
X693860Y252210D01*
G01X687205Y278766D02*
Y273366D01*
X687682Y272889D01*
G01X694292Y278766D02*
Y274308D01*
X695500Y273100D01*
G01X706102Y6630D02*
Y12139D01*
X706360Y12397D01*
G01X699015Y6630D02*
Y11994D01*
X699503Y12482D01*
G01X700197Y38966D02*
Y34083D01*
X700940Y33340D01*
G01X707283Y38966D02*
Y33459D01*
X707157Y33333D01*
G01X714000Y67800D02*
X712100D01*
X711000Y66700D01*
G01X704922Y246430D02*
Y249724D01*
X707490Y252292D01*
Y252310D01*
G01X697835Y246430D02*
Y250265D01*
X699800Y252230D01*
G01X701378Y278766D02*
Y275219D01*
X700300Y274141D01*
Y273100D01*
G01X708465Y278766D02*
Y275206D01*
X706900Y273641D01*
Y273000D01*
G01X727362Y6630D02*
Y10327D01*
X725530Y12159D01*
Y12507D01*
G01X720275Y6630D02*
Y10192D01*
X719110Y11357D01*
Y12347D01*
G01X713189Y6630D02*
Y10896D01*
X714000Y11707D01*
Y12407D01*
G01X714370Y38966D02*
Y35260D01*
X712450Y33340D01*
G01X723819Y38966D02*
Y35888D01*
X725653Y34054D01*
Y32654D01*
G01X716732Y38966D02*
Y34725D01*
X718350Y33107D01*
G01X727403Y67865D02*
X724735D01*
X723100Y69500D01*
X721000D01*
G01X717000Y67700D02*
X714100D01*
X714000Y67800D01*
G01X717000Y67700D02*
X719200D01*
X721000Y69500D01*
G01X721200Y137000D02*
X727400D01*
X727800Y136600D01*
G01X725000Y210300D02*
X728000D01*
G01X725000D02*
X722000D01*
G01D02*
X721380Y209680D01*
Y202645D01*
G01X718400Y213500D02*
Y210300D01*
X718500Y210200D01*
G01Y217300D02*
X718400Y217200D01*
Y213500D01*
G01X722000Y213700D02*
Y217300D01*
G01D02*
X718500D01*
G01X726181Y246430D02*
Y252342D01*
X725950Y252573D01*
G01X719095Y246430D02*
Y249895D01*
X721375Y252175D01*
X721395D01*
G01X716733Y246430D02*
Y252185D01*
X716737Y252189D01*
G01X712008Y246430D02*
Y252298D01*
X712350Y252640D01*
G01X715551Y278766D02*
Y274175D01*
X716737Y272989D01*
G01X722638Y278766D02*
Y274475D01*
X721395Y273232D01*
Y273100D01*
G01X734449Y6630D02*
X734400Y6679D01*
Y9977D01*
X732110Y12267D01*
G01X737300Y12307D02*
X736811Y11818D01*
Y6630D01*
G01X737992Y38966D02*
Y33589D01*
X738487Y33094D01*
G01X730905Y38966D02*
Y35909D01*
X733474Y33340D01*
G01X744700Y69700D02*
X744200Y70200D01*
X740300D01*
G01D02*
X739200D01*
X736865Y67865D01*
X735277D01*
G01X741500Y86700D02*
Y85178D01*
X739911Y83589D01*
G01X735277Y79365D02*
Y80477D01*
X736300Y81500D01*
X737822D01*
X739911Y83589D01*
G01X729371Y79365D02*
Y82000D01*
X728200Y83171D01*
Y84800D01*
G01X728000Y88400D02*
Y85000D01*
X728200Y84800D01*
G01X731000Y88400D02*
X731100D01*
X734200Y85300D01*
G01X733309Y79365D02*
X733340Y79396D01*
Y82340D01*
X734200Y83200D01*
Y85300D01*
G01X728000Y91800D02*
X726800Y93000D01*
Y95500D01*
G01X731000Y91800D02*
Y94100D01*
X730200Y94900D01*
G01X741500Y182700D02*
X738500D01*
G01X741500D02*
Y184680D01*
X740680Y185500D01*
Y187440D01*
G01X735500Y182700D02*
X733200D01*
X731900Y184000D01*
G01X738500Y182700D02*
X735500D01*
G01X736500Y174500D02*
X734300Y172300D01*
X733500D01*
G01X738500Y179300D02*
Y176500D01*
X736500Y174500D01*
G01X730200Y169000D02*
Y172000D01*
G01D02*
X730500Y172300D01*
X733500D01*
G01X731900Y184000D02*
Y186500D01*
X732840Y187440D01*
X733320D01*
G01X740500Y197800D02*
X737000D01*
G01X733000Y197525D02*
X728740D01*
G01X733000D02*
X736725D01*
X737000Y197800D01*
G01X728740Y190000D02*
X729705D01*
X732265Y192560D01*
X733320D01*
G01X737000Y197800D02*
Y193500D01*
X736060Y192560D01*
X733320D01*
G01X728740Y202645D02*
Y206500D01*
G01X728000Y210300D02*
X728740Y209560D01*
Y206500D01*
G01X740355Y246430D02*
Y252200D01*
X739755Y252800D01*
X739750D01*
G01X733268Y246430D02*
Y249791D01*
X734937Y251460D01*
Y253100D01*
G01X729725Y278766D02*
Y275206D01*
X727800Y273281D01*
Y272800D01*
G01X736811Y278766D02*
Y275511D01*
X734510Y273210D01*
Y273110D01*
G01X739173Y278766D02*
Y273478D01*
X739838Y272813D01*
G01X743897Y6630D02*
Y11053D01*
X745100Y12256D01*
G01X745078Y38966D02*
Y33285D01*
X744800Y33007D01*
G01X744700Y69700D02*
Y68300D01*
X742500Y66100D01*
G01X747441Y246430D02*
Y250641D01*
X749000Y252200D01*
G01X746260Y278766D02*
Y273366D01*
X746737Y272889D01*
X-19686Y15748D03*
Y573228D03*
X11500Y68500D03*
X12000Y279000D03*
X45669Y77185D03*
Y172460D03*
X42717Y191732D03*
Y270472D03*
X144000Y67875D03*
Y147125D03*
X200197Y282677D03*
X235630Y75590D03*
Y174016D03*
X298622Y282677D03*
X350197Y231103D03*
X498425Y22798D03*
D03*
X492520Y262598D03*
D03*
X755512D03*
D03*
X761417Y22798D03*
D03*
X816000Y280000D03*
X846455Y15748D03*
Y573228D03*
G54D140*
G01X91400Y250800D02*
X93400Y252800D01*
X94420D01*
G01X99420D02*
Y252420D01*
X95600Y248600D01*
Y248200D01*
X93800Y246400D01*
G01X106700Y259800D02*
X108200Y258300D01*
X109500D01*
G01X107900Y254300D02*
Y256700D01*
X109500Y258300D01*
G01X191500Y94100D02*
X191675Y93925D01*
Y93236D01*
X192200Y92711D01*
Y90520D01*
X193920Y88800D01*
X194600D01*
G01D02*
X197600D01*
G01X228000Y139700D02*
Y138100D01*
X230264Y135836D01*
X249100D01*
G01D02*
X253427D01*
X260518Y142927D01*
X263581D01*
X266154Y145500D01*
X274800D01*
G01X758100Y144100D02*
X759700Y145700D01*
Y145900D01*
G01X771726Y128600D02*
X776300D01*
G01X759700Y145900D02*
X763300D01*
G01D02*
Y148700D01*
X764500Y149900D01*
G01X766700Y142900D02*
Y141000D01*
X766600Y140900D01*
Y139800D01*
G01X766700Y145900D02*
X767944D01*
X771300Y142544D01*
Y140200D01*
G01X776300Y128600D02*
Y127473D01*
X777573Y126200D01*
X781700D01*
X784500Y129000D01*
X788600D01*
X790015Y130415D01*
Y132549D01*
G01X779500Y148700D02*
X779100Y149100D01*
Y154500D01*
G54D131*
X778850Y243000D03*
X802150D03*
G54D113*
X638000Y215500D03*
G54D104*
X535210Y218348D03*
Y220316D03*
Y222285D03*
Y224254D03*
Y226222D03*
X546710D03*
Y224254D03*
Y222285D03*
Y220316D03*
Y218348D03*
G54D20*
X20000Y116100D03*
Y110900D03*
Y129600D03*
Y124400D03*
X72500Y90900D03*
Y96100D03*
X72400Y198000D03*
X77400D03*
X72400Y203200D03*
X77400D03*
X108550Y146600D03*
Y141400D03*
X177000Y134900D03*
Y140100D03*
X204000Y197400D03*
X198200Y197401D03*
X204000Y202600D03*
X198200Y202601D03*
X198500Y258600D03*
Y253400D03*
X255000Y225600D03*
Y220400D03*
X287500Y160100D03*
Y154900D03*
X507000Y224600D03*
Y219400D03*
X522500Y224600D03*
Y219400D03*
X605300Y235600D03*
Y230400D03*
X740000Y238600D03*
Y233400D03*
X749800Y105700D03*
Y110900D03*
G54D122*
X738017Y124213D03*
Y143313D03*
X752191Y124213D03*
Y143313D03*
G54D11*
G01X296811Y263386D02*
X288406D01*
X286393Y265399D01*
X278824D01*
X276811Y263386D01*
X-11600Y33200D03*
X18400Y76200D03*
X24000Y280000D03*
X325500Y229000D03*
X394100Y57700D03*
X468000Y171500D03*
X799500Y10500D03*
X833100Y564800D03*
X842500Y35000D03*
G54D150*
G01X391152Y195061D02*
X392650Y193563D01*
X392700D01*
G01X417372Y187561D02*
Y187838D01*
X419097Y189563D01*
G01X423102Y204101D02*
X422500Y204703D01*
Y209775D01*
X420975Y211300D01*
G01X437592Y114531D02*
Y114008D01*
X438700Y112900D01*
G01X435442Y116611D02*
X434960Y116129D01*
Y114529D01*
G01X586811Y246430D02*
Y250243D01*
X585667Y251387D01*
Y256467D01*
X589089Y259889D01*
X590837D01*
G01X596260Y246430D02*
Y250593D01*
X597054Y251387D01*
Y258828D01*
X596462Y259420D01*
Y263238D01*
X594500Y265200D01*
G01X597441Y278766D02*
Y268941D01*
X595900Y267400D01*
X593900D01*
X592562Y266062D01*
Y261974D01*
X594536Y260000D01*
X594600D01*
G01X602166Y278766D02*
Y275233D01*
X600550Y273617D01*
Y272150D01*
X601737Y270963D01*
Y263037D01*
X598899Y260199D01*
X598398D01*
G01X599803Y278766D02*
Y274780D01*
X599200Y274177D01*
Y266300D01*
X598300Y265400D01*
G01X592717Y278766D02*
Y274460D01*
X593411Y273766D01*
Y268837D01*
X590700Y266126D01*
Y264833D01*
G01X622244Y38966D02*
Y34228D01*
X622125Y34109D01*
Y29546D01*
X620194Y27615D01*
X619829D01*
X617800Y25586D01*
Y21607D01*
X619600Y19807D01*
X619607D01*
G01X617519Y38966D02*
Y34561D01*
X617019Y34061D01*
Y29826D01*
X614032Y26839D01*
Y21693D01*
X615852Y19873D01*
Y19807D01*
G01X619882Y38966D02*
Y34960D01*
X620775Y34067D01*
Y30106D01*
X619634Y28965D01*
X619027D01*
X616257Y26195D01*
Y25206D01*
X615907Y24856D01*
G01X613977Y278766D02*
Y274024D01*
X614218Y273783D01*
Y272269D01*
X613150Y271201D01*
X613149D01*
X608453Y266505D01*
Y261404D01*
X609868Y259989D01*
X611104D01*
X611706Y259387D01*
G01X612796Y246430D02*
Y249923D01*
X614000Y251127D01*
Y258100D01*
X613566Y258534D01*
Y261425D01*
X613555Y261436D01*
Y262866D01*
X612042Y264379D01*
X611542D01*
X611536Y264385D01*
G01X617520Y246430D02*
Y259299D01*
X617507Y259312D01*
Y261710D01*
X617305Y261912D01*
Y263021D01*
X615537Y264789D01*
G01X615158Y246430D02*
Y250126D01*
X615632Y250600D01*
Y259600D01*
X615532Y259700D01*
G01X616339Y278766D02*
Y271189D01*
X619180Y268348D01*
Y265380D01*
X619100Y265300D01*
G01X618701Y278766D02*
Y274928D01*
X618462Y274689D01*
Y272171D01*
X621055Y269578D01*
Y261762D01*
X619382Y260089D01*
G01X621063Y6630D02*
Y12544D01*
X621532Y13013D01*
Y23341D01*
X620009Y24864D01*
X619730D01*
G01X628149Y6630D02*
Y14058D01*
X629132Y15041D01*
Y23184D01*
X627255Y25061D01*
Y25107D01*
G01X630512Y6630D02*
Y19619D01*
X631000Y20107D01*
G01X625787Y6630D02*
Y11399D01*
X625975Y11587D01*
Y13225D01*
X623482Y15718D01*
Y19957D01*
X623532Y20007D01*
G01X626968Y38966D02*
Y33264D01*
X623505Y29801D01*
Y25157D01*
X623555Y25107D01*
G01X635236Y6630D02*
Y10468D01*
X635475Y10707D01*
Y13225D01*
X632882Y15818D01*
Y23634D01*
X634555Y25307D01*
G01X629330Y38966D02*
Y33137D01*
X625380Y29187D01*
Y21632D01*
X626905Y20107D01*
X627031D01*
X627231Y19907D01*
G01X631693Y38966D02*
Y34228D01*
X631005Y33540D01*
Y25612D01*
X630955Y25562D01*
Y25207D01*
G01X626969Y246430D02*
Y254569D01*
X630432Y258032D01*
Y260100D01*
G01X631693Y246430D02*
Y256193D01*
X633600Y258100D01*
X634900D01*
X636155Y259355D01*
Y263609D01*
X634432Y265332D01*
X634280D01*
G01X624607Y246430D02*
Y254407D01*
X628557Y258357D01*
Y263764D01*
X626832Y265489D01*
X626651D01*
G01X622244Y246430D02*
Y249922D01*
X622932Y250610D01*
Y260188D01*
X622933Y260189D01*
G01X634055Y246430D02*
Y249445D01*
X633162Y250338D01*
Y255149D01*
X634440Y256427D01*
X635427D01*
X638030Y259030D01*
Y260340D01*
X638032Y260342D01*
G01X625788Y278766D02*
Y271338D01*
X624805Y270355D01*
Y262212D01*
X626682Y260335D01*
Y260300D01*
G01X623425Y278766D02*
Y265715D01*
X622899Y265189D01*
G01X628150Y278766D02*
Y273997D01*
X627962Y273809D01*
Y272171D01*
X630455Y269678D01*
Y265400D01*
G01X632874Y278766D02*
Y272852D01*
X632405Y272383D01*
Y262055D01*
X633928Y260532D01*
X633975D01*
X634207Y260300D01*
G01X637598Y6630D02*
Y14207D01*
X634757Y17048D01*
Y20207D01*
G01X639960Y6630D02*
Y11500D01*
X639870Y11590D01*
Y13277D01*
X644276Y17683D01*
Y23940D01*
X642809Y25407D01*
X642646D01*
X642246Y25807D01*
G01X636417Y38966D02*
Y26097D01*
X636430Y26084D01*
Y23686D01*
X636632Y23484D01*
Y22375D01*
X638400Y20607D01*
G01X638779Y38966D02*
Y35786D01*
X638305Y35312D01*
Y25689D01*
X638290Y25674D01*
G01X641141Y38966D02*
Y35646D01*
X640071Y34576D01*
Y30307D01*
X640371Y30007D01*
Y23971D01*
X640382Y23960D01*
Y22530D01*
X642205Y20707D01*
X642451D01*
G01X636418Y246430D02*
Y249618D01*
X636918Y250118D01*
Y253741D01*
X637022Y253845D01*
Y255513D01*
X639905Y258396D01*
Y263617D01*
X638182Y265340D01*
X638090D01*
G01X654134Y6630D02*
Y10616D01*
X654541Y11023D01*
Y19440D01*
X655326Y20225D01*
X655700D01*
G01X651771Y6630D02*
Y10163D01*
X653191Y11583D01*
Y13137D01*
X652200Y14128D01*
Y23207D01*
X653800Y24807D01*
X655184D01*
X655600Y25223D01*
X655602D01*
G01X656496Y6630D02*
Y10123D01*
X655922Y10697D01*
Y14377D01*
X661375Y19830D01*
Y23932D01*
X659400Y25907D01*
G01X661220Y6630D02*
Y10936D01*
X660425Y11731D01*
Y14125D01*
X660293Y14257D01*
Y15800D01*
X662974Y18481D01*
Y20730D01*
X663200Y20956D01*
G01X667126Y38966D02*
Y28733D01*
X664382Y25989D01*
X663218D01*
X663202Y25973D01*
G01X657677Y38966D02*
Y35984D01*
X656108Y34415D01*
X655708D01*
X654700Y33407D01*
Y28751D01*
X657475Y25976D01*
Y22200D01*
X659201Y20474D01*
X659400D01*
G54D141*
G01X306994Y117725D02*
X310180Y120911D01*
X314942D01*
X315342Y121311D01*
G01X309194Y117700D02*
X309192Y117702D01*
Y118791D01*
X310512Y120111D01*
X315840D01*
X319112Y121101D01*
G01X307500Y188000D02*
X309844Y185656D01*
X312404D01*
X312409Y185661D01*
X312704D01*
X316624Y189581D01*
X317112D01*
G01X309700Y187997D02*
X311236Y186461D01*
X312372D01*
X315912Y190001D01*
Y190079D01*
X316614Y190781D01*
X317611D01*
X319011Y189381D01*
X320112D01*
G01X301300Y188700D02*
Y188980D01*
X304070Y191750D01*
X314180D01*
X314181Y191751D01*
X314512D01*
X314513Y191750D01*
X314843D01*
X317132Y194039D01*
Y194131D01*
G01X303480Y189100D02*
Y190028D01*
X304402Y190950D01*
X315175D01*
X317156Y192931D01*
X317630D01*
X318332Y193633D01*
Y196071D01*
X318702Y196441D01*
G01X320992Y112180D02*
Y114189D01*
X321992Y115189D01*
Y116451D01*
G01X319282Y115791D02*
X320200D01*
X320585Y115406D01*
Y114914D01*
X320192Y114521D01*
Y113852D01*
X319640Y113300D01*
X319096D01*
G01X366392Y201181D02*
X367750Y203900D01*
Y219950D01*
X373300Y225500D01*
X374732D01*
X375772Y226540D01*
X376160D01*
X376196Y226576D01*
G01X366262Y204091D02*
X366950Y204779D01*
Y220282D01*
X372968Y226300D01*
X374400D01*
X375241Y227141D01*
Y227531D01*
G01X331658Y212660D02*
X332398Y213400D01*
X333404D01*
X336000Y210800D01*
Y208332D01*
X336932Y207400D01*
Y206948D01*
X338512Y205368D01*
Y204751D01*
G01X338822Y200601D02*
X339712Y204253D01*
Y205300D01*
X337732Y207280D01*
Y207732D01*
X336800Y208664D01*
Y211132D01*
X333736Y214200D01*
X332276D01*
X331616Y214860D01*
G01X344342Y204541D02*
X344742Y204941D01*
Y206226D01*
X344202Y206766D01*
Y208934D01*
X339500Y213636D01*
Y215778D01*
X338898Y216380D01*
X337990D01*
X337341Y215731D01*
G01X341502Y199771D02*
X340502Y202300D01*
Y203760D01*
X342592Y205850D01*
Y205927D01*
X342602Y205937D01*
Y207998D01*
X340600Y210000D01*
X339512D01*
X338967Y209455D01*
G01X338926Y211674D02*
X339800Y210800D01*
X340932D01*
X343402Y208330D01*
Y205528D01*
X341702Y203828D01*
Y202771D01*
G01X361862Y200771D02*
X360862Y204043D01*
Y206794D01*
X361200Y207132D01*
Y211953D01*
X362347Y213100D01*
Y221879D01*
X364575Y224107D01*
Y229015D01*
X364300Y229290D01*
Y229390D01*
G01X362062Y204541D02*
X361662Y204941D01*
Y206462D01*
X362000Y206800D01*
Y211621D01*
X363147Y212768D01*
Y221547D01*
X365375Y223775D01*
Y229015D01*
X365650Y229290D01*
Y229390D01*
G01X337307Y217961D02*
X338088Y217180D01*
X339230D01*
X340300Y216110D01*
Y213968D01*
X345002Y209266D01*
Y207098D01*
X345542Y206558D01*
Y204043D01*
X344132Y200771D01*
G01X377875Y234075D02*
Y234025D01*
X377600Y233750D01*
Y232700D01*
X365450Y220550D01*
Y211554D01*
X363600Y209704D01*
Y206052D01*
X365000Y204652D01*
Y203211D01*
X365182Y203029D01*
Y201945D01*
X364022Y197931D01*
G01X376525Y234075D02*
Y233975D01*
X376800Y233700D01*
Y233032D01*
X364650Y220882D01*
Y211886D01*
X362800Y210036D01*
Y205720D01*
X364200Y204320D01*
Y202749D01*
X363982Y202531D01*
G01X357721Y91779D02*
X355900Y93600D01*
Y99900D01*
X357100Y101100D01*
X359400D01*
X359700Y100800D01*
X360500D01*
X361000Y101300D01*
X362200D01*
X364346Y103446D01*
X365967D01*
X367082Y104561D01*
G01X347593Y210277D02*
Y210247D01*
X348302Y209538D01*
Y207631D01*
X347162Y206491D01*
G01X347664Y212476D02*
X349102Y211038D01*
Y206471D01*
X347315Y204684D01*
X346252Y202531D01*
G01X353385Y212898D02*
X351542Y211055D01*
Y205515D01*
X350982Y204955D01*
Y203700D01*
X352162Y201181D01*
G01X348542Y204091D02*
Y204779D01*
X349942Y206179D01*
Y213058D01*
X348550Y214450D01*
X344002D01*
X343242Y213690D01*
G01X352182Y204101D02*
Y205023D01*
X352342Y205183D01*
Y210613D01*
X352689Y210960D01*
X353341D01*
X353594Y210707D01*
G01X343198Y215910D02*
X343858Y215250D01*
X348882D01*
X350742Y213390D01*
Y205847D01*
X349978Y205083D01*
Y203829D01*
X348662Y201181D01*
G01X357966Y217516D02*
Y216598D01*
X355300Y213932D01*
Y206259D01*
X356242Y205317D01*
Y204751D01*
G01X359827Y216341D02*
X358841D01*
X356100Y213600D01*
Y206591D01*
X357442Y205249D01*
Y204253D01*
X356552Y200601D01*
G01X375142Y107891D02*
Y106126D01*
X373202Y104186D01*
Y101540D01*
X372558Y100896D01*
X370896D01*
X368600Y98600D01*
Y97500D01*
G01X364800Y91200D02*
X366600Y93000D01*
Y97835D01*
X370936Y102171D01*
X372102D01*
G01X361200Y90200D02*
X362934Y91934D01*
Y98638D01*
X364392Y100096D01*
X366490D01*
X369082Y102688D01*
Y104500D01*
X369482Y104900D01*
X370403D01*
X370732Y104571D01*
G01X361200Y97500D02*
X362134Y98434D01*
Y98970D01*
X364060Y100896D01*
X366158D01*
X368282Y103020D01*
Y104832D01*
X370602Y107152D01*
Y107481D01*
G01X368600Y90700D02*
Y90900D01*
X370300Y92600D01*
Y99168D01*
X371228Y100096D01*
X372890D01*
X374932Y102138D01*
Y104121D01*
G01X364874Y98250D02*
X365850D01*
X370971Y103371D01*
X371230D01*
X373012Y105153D01*
Y106131D01*
G01X357900Y99200D02*
X358200Y99500D01*
X360500D01*
X361500Y100500D01*
X362532D01*
X364203Y102171D01*
X365702D01*
G01X364702Y106111D02*
X364626Y106035D01*
X362803D01*
G01X367102Y107481D02*
X365965D01*
X365316Y108130D01*
G01X369450Y212040D02*
Y210850D01*
X372396Y207904D01*
Y202645D01*
X372302Y202551D01*
G01X369580Y218800D02*
X371090Y217290D01*
Y210342D01*
X373196Y208236D01*
Y206187D01*
X373962Y205421D01*
Y204751D01*
G01X358382Y212427D02*
X356900Y210945D01*
Y207000D01*
X358100Y205800D01*
X359422Y202771D01*
G01X359222Y206491D02*
X358541D01*
X357700Y207332D01*
Y209422D01*
X358498Y210220D01*
G01X379500Y83302D02*
X381250Y85052D01*
Y97067D01*
X385612Y101429D01*
Y103600D01*
X386012Y104000D01*
Y105059D01*
X384832Y106239D01*
Y107481D01*
G01X387100Y83500D02*
Y83600D01*
X389000Y85500D01*
Y97600D01*
X389832Y98432D01*
Y102171D01*
G01X371900Y85400D02*
X373800Y87300D01*
Y97900D01*
X376796Y100896D01*
X378228D01*
X378872Y101540D01*
Y103719D01*
X380099Y104946D01*
X380127D01*
X380976Y105795D01*
Y107527D01*
X380442Y108061D01*
G01X375800Y83500D02*
X377600Y85300D01*
Y98004D01*
X380472Y100876D01*
Y101872D01*
X382422Y103822D01*
Y106111D01*
G01X383350Y83350D02*
X385300Y85300D01*
Y97500D01*
X387932Y100132D01*
Y103134D01*
X388462Y103664D01*
Y104571D01*
G01X384812Y104561D02*
Y101761D01*
X380450Y97399D01*
Y91600D01*
X379500Y90650D01*
Y90600D01*
G01X388332Y107481D02*
Y107479D01*
X386900Y106047D01*
Y100600D01*
X383450Y97150D01*
Y90500D01*
G01X387200D02*
Y98200D01*
X388732Y99732D01*
Y102802D01*
X389942Y104012D01*
Y105329D01*
X390742Y106129D01*
Y106131D01*
G01X375800Y90500D02*
Y97336D01*
X379672Y101208D01*
Y102821D01*
X380762Y103911D01*
G01X371950Y92500D02*
Y98024D01*
X376342Y102416D01*
Y106359D01*
X377296Y107313D01*
X377892D01*
X379782Y109203D01*
Y110771D01*
G01X381600Y119900D02*
Y120200D01*
X383700Y122300D01*
Y123529D01*
X384272Y124101D01*
G01X387032Y121101D02*
Y120839D01*
X385721Y119528D01*
G01X384272Y115101D02*
X385200Y114173D01*
Y113137D01*
G01X382596Y108600D02*
X382473D01*
X381300Y109773D01*
Y111100D01*
X380412Y111988D01*
Y115401D01*
X379212Y116601D01*
G01X381900Y113000D02*
X383000Y114100D01*
Y116829D01*
X384272Y118101D01*
G01X385600Y116500D02*
X385700Y116400D01*
X385733D01*
X387032Y115101D01*
G01X381500Y123200D02*
X380901Y122601D01*
X379212D01*
G01X384272Y127101D02*
Y126776D01*
X385479Y125569D01*
G01X379212Y125601D02*
X380038Y126427D01*
X381600D01*
G01X387032Y124101D02*
X385523Y122592D01*
Y122532D01*
G01X384740Y180080D02*
X384700Y180040D01*
Y179900D01*
X383361Y178561D01*
X383332D01*
G01X381800Y183300D02*
X381900D01*
X383332Y181868D01*
Y181561D01*
G01X378272Y183061D02*
X378879D01*
X381720Y180220D01*
G01X380540Y177370D02*
X380460Y177450D01*
Y177873D01*
X378272Y180061D01*
G01X384708Y188910D02*
Y188192D01*
X385339Y187561D01*
X386092D01*
G01X381460Y195610D02*
Y195433D01*
X383332Y193561D01*
G01X379750Y213500D02*
X379034Y212784D01*
Y205656D01*
X378382Y205004D01*
Y198471D01*
X378962Y197891D01*
G01X372800Y221600D02*
X374500Y219900D01*
Y209900D01*
X375500Y208900D01*
Y206212D01*
X375962Y205750D01*
Y203813D01*
X375496Y203347D01*
Y198445D01*
X374942Y197891D01*
G01X384390Y196470D02*
Y196310D01*
X384370Y196290D01*
Y195283D01*
X386092Y193561D01*
G01X384600Y186100D02*
Y186023D01*
X386062Y184561D01*
X386092D01*
G01X372700Y213700D02*
Y210400D01*
X374400Y208700D01*
Y206115D01*
X375162Y205353D01*
Y204145D01*
X374282Y203265D01*
Y200601D01*
G01X382750Y229000D02*
X384300Y227450D01*
Y211000D01*
X381522Y208222D01*
Y205737D01*
X381792Y205467D01*
Y202611D01*
X381712Y202531D01*
G01X379700Y219200D02*
X381250Y217650D01*
Y211350D01*
X379834Y209934D01*
Y204583D01*
X379792Y204541D01*
G01X376300Y216200D02*
X377900Y214600D01*
Y210532D01*
X378134Y210298D01*
Y205888D01*
X377152Y204906D01*
Y202771D01*
G01X385900Y218400D02*
X386322Y217978D01*
Y202481D01*
X387622Y201181D01*
G01X376300Y211000D02*
X377334Y209966D01*
Y206873D01*
X376952Y206491D01*
G01X382600Y222600D02*
Y210900D01*
X380722Y209022D01*
Y205309D01*
X380992Y205039D01*
Y203859D01*
X379582Y202449D01*
Y200771D01*
G01X385947Y226500D02*
Y226053D01*
X387500Y224500D01*
Y207832D01*
X387122Y207454D01*
Y204621D01*
X387642Y204101D01*
G01X397300Y89168D02*
X398800Y90668D01*
Y99204D01*
X400628Y101032D01*
Y101635D01*
X401162Y102169D01*
Y102171D01*
G01X390700Y89300D02*
Y89400D01*
X392400Y91100D01*
Y99900D01*
X393396Y100896D01*
X395958D01*
X396602Y101540D01*
Y102802D01*
X396300Y103104D01*
Y105191D01*
X396502Y105393D01*
Y106498D01*
X395502Y107498D01*
Y108891D01*
G01X400400Y98500D02*
X400500Y98600D01*
Y99450D01*
X402262Y101212D01*
Y104281D01*
X402542Y104561D01*
G01X394100Y99000D02*
X395194D01*
X397682Y101488D01*
Y103013D01*
X397282Y103413D01*
Y104409D01*
X398172Y105299D01*
Y108061D01*
G01X400400Y92200D02*
X402000Y93800D01*
Y99600D01*
X403442Y101042D01*
Y103763D01*
X403742Y104063D01*
Y105059D01*
X402562Y106239D01*
Y107481D01*
G01X394100Y91400D02*
X395550Y92850D01*
Y97750D01*
X397150Y99350D01*
Y99818D01*
X398482Y101150D01*
Y103911D01*
G01X390750Y96500D02*
X390932Y96682D01*
Y104089D01*
X392734Y105891D01*
X395302D01*
G01X397100Y96600D02*
X398000Y97500D01*
Y99536D01*
X399828Y101364D01*
Y105787D01*
X400152Y106111D01*
G01X394852Y116601D02*
X396250Y117999D01*
X396251D01*
G01X402672Y115101D02*
X401749Y114178D01*
Y112418D01*
G01X399912Y118101D02*
Y118389D01*
X401159Y119636D01*
G01X399912Y115101D02*
X401353Y116542D01*
Y116562D01*
G01X393331Y118043D02*
X393278Y117990D01*
Y117900D01*
X392092Y116714D01*
Y116601D01*
G01Y113601D02*
X393351Y114860D01*
Y115107D01*
G01X397650Y115500D02*
X397513Y115363D01*
X396614D01*
X394852Y113601D01*
G01X392092Y125601D02*
X390979D01*
X389914Y124536D01*
G01X396700Y128000D02*
Y127800D01*
X394852Y125952D01*
Y125601D01*
G01X398500Y125604D02*
X398604Y125708D01*
Y125793D01*
X399912Y127101D01*
G01X401500Y125600D02*
Y125929D01*
X402672Y127101D01*
G01X392092Y122601D02*
X392101D01*
X393482Y123982D01*
G01X399912Y124101D02*
X399798D01*
X398512Y122815D01*
G01X403600Y180200D02*
X402239Y181561D01*
X401732D01*
G01X391152Y183061D02*
X392527Y181686D01*
X392599D01*
G01X398972Y181561D02*
Y181672D01*
X400100Y182800D01*
Y182814D01*
X400252Y182966D01*
G01X391152Y192061D02*
X391039D01*
X389500Y193600D01*
G01X403022Y192094D02*
Y191851D01*
X401732Y190561D01*
G01X402967Y195005D02*
Y194796D01*
X401732Y193561D01*
G01X391152Y186061D02*
Y186009D01*
X392624Y184537D01*
G01X403600Y182400D02*
Y182693D01*
X401732Y184561D01*
G01X395600Y184100D02*
X394900D01*
X393912Y183112D01*
Y183061D01*
G01X395600Y190300D02*
X395500Y190200D01*
X395052D01*
X393912Y189061D01*
G01Y192061D02*
X392600Y190749D01*
Y190600D01*
G01X396200Y194700D02*
X396100D01*
X395800Y194400D01*
X394573D01*
X393912Y195061D01*
G01X397307Y186607D02*
X398018D01*
X398972Y187561D01*
G01X397805Y192061D02*
X397830Y192086D01*
Y192102D01*
X398972Y193244D01*
Y193561D01*
G01Y184561D02*
X400257Y185846D01*
Y186055D01*
X400301Y186099D01*
G01X399700Y225000D02*
X401500Y223200D01*
Y213100D01*
X397050Y208650D01*
Y205320D01*
X397522Y204848D01*
Y204541D01*
G01X404400Y228600D02*
X402700Y226900D01*
Y205069D01*
X401722Y204091D01*
G01X389022Y206491D02*
X389200Y206669D01*
Y221200D01*
X390800Y222800D01*
Y228650D01*
X389150Y230300D01*
G01X394682Y206491D02*
Y208582D01*
X397600Y211500D01*
Y222400D01*
X395600Y224400D01*
G01X391950Y220800D02*
X390100Y218950D01*
Y208500D01*
X390492Y208108D01*
Y204167D01*
X392002Y202657D01*
Y200601D01*
G01X392100Y213700D02*
X390900Y212500D01*
Y208832D01*
X391292Y208440D01*
Y205151D01*
X391692Y204751D01*
G01X395700Y217000D02*
X393900Y215200D01*
Y210500D01*
X393300Y209900D01*
Y204353D01*
X394882Y202771D01*
G01X399700Y216400D02*
Y212432D01*
X396250Y208982D01*
Y203725D01*
X397312Y202663D01*
Y200771D01*
G01X404400Y222300D02*
X404107Y222007D01*
Y204674D01*
X401842Y202409D01*
Y201181D01*
G01X389100Y224000D02*
X388400Y223300D01*
Y207600D01*
X387922Y207122D01*
Y205860D01*
X389342Y204440D01*
Y203231D01*
X390022Y202551D01*
G01X419452Y204091D02*
Y205008D01*
X419972Y205528D01*
Y208524D01*
X418790Y209706D01*
Y211350D01*
X420540Y213100D01*
X422200D01*
X424050Y214950D01*
Y223882D01*
X415357Y232575D01*
X408725D01*
X408450Y232850D01*
X408350D01*
G01X417172Y202531D02*
Y203860D01*
X419172Y205860D01*
Y208192D01*
X417990Y209374D01*
Y211682D01*
X420208Y213900D01*
X421868D01*
X423250Y215282D01*
Y223550D01*
X415025Y231775D01*
X408725D01*
X408450Y231500D01*
X408350D01*
G01X403726Y83826D02*
X405500Y85600D01*
Y93900D01*
X405300Y94100D01*
Y102772D01*
X406182Y103654D01*
Y104571D01*
G01X413022Y105891D02*
X412382Y105251D01*
Y103219D01*
X411200Y102037D01*
Y99000D01*
X412900Y97300D01*
Y87200D01*
X411300Y85600D01*
G01X407500Y84000D02*
X409200Y85700D01*
Y102939D01*
X410382Y104121D01*
G01X415902Y108061D02*
X414322Y103800D01*
Y102468D01*
X414750Y102040D01*
Y98128D01*
X414622Y98000D01*
G01X414722Y90250D02*
X416300Y91828D01*
Y98716D01*
X415550Y99466D01*
Y102372D01*
X415122Y102800D01*
Y103622D01*
X415411Y103911D01*
X416212D01*
G01X411000Y92100D02*
X410400Y92700D01*
Y102369D01*
X411582Y103551D01*
Y106282D01*
X413222Y107922D01*
Y108891D01*
G01X418400Y98150D02*
X417999D01*
X416350Y99799D01*
Y101781D01*
X417882Y103313D01*
Y106111D01*
G01X407400Y91000D02*
Y96800D01*
X406100Y98100D01*
Y102440D01*
X407106Y103446D01*
X407946D01*
X410200Y105700D01*
X410592Y107891D01*
G01X403700Y90200D02*
X404300Y90800D01*
Y103400D01*
X404600Y103700D01*
Y106019D01*
X406062Y107481D01*
G01X407732Y113601D02*
X407791D01*
X409100Y114910D01*
X409110D01*
G01X410492Y113601D02*
X409852D01*
X409711Y113460D01*
X409560D01*
X408501Y112401D01*
X407234D01*
X405200Y114435D01*
Y115343D01*
G01X407732Y116601D02*
X409196Y118065D01*
Y118195D01*
G01X402672Y118101D02*
X404094D01*
X404500Y118507D01*
X404529D01*
G01X410492Y116601D02*
X411399D01*
X412287Y115713D01*
X412462D01*
G01X416000Y135983D02*
Y136683D01*
X414902Y137781D01*
G01X405900Y121700D02*
X405073D01*
X402672Y124101D01*
G01X415000Y131400D02*
X414723D01*
X413402Y132721D01*
G01X404900Y124600D02*
X405733D01*
X407732Y122601D01*
G01X418500Y128200D02*
X416739Y129961D01*
X416402D01*
G01X410492Y131601D02*
Y131600D01*
X408956Y130064D01*
G01X415100Y127900D02*
Y128200D01*
X413402Y129898D01*
Y129961D01*
G01X416402Y145601D02*
X417900Y146900D01*
G01X420902Y140541D02*
X419959D01*
X418000Y142500D01*
G01X411900Y146800D02*
Y146859D01*
X413402Y148361D01*
G01X414902Y140541D02*
X413461Y139100D01*
X413300D01*
G01X408800Y147000D02*
X410199Y145601D01*
X410402D01*
G01X414900Y147000D02*
X414801D01*
X413402Y145601D01*
G01X417902Y137781D02*
X419283Y136400D01*
X419500D01*
G01X411902Y140541D02*
X413400Y142040D01*
Y142700D01*
G01X413402Y161241D02*
X414761Y162600D01*
X414800D01*
G01X418439Y167118D02*
X416845D01*
X414902Y169061D01*
G01X414572Y165913D02*
Y165831D01*
X416402Y164001D01*
G01X410402D02*
X410499D01*
X411800Y162700D01*
G01X413402Y164001D02*
X411671Y165732D01*
X411356D01*
G01X417902Y171821D02*
X418087D01*
X419453Y173187D01*
G01X411902Y169061D02*
X413264Y170423D01*
X413265D01*
G01X414960Y178130D02*
X414651D01*
X413402Y176881D01*
G01X414902Y171821D02*
X416400Y170300D01*
G01X413402Y179641D02*
X413134D01*
X411553Y181222D01*
G01X411260Y178090D02*
X410715D01*
X409686Y177061D01*
X409552D01*
G01X414950Y181460D02*
X415160Y181250D01*
Y181106D01*
X416402Y179864D01*
Y179641D01*
G01X414612Y187561D02*
Y187357D01*
X415764Y186205D01*
X415992D01*
G01X414612Y190561D02*
X414685D01*
X415992Y189254D01*
G01X408100Y193600D02*
X407300D01*
X406792Y194108D01*
Y195061D01*
G01X408200Y190500D02*
X406792Y191908D01*
Y192061D01*
G01X408242Y184624D02*
X407224D01*
X406792Y184192D01*
Y183061D01*
G01X405231Y184976D02*
X405707D01*
X406792Y186061D01*
G01X417372Y193561D02*
Y194691D01*
X416500Y195563D01*
G01X419600Y216200D02*
X419450Y216050D01*
Y214400D01*
X414100Y209050D01*
Y205316D01*
X412612Y203828D01*
Y202771D01*
G01X412412Y199771D02*
X411412Y200771D01*
Y203760D01*
X411422Y203770D01*
Y205750D01*
X411312Y205860D01*
Y209262D01*
X415800Y213750D01*
Y215900D01*
G01X412100Y218400D02*
X411300Y217600D01*
Y211968D01*
X408896Y209564D01*
Y205277D01*
X409422Y204751D01*
G01X408200Y226900D02*
X408100D01*
X406300Y225100D01*
Y213600D01*
X405372Y212672D01*
Y204101D01*
G01X412050Y225100D02*
X410500Y223550D01*
Y212300D01*
X408096Y209896D01*
Y202895D01*
X407752Y202551D01*
G01X419550Y222700D02*
X417600Y220750D01*
Y214200D01*
X412412Y209012D01*
Y206491D01*
G01X415600Y222700D02*
X413900Y221000D01*
Y213100D01*
X410338Y209538D01*
Y205562D01*
X410622Y205278D01*
Y204253D01*
X409732Y203363D01*
Y200601D01*
G01X408100Y220500D02*
Y212600D01*
X406742Y211242D01*
Y206491D01*
G01X419572Y201181D02*
X418491Y200100D01*
X416900D01*
G01X427560Y104770D02*
Y105640D01*
X427069Y106131D01*
X426192D01*
G01X422078Y97678D02*
X422500Y98100D01*
Y102275D01*
X421692Y103083D01*
Y104829D01*
X420240Y106281D01*
X419794D01*
X419092Y106983D01*
Y108641D01*
X420672Y110221D01*
G01X422000Y91300D02*
X424275Y93575D01*
Y101457D01*
X424192Y101540D01*
Y101715D01*
X422492Y103415D01*
Y105281D01*
X420292Y107481D01*
G01X420262Y104561D02*
X420100Y104399D01*
Y93100D01*
X418300Y91300D01*
G01X429105Y106337D02*
X428294Y107148D01*
X428282D01*
Y108061D01*
G01X427900Y114300D02*
X426831D01*
X426132Y113601D01*
G01X428100Y116500D02*
X426233D01*
X426132Y116601D01*
G01X418312Y118101D02*
Y118412D01*
X419100Y119200D01*
X420100D01*
X420600Y118700D01*
Y118300D01*
G01X420672Y120600D02*
X418812D01*
X418312Y121100D01*
Y121101D01*
G01X424700Y115000D02*
Y114982D01*
X423372Y113654D01*
Y113601D01*
G01Y116601D02*
Y116554D01*
X422042Y115224D01*
G01X428100Y120000D02*
X428377Y120277D01*
Y123376D01*
X429902Y124901D01*
G01X423500Y128200D02*
X422402Y129298D01*
Y129961D01*
G01X419402Y132721D02*
X419545D01*
X420942Y131324D01*
G01X423900Y131500D02*
X423800Y131600D01*
X423666D01*
X422545Y132721D01*
X422402D01*
G01X426902Y137781D02*
X426681D01*
X425000Y136100D01*
Y135350D01*
G01X425402Y129961D02*
X427000Y128363D01*
Y128050D01*
G01X424900Y121213D02*
X425828Y122141D01*
X426902D01*
G01X422402Y148361D02*
X422299D01*
X420861Y146923D01*
G01X423902Y137781D02*
X422400Y139000D01*
G01X419402Y148361D02*
X420728Y149687D01*
X420861D01*
G01X423902Y140541D02*
X424856Y142270D01*
G01X427600Y143841D02*
X427162D01*
X425402Y145601D01*
G01X426900Y147100D02*
Y147200D01*
X428061Y148361D01*
X428402D01*
G01X429902Y137781D02*
X429668D01*
X428390Y139059D01*
G01X429902Y140541D02*
X430694Y141333D01*
Y142275D01*
G01X431100Y145500D02*
X431000D01*
X430899Y145601D01*
X428402D01*
G01X421500Y142400D02*
X421600Y142500D01*
Y144799D01*
X422402Y145601D01*
G01X420804Y162659D02*
X420984D01*
X422402Y161241D01*
G01X423945Y165221D02*
X424182D01*
X425402Y164001D01*
G01X421710Y167230D02*
Y164824D01*
X422402Y164132D01*
Y164001D01*
G01X420900Y160037D02*
Y160700D01*
X420359Y161241D01*
X419402D01*
G01X428402Y179641D02*
X430061Y181300D01*
X430310D01*
X430360Y181350D01*
G01X425402Y179641D02*
X425589D01*
X426920Y178310D01*
X426970D01*
G01X429902Y171821D02*
X428460Y170379D01*
Y170293D01*
X428431Y170264D01*
G01X423902Y171821D02*
X424135D01*
X425427Y173113D01*
G01X428402Y176881D02*
X429601D01*
X430340Y177620D01*
G01X422337Y170575D02*
X422330Y170568D01*
Y170489D01*
X420902Y169061D01*
G01X422402Y179641D02*
X423642Y180881D01*
Y181374D01*
G01X423902Y169061D02*
X424149D01*
X425315Y170227D01*
X425387D01*
X425400Y170240D01*
G01X422402Y176881D02*
X423795Y178274D01*
X423842D01*
G01X420922Y178117D02*
X420217D01*
X419402Y177302D01*
Y176881D01*
G01X428238Y167709D02*
X429590Y169061D01*
X429902D01*
G01X426902Y171821D02*
X428201Y173120D01*
X428500D01*
G01X422432Y195061D02*
X421171Y196322D01*
Y196496D01*
G01X429100Y189696D02*
X428402Y190394D01*
Y192521D01*
G01X426173Y190784D02*
Y190127D01*
X426200Y190100D01*
Y188163D01*
X426902Y187461D01*
G01Y195061D02*
X428461D01*
X428779Y195379D01*
X428830D01*
G01X422152Y189600D02*
Y189211D01*
X423902Y187461D01*
G01X420902Y184701D02*
X420501D01*
X418600Y182800D01*
G01X432100Y190400D02*
X432000Y190300D01*
Y189559D01*
X429902Y187461D01*
G01X420800Y193100D02*
X421393D01*
X422432Y192061D01*
G01X426902Y184701D02*
X425558Y186045D01*
X425500D01*
G01X427900Y202800D02*
X427971D01*
X428000Y202771D01*
X430142D01*
G01X427462Y200601D02*
X427035Y200174D01*
X424832D01*
G01X423072Y201181D02*
X421811Y202442D01*
Y202603D01*
G01X437800Y128100D02*
X437771D01*
X436022Y126351D01*
G01X452200Y129800D02*
X443889Y138111D01*
X437022D01*
X435442Y139691D01*
G01X453000Y118700D02*
X451100D01*
X447700Y122100D01*
Y125000D01*
X442568Y130132D01*
X440531D01*
X438414Y132249D01*
X437374D01*
X437372Y132251D01*
G01X459700Y129900D02*
X458300Y131300D01*
X453400D01*
X445176Y139524D01*
X440069D01*
X439592Y140001D01*
G01X456500Y126100D02*
X455600Y127000D01*
X451331D01*
X443029Y135302D01*
X441221D01*
X439712Y136811D01*
X437612D01*
G01X463200Y126200D02*
X461600Y127800D01*
X451663D01*
X443361Y136102D01*
X441553D01*
X441332Y136323D01*
Y137011D01*
G01X459800Y118800D02*
X458100Y120500D01*
X450600D01*
X448900Y122200D01*
Y125300D01*
X442849Y131351D01*
X441332D01*
G01X460100Y123100D02*
X458300Y121300D01*
X452100D01*
X451100Y122300D01*
Y124499D01*
X441948Y133652D01*
X439901D01*
X439382Y134171D01*
G01X453000Y123300D02*
Y124000D01*
X442498Y134502D01*
X440821D01*
X439952Y135371D01*
X436604D01*
X435614Y134381D01*
X435612D01*
G01X456000Y133500D02*
X453800D01*
X445729Y141571D01*
X440529D01*
X438942Y143158D01*
Y144051D01*
G01X463100Y133700D02*
X461700Y135100D01*
X455400D01*
X443600Y146900D01*
X440092D01*
X437999Y144807D01*
X436758D01*
X436022Y144071D01*
G01X454200Y167400D02*
X454100D01*
X454000Y167500D01*
X449000D01*
X443281Y161781D01*
X438942D01*
G01X451000Y171100D02*
X449000D01*
X442106Y164206D01*
X437117D01*
X436022Y165301D01*
G01X461200Y167400D02*
X459400Y169200D01*
X449431D01*
X443285Y163054D01*
X437277D01*
X436024Y161801D01*
X436022D01*
G01X458000Y171100D02*
X456100Y173000D01*
X449300D01*
X441731Y165431D01*
X438932D01*
G01X453000Y174900D02*
X452200Y175700D01*
X450231D01*
X441332Y166801D01*
G01X471300Y181800D02*
X469600Y183500D01*
X449933D01*
X438704Y172271D01*
X437612D01*
G01X469500Y189000D02*
Y189300D01*
X467500Y191300D01*
X452403D01*
X450166Y189066D01*
X442056Y180956D01*
X437447D01*
X436022Y179531D01*
G01X464300Y181800D02*
X449733D01*
X441332Y173399D01*
Y172471D01*
G01X473900Y178200D02*
X472200Y179900D01*
X449200D01*
X442632Y173332D01*
Y172005D01*
X441690Y171063D01*
X438775D01*
X437543Y169831D01*
X435612D01*
G01X437372Y167711D02*
X437683Y167400D01*
X438369D01*
X439400Y168431D01*
X441830D01*
X449899Y176500D01*
X458400D01*
X460000Y174900D01*
G01X466900Y178200D02*
X450000D01*
X441863Y170063D01*
X439816D01*
X439384Y169631D01*
X439382D01*
G01X453400Y193300D02*
X451918D01*
X443432Y184814D01*
Y183532D01*
X441706Y181806D01*
X437247D01*
X436022Y183031D01*
G01X473100Y185500D02*
X471400Y187200D01*
X450700D01*
X441631Y178131D01*
X441332D01*
G01X466000Y185500D02*
X450500D01*
X442006Y177006D01*
X437507D01*
X437392Y177121D01*
G01X462500Y189000D02*
X451300D01*
X450428Y188128D01*
X442405Y180106D01*
X440337D01*
X440081Y179850D01*
X439741Y179511D01*
X438942D01*
G01X437592Y194951D02*
Y196074D01*
X438742Y197224D01*
G01X457400Y197000D02*
X457300D01*
X455400Y198900D01*
X449632D01*
X448100Y197368D01*
Y192878D01*
X441285Y186063D01*
X437994D01*
X437372Y185441D01*
G01X450400Y197000D02*
X449200Y195800D01*
Y192846D01*
X441332Y184978D01*
Y184531D01*
G01X460400Y193300D02*
X458600Y195100D01*
X452586D01*
X442632Y185146D01*
Y183864D01*
X441374Y182606D01*
X439477D01*
X438932Y183151D01*
G01X459500Y200700D02*
X457700Y202500D01*
X450700D01*
X446500Y198300D01*
Y193542D01*
X441297Y188339D01*
X440127D01*
X439890Y188576D01*
X438874D01*
X437859Y187561D01*
X435612D01*
G01X452500Y200700D02*
X450300D01*
X447300Y197700D01*
Y193210D01*
X441441Y187351D01*
X439382D01*
G54D30*
X43500Y143500D03*
X55000Y101500D03*
G54D105*
X562000Y136000D03*
G54D114*
X626889Y208000D03*
Y213000D03*
Y218000D03*
Y223000D03*
X649111Y213000D03*
Y208000D03*
Y223000D03*
Y218000D03*
G54D21*
X24000Y127700D03*
Y124300D03*
X27200Y127700D03*
Y124300D03*
X30200Y127700D03*
Y124300D03*
X24900Y197300D03*
Y200700D03*
X37500Y127700D03*
Y124300D03*
X57000Y127200D03*
Y123800D03*
X52500Y238200D03*
Y234800D03*
X49500Y238200D03*
Y234800D03*
X61300Y253300D03*
Y249900D03*
X79000Y132600D03*
Y129200D03*
X68000Y198300D03*
Y201700D03*
X77700Y256500D03*
Y253100D03*
X64400Y253300D03*
Y249900D03*
X89500Y258300D03*
Y254900D03*
X80200Y266200D03*
Y262800D03*
X118000Y54200D03*
Y50800D03*
X123700Y150900D03*
Y154300D03*
X129500Y81200D03*
Y77800D03*
X130600Y131800D03*
Y128400D03*
X126800Y144300D03*
Y140900D03*
X127000Y150800D03*
Y154200D03*
X150000Y167200D03*
Y163800D03*
X184500Y65000D03*
Y61600D03*
X187500Y65000D03*
Y61600D03*
X185500Y87800D03*
Y91200D03*
X190500Y65000D03*
Y61600D03*
X193500Y65000D03*
Y61600D03*
X194600Y88800D03*
X197600D03*
X194600Y92200D03*
X197600D03*
X197300Y135800D03*
X191300D03*
X194300D03*
X197300Y139200D03*
X191300D03*
X194300D03*
X221500Y212300D03*
Y215700D03*
X238000Y166700D03*
Y163300D03*
X246000Y193200D03*
Y189800D03*
X255500Y96700D03*
Y93300D03*
X270000Y84700D03*
Y81300D03*
X267000Y84700D03*
Y81300D03*
X276700Y182700D03*
Y186100D03*
X293000Y195700D03*
Y192300D03*
X289500Y218700D03*
Y215300D03*
X322000Y257800D03*
X311500D03*
X322000Y261200D03*
X311500D03*
X441600Y254800D03*
Y251400D03*
X449000Y281700D03*
Y278300D03*
X446000Y281700D03*
Y278300D03*
X462500Y255200D03*
Y251800D03*
X461000Y270700D03*
Y267300D03*
X465500Y143763D03*
Y140363D03*
Y255200D03*
Y251800D03*
X509200Y103200D03*
Y99800D03*
X523000Y74800D03*
Y78200D03*
X531500Y237200D03*
Y233800D03*
X555300Y214100D03*
Y217500D03*
X566500Y84700D03*
Y81300D03*
X595500Y202200D03*
Y198800D03*
X613000Y115700D03*
Y112300D03*
X616000Y115700D03*
Y112300D03*
X622500Y88700D03*
Y85300D03*
X623000Y115700D03*
Y112300D03*
X634000Y136300D03*
Y139700D03*
X628900Y178400D03*
Y175000D03*
X646500Y182200D03*
Y178800D03*
X667500Y164800D03*
Y168200D03*
X668000Y211500D03*
Y208100D03*
X694500Y226700D03*
Y223300D03*
X691500Y226700D03*
Y223300D03*
X682500Y226700D03*
Y223300D03*
X711000Y66700D03*
Y63300D03*
X714000Y71200D03*
Y67800D03*
X725200Y119900D03*
Y116500D03*
X718700Y126600D03*
Y123200D03*
X718000Y143700D03*
Y140300D03*
X723000Y183200D03*
Y179800D03*
X726000Y183200D03*
Y179800D03*
X725000Y213700D03*
Y210300D03*
X722000Y213700D03*
Y210300D03*
X718500Y220700D03*
Y217300D03*
X722000Y220700D03*
Y217300D03*
X728000Y104300D03*
X739500Y104600D03*
X728000Y107700D03*
X739500Y108000D03*
X728000Y158700D03*
Y155300D03*
X735500Y182700D03*
Y179300D03*
X740500Y197800D03*
Y201200D03*
X744000Y165200D03*
Y161800D03*
X754500Y158700D03*
Y155300D03*
X782500Y41800D03*
Y45200D03*
X779500Y148700D03*
Y145300D03*
X807500Y86200D03*
Y82800D03*
G54D12*
G01X60433Y24392D02*
Y38000D01*
G01X64370Y24392D02*
Y34063D01*
X60433Y38000D01*
G01D02*
Y40433D01*
X63500Y43500D01*
G01X72244Y24392D02*
X72315Y24463D01*
Y35957D01*
X74000Y37642D01*
G01X68307Y24392D02*
X68315Y24400D01*
Y35827D01*
X66500Y37642D01*
G01X84055Y24392D02*
X84126Y24463D01*
Y35832D01*
G01X87992Y24392D02*
X88063Y24463D01*
Y36050D01*
G01X84126Y35832D02*
X82211Y37747D01*
G01X88063Y36050D02*
X89862Y37849D01*
G01X103740Y24392D02*
X103811Y24463D01*
Y35709D01*
G01X99803Y24392D02*
X99874Y24463D01*
Y36268D01*
G01X103811Y35709D02*
X105794Y37692D01*
G01X99874Y36268D02*
X98500Y37642D01*
G01X115551Y24392D02*
X115622Y24463D01*
Y35648D01*
X113605Y37665D01*
G01X119488Y24392D02*
Y35630D01*
X121500Y37642D01*
G01X131299Y24392D02*
X131370Y24463D01*
Y35618D01*
X129336Y37652D01*
G01X135236Y24392D02*
X135307Y24463D01*
Y35649D01*
X137300Y37642D01*
G01X150984Y24392D02*
X151055Y24463D01*
Y35620D01*
X153088Y37653D01*
G01X147047Y24392D02*
X147118Y24463D01*
Y35594D01*
X145070Y37642D01*
G01X162795Y24392D02*
X162866Y24463D01*
Y35736D01*
X160898Y37704D01*
G01X166732Y24392D02*
X166803Y24463D01*
Y35315D01*
X168791Y37303D01*
Y37689D01*
G01X178543Y24392D02*
Y35796D01*
X176640Y37699D01*
G01X182480Y24392D02*
Y35680D01*
X184500Y37700D01*
G01X194291Y24392D02*
Y35751D01*
X192400Y37642D01*
G01X198228Y24392D02*
Y35570D01*
X200300Y37642D01*
G01X213976Y24392D02*
Y35244D01*
X216085Y37353D01*
Y37649D01*
G01X210039Y24392D02*
Y35203D01*
X207600Y37642D01*
G01X229724Y24392D02*
Y35635D01*
X231780Y37691D01*
G01X225787Y24392D02*
Y35767D01*
X223868Y37686D01*
G01X245472Y24392D02*
Y35244D01*
X247500Y37272D01*
Y37642D01*
G01X241535Y24392D02*
Y35737D01*
X239599Y37673D01*
G01X261220Y24392D02*
X261291Y24463D01*
Y35891D01*
X263100Y37700D01*
G01X257283Y24392D02*
X257354Y24463D01*
Y35288D01*
X255000Y37642D01*
G01X276968Y24392D02*
X277039Y24463D01*
Y35639D01*
X278800Y37400D01*
Y37700D01*
G01X273031Y24392D02*
X273102Y24463D01*
Y35898D01*
X271200Y37800D01*
X271000D01*
G01X292716Y24392D02*
X292787Y24463D01*
Y36087D01*
X294500Y37800D01*
Y37900D01*
G01X288779Y24392D02*
X288850Y24463D01*
Y35850D01*
X286900Y37800D01*
G01X308464Y24392D02*
Y36016D01*
X310348Y37900D01*
G01X304527Y24392D02*
Y35473D01*
X302600Y37400D01*
Y37800D01*
G01X324212Y24392D02*
Y36016D01*
X326096Y37900D01*
G01X320275Y24392D02*
Y35473D01*
X318048Y37700D01*
G01X336023Y24392D02*
Y35677D01*
X333700Y38000D01*
G01X383268Y24392D02*
Y37232D01*
G01X379331Y37431D02*
Y24392D01*
G01X375394D02*
Y36399D01*
X375400Y36405D01*
Y37700D01*
G01X380000Y38100D02*
X379331Y37431D01*
G01X383268Y37232D02*
X382400Y38100D01*
X380000D01*
X14000Y104500D03*
X14400Y98000D03*
X14000Y109500D03*
X15400Y118000D03*
X10900D03*
X13000Y137000D03*
X15500Y122800D03*
X15000Y127500D03*
X11000Y122800D03*
X10500Y127500D03*
X13000Y141500D03*
X13100Y150600D03*
X13000Y146000D03*
X11500Y163700D03*
Y159000D03*
X7000Y163700D03*
Y159000D03*
X14500Y198000D03*
X17300Y208100D03*
X4500Y228900D03*
X4600Y223100D03*
X4500Y234800D03*
X4400Y245100D03*
Y256700D03*
X5000Y275000D03*
X12600Y266900D03*
X15300Y285800D03*
X4900Y285700D03*
X23400Y81550D03*
X25000Y77300D03*
X33000Y105000D03*
X29651Y131448D03*
X20300Y133700D03*
X33900Y127200D03*
X24800Y131700D03*
X30200Y145000D03*
Y149200D03*
X34000Y161500D03*
X30300Y157600D03*
X30200Y153400D03*
X19800Y161400D03*
X28400Y200100D03*
X25200Y286000D03*
X34900Y86300D03*
X37500Y105000D03*
X42000D03*
X38464Y98248D03*
X39142Y93495D03*
X45500Y118000D03*
X42500Y159500D03*
X43000Y220000D03*
X43500Y242000D03*
X44000Y234000D03*
X37500Y264000D03*
X63500Y43500D03*
Y57500D03*
Y48000D03*
Y52500D03*
X49500Y120000D03*
X50500Y160000D03*
X55600Y158700D03*
X63200Y194900D03*
X51000Y229500D03*
X60127Y217067D03*
X50500Y221500D03*
X68500Y47500D03*
X73500Y48000D03*
X68000Y52500D03*
X73100Y86700D03*
X72000Y82000D03*
X75000Y135700D03*
X67200Y177500D03*
X76200Y187200D03*
X70900Y193800D03*
X79000Y190400D03*
X66900Y192500D03*
X74544Y213236D03*
X68652Y212848D03*
X78623Y210704D03*
X67400Y205500D03*
X67813Y227987D03*
X64768Y215669D03*
X67892Y233192D03*
X67988Y239488D03*
X74100Y256200D03*
X64800Y246073D03*
X70100Y259300D03*
X85500Y75000D03*
X85906Y85094D03*
X95500Y93500D03*
X94000Y137500D03*
Y133000D03*
X82000Y177500D03*
X86500D03*
X90700Y177050D03*
X88000Y186500D03*
X94002Y210600D03*
X83447Y210471D03*
X81960Y199734D03*
X86600Y249500D03*
X93800Y246400D03*
X82000Y254500D03*
X88500Y265000D03*
X81700Y272600D03*
X92800Y285600D03*
X99500Y91500D03*
Y96000D03*
X104000Y106600D03*
Y92000D03*
Y96500D03*
Y115500D03*
Y111000D03*
X105775Y137349D03*
X103175Y134050D03*
X98500Y137500D03*
X109000Y134050D03*
X98500Y133000D03*
X96000Y161500D03*
X103300Y206800D03*
X107462Y209526D03*
X99900Y216100D03*
X105000Y229213D03*
X99900Y239450D03*
X100700Y231800D03*
X100000Y267400D03*
X100700Y262900D03*
X101400Y272600D03*
X97500Y285450D03*
X102000D03*
X106500Y285550D03*
X110700D03*
X116089Y47089D03*
X126000Y72500D03*
X119400Y106700D03*
X123800Y102500D03*
X123900Y106700D03*
X119400Y102300D03*
Y115900D03*
Y111200D03*
X123900Y115900D03*
Y111200D03*
X114500Y134050D03*
X113200Y146700D03*
X113100Y151000D03*
X117500Y146950D03*
X119000Y159100D03*
X114700Y158800D03*
X116500Y211200D03*
X122250Y228750D03*
Y233000D03*
Y237300D03*
Y241500D03*
X140026Y46584D03*
X133500Y74200D03*
X134100Y96600D03*
X128500Y165000D03*
X140500Y182000D03*
X127500Y197000D03*
X133941Y208863D03*
X131003Y205766D03*
X138100Y208100D03*
X137757Y200557D03*
X134500Y226000D03*
X129500Y252500D03*
X139000Y247500D03*
X129000Y268000D03*
X136500Y272500D03*
X131500D03*
X141000D03*
X156070Y158720D03*
X153100Y170900D03*
X149400Y177700D03*
X154000Y196000D03*
X155900Y200500D03*
X164300Y158700D03*
X161026Y191750D03*
X158700Y213800D03*
X158600Y208400D03*
X166500Y241000D03*
X173000Y56423D03*
X186900Y68900D03*
X173524Y65754D03*
X186500Y82700D03*
X178994Y90247D03*
X174700Y88100D03*
X187500Y76100D03*
X175600Y94500D03*
X176100Y106100D03*
X181466Y142065D03*
X187600Y188800D03*
X182100Y207900D03*
X186500Y276500D03*
Y281000D03*
X189000Y87700D03*
X196000Y77125D03*
X192500Y161900D03*
X192600Y166700D03*
X201200Y164200D03*
X196518Y182800D03*
X193000Y189900D03*
X190000Y184000D03*
X203100Y252900D03*
X191100Y276600D03*
X190900Y280800D03*
X212201Y44539D03*
X218500Y49500D03*
X205500Y59000D03*
X216261Y74846D03*
X212300Y157300D03*
X212600Y161500D03*
X212268Y166850D03*
X206300Y192900D03*
X211202Y186727D03*
X211900Y253000D03*
X207500D03*
X217000Y252900D03*
X217200Y258000D03*
X212400Y281200D03*
X217000Y281000D03*
X212500Y277000D03*
X208000D03*
X229098Y70092D03*
X230000Y74900D03*
X226400Y64609D03*
X226900Y133300D03*
X229832Y154168D03*
X229500Y160900D03*
X227000Y183300D03*
Y178500D03*
X226292Y173752D03*
X231500Y211500D03*
X234100Y215700D03*
X234525Y239250D03*
X229700Y234700D03*
X225300Y239200D03*
X234525Y243450D03*
X229725D03*
X225300Y243400D03*
X234525Y234800D03*
X225300D03*
X229675Y239000D03*
X233500Y258958D03*
X228000Y259000D03*
X221300Y255400D03*
X243736Y66438D03*
X241496Y71328D03*
X240130Y77300D03*
X236400Y95100D03*
X241741Y105300D03*
X248700Y96100D03*
X240565Y113365D03*
X249100Y135836D03*
X244500Y122500D03*
X247500Y127000D03*
X247600Y147327D03*
X249000Y157810D03*
X241500Y168500D03*
X249350Y199400D03*
X235211Y190389D03*
X246000Y186100D03*
X248300Y213500D03*
X243000Y214000D03*
X247500Y239250D03*
X243300Y235050D03*
X247500Y243450D03*
X243300D03*
X238900D03*
X243300Y239250D03*
X247500Y235050D03*
X238925Y235000D03*
Y239200D03*
X236900Y231300D03*
X248000Y259000D03*
X238500D03*
X243000D03*
X258400Y65600D03*
X253520Y89664D03*
X258000Y79550D03*
X253100Y116000D03*
X258500Y130000D03*
X259000Y145652D03*
X262000Y157500D03*
X264600Y169900D03*
X259779Y173043D03*
X257383Y190111D03*
X257000Y213500D03*
X252350Y202350D03*
X252700Y213500D03*
X257000Y201600D03*
X258400Y229800D03*
X263000Y221500D03*
X251700Y239250D03*
Y243450D03*
X257000Y242500D03*
X252500Y259000D03*
X253000Y267000D03*
X267121Y70348D03*
X270150Y77000D03*
X276654Y131454D03*
X270977Y182073D03*
X271701Y174800D03*
X273074Y186392D03*
X265400Y187500D03*
X269500Y194400D03*
X270336Y206467D03*
X272700Y214900D03*
X268600Y219059D03*
X274162Y243180D03*
X271200Y235733D03*
X278200Y281350D03*
X284262Y52009D03*
X294800Y94100D03*
X295500Y99500D03*
X282000Y146000D03*
X295290Y177645D03*
X290600Y181900D03*
X280700Y186000D03*
X286500Y201500D03*
X292685Y221445D03*
X282686Y281336D03*
X303400Y73700D03*
X296000Y75940D03*
Y84125D03*
X303900Y80475D03*
X298800Y95400D03*
X299000Y112500D03*
X298500Y130000D03*
X301000Y134500D03*
X297200Y146000D03*
X304300Y141400D03*
X298997Y139003D03*
X304400Y146500D03*
X300276Y162090D03*
X303261Y156952D03*
X298717Y155403D03*
X304303Y164703D03*
X303000Y177200D03*
X297500Y181907D03*
X297000Y192000D03*
X309700Y245800D03*
X314000Y54000D03*
X317500Y45700D03*
X315000Y66500D03*
X321300Y88200D03*
X314800Y88500D03*
X314100Y233700D03*
X318700Y250400D03*
X320300Y245800D03*
X313000Y250000D03*
X339638Y67138D03*
X340800Y83900D03*
X331600Y82200D03*
X334500Y266300D03*
X334300Y270500D03*
X335700Y278751D03*
X331500D03*
X353100Y56151D03*
X345089Y73089D03*
X353500Y71900D03*
X357000Y69500D03*
X349300Y83000D03*
X345100D03*
X354200Y76400D03*
X354141Y87158D03*
X343600Y270500D03*
X371400Y42500D03*
X371500Y47000D03*
X359800Y72700D03*
X362700Y69600D03*
X380000Y38100D03*
X375600Y42500D03*
X380300D03*
X375700Y47000D03*
X380295Y46779D03*
X379500Y270000D03*
X387000D03*
X394300Y269900D03*
X413200Y64450D03*
X418600Y85000D03*
X434000Y18500D03*
X428875Y42975D03*
X431990Y49271D03*
X422825Y74925D03*
X431900Y83200D03*
X428500Y224000D03*
X433500Y224400D03*
X443644Y22233D03*
X439892Y42508D03*
X440666Y36034D03*
X440700Y87000D03*
X437300Y83100D03*
X440400Y224000D03*
X435500Y219000D03*
X443800Y246100D03*
X442500Y258600D03*
X439400Y281600D03*
X465000Y12049D03*
X452500Y26125D03*
X457863Y140000D03*
X450800Y145400D03*
X453900Y149150D03*
X461500Y244500D03*
X465000Y248000D03*
X457300Y271400D03*
X457029Y266505D03*
X456000Y281700D03*
X474000Y9000D03*
X467200Y4400D03*
X466100Y23900D03*
X469000Y133000D03*
X481500Y8900D03*
X489600Y8800D03*
X497100D03*
X510000Y135400D03*
X509900Y142000D03*
Y148855D03*
X498875Y154600D03*
X505200Y215000D03*
X496711Y248999D03*
X521500Y70700D03*
X527000Y69500D03*
X525500Y83500D03*
X514000Y103500D03*
X513479Y132021D03*
X513800Y138955D03*
X513500Y145500D03*
X523000Y198000D03*
X522400Y184500D03*
X518000Y198000D03*
X514000Y205200D03*
X527000Y225500D03*
X532000Y67500D03*
X537300Y65036D03*
X532986Y85675D03*
X534800Y81100D03*
X529698Y222802D03*
X529000Y215500D03*
X535200Y230400D03*
X550000Y85500D03*
X544000Y81000D03*
X543274Y212774D03*
X550860Y226200D03*
X550915Y219430D03*
X547700Y230982D03*
X570500Y85000D03*
X566000Y194000D03*
X568500Y211560D03*
X560500Y202200D03*
X565729Y203031D03*
X570500Y202500D03*
X562300Y217600D03*
X568000Y217500D03*
X582000Y74000D03*
X574500D03*
X573300Y80100D03*
X593000Y73500D03*
X597916Y186411D03*
X601000Y195800D03*
X598900Y200500D03*
X600900Y230200D03*
X603047Y217747D03*
X598814Y240095D03*
X615469Y73969D03*
X617000Y79500D03*
Y87000D03*
X609600Y117800D03*
X615500Y119500D03*
X611255Y133045D03*
X617500Y152650D03*
X610955Y138955D03*
X613590Y162596D03*
X612500Y157150D03*
X618500Y162800D03*
X615000Y182500D03*
X612000Y212000D03*
X615700Y230200D03*
X617949Y223800D03*
X615100Y238900D03*
X630000Y55300D03*
Y72000D03*
X623500Y74500D03*
X620000Y101500D03*
Y94000D03*
X623000Y121000D03*
X630000Y136600D03*
X625800Y128500D03*
X623500Y150000D03*
X623700Y162399D03*
X626500Y154900D03*
X624900Y167047D03*
X633000Y162500D03*
X626186Y194451D03*
X623400Y230100D03*
X623900Y239600D03*
X646000Y46007D03*
X640000D03*
X640500Y55000D03*
X644000Y77000D03*
X635225Y125500D03*
X645000Y161000D03*
X642375Y173100D03*
X638524Y178140D03*
X650100Y176700D03*
X636300Y191800D03*
X643800Y232600D03*
X655133Y55833D03*
X654500Y46107D03*
X653000Y93000D03*
X650726Y125724D03*
X664212Y147993D03*
X660500Y151289D03*
X662800Y179500D03*
X655500Y173100D03*
X652146Y194648D03*
X663155Y186000D03*
X658479Y202400D03*
X657900Y208000D03*
X662000Y222500D03*
X659811Y260757D03*
X657500Y258400D03*
X661308Y263698D03*
X655500Y270500D03*
X657787Y264179D03*
X656000Y261400D03*
X655523Y266616D03*
X658667Y267622D03*
X667800Y90100D03*
X678400Y114500D03*
X666800Y118400D03*
X668411Y148089D03*
X678500Y141500D03*
X674750Y151700D03*
X671100Y166000D03*
X667061Y175239D03*
X673900Y173600D03*
X695500Y94500D03*
X696500Y123000D03*
X693500Y148000D03*
X685500Y152000D03*
X690000Y159000D03*
X694500D03*
X681500Y187300D03*
X690400Y188600D03*
X695300Y188650D03*
X691500Y219500D03*
X682544Y219456D03*
X700089Y91411D03*
X707500Y78000D03*
X701600Y104900D03*
X701400Y98400D03*
X705580Y157480D03*
X709879Y165479D03*
X710200Y201700D03*
X710000Y210000D03*
X697200Y219600D03*
X725632Y49600D03*
X721950Y51950D03*
X721200Y65100D03*
X722000Y74500D03*
X717000D03*
X721000Y69500D03*
X725000Y64000D03*
X715000Y80300D03*
X714500Y85500D03*
X722600Y80500D03*
X724200Y104300D03*
X718400Y112800D03*
X724400Y112700D03*
X724900Y133600D03*
X724600Y142800D03*
X719087Y167143D03*
X714842Y173742D03*
X719200Y184100D03*
X718400Y213500D03*
X723500Y224500D03*
X732000Y63500D03*
X739500Y75500D03*
X740300Y70200D03*
X739911Y83589D03*
X728200Y84800D03*
X734200Y85300D03*
X729500Y111500D03*
X728440Y125224D03*
X731636Y138979D03*
X734000Y150850D03*
X728589Y150527D03*
X738500Y148500D03*
X730784Y145184D03*
X741167Y153000D03*
X741000Y158500D03*
X736500Y174500D03*
X730400Y179400D03*
X731900Y184000D03*
X733000Y197525D03*
X728740Y206500D03*
X733000Y215000D03*
X730000Y223900D03*
X753500Y24007D03*
Y20007D03*
Y28507D03*
X755500Y16000D03*
X743500Y100500D03*
X745100Y114900D03*
X752500Y151500D03*
X746782Y149282D03*
X770500Y13007D03*
X767500Y24007D03*
X760500Y29000D03*
X761000Y16007D03*
X767500Y28507D03*
Y19507D03*
X764200Y44200D03*
X767500Y33207D03*
X759000Y37507D03*
X764500Y54000D03*
X764300Y49200D03*
X769500Y50000D03*
X761000Y58500D03*
X764500Y84800D03*
X760400Y88700D03*
X768100Y89000D03*
X761300Y95700D03*
X762100Y135000D03*
X769400Y136800D03*
X762800Y129200D03*
X759700Y141100D03*
Y145900D03*
X763600Y168000D03*
X764000Y188000D03*
Y197500D03*
Y192810D03*
Y202310D03*
X769500Y234500D03*
X769400Y252700D03*
X785500Y8000D03*
X781500Y51000D03*
X777000Y93100D03*
X774300Y102500D03*
X778500D03*
Y107000D03*
X787500Y93000D03*
X783000D03*
X774300Y107000D03*
X783000Y113000D03*
Y118500D03*
Y123000D03*
X775665Y146865D03*
X778000Y138000D03*
X785830Y188700D03*
X785400Y202800D03*
X789000Y204979D03*
X789200Y214200D03*
Y209800D03*
X784500Y222500D03*
X789000Y223500D03*
X789200Y218700D03*
X786000Y228000D03*
Y232400D03*
X786200Y236900D03*
X786300Y241500D03*
X785000Y245800D03*
Y250200D03*
Y254900D03*
X792000Y83000D03*
X796500D03*
X792000Y87700D03*
X796500D03*
X799200Y98600D03*
X803100Y106000D03*
X799200Y102800D03*
X799000Y107100D03*
X803500Y116700D03*
Y112500D03*
X799000Y116100D03*
Y111900D03*
X789910Y187679D03*
X794110D03*
X798310Y187779D03*
X793500Y204979D03*
Y223500D03*
X793200Y228400D03*
Y232600D03*
Y237200D03*
Y242400D03*
X793300Y247200D03*
X795300Y260800D03*
X795400Y251700D03*
X795300Y256500D03*
X791000Y254500D03*
X795300Y265000D03*
X810500Y196500D03*
Y192300D03*
X809200Y209500D03*
Y213700D03*
Y218400D03*
X809100Y228600D03*
Y224400D03*
X808700Y238300D03*
Y234100D03*
Y242900D03*
X809500Y251500D03*
Y257000D03*
X808700Y247100D03*
X810100Y275000D03*
X812035Y271067D03*
X810100Y267339D03*
X812000Y263500D03*
X809700Y285900D03*
X820500Y6500D03*
X821900Y273100D03*
X821600Y285500D03*
G54D123*
X735554Y126676D03*
Y140850D03*
X754654Y126676D03*
Y140850D03*
G54D132*
X804032Y27032D03*
X794032D03*
X804032Y37032D03*
Y47032D03*
X794032Y37032D03*
Y47032D03*
X804032Y57032D03*
X794032D03*
X804032Y67032D03*
X794032D03*
G54D142*
G01X70851Y-113865D02*
Y-96365D01*
G01X80021D02*
Y-113865D01*
G01Y-105115D02*
X70851D01*
G01X92936Y-113865D02*
X91626Y-113573D01*
X90316Y-112407D01*
X89442Y-110365D01*
X89006Y-108032D01*
X89442Y-105698D01*
X90316Y-103657D01*
X91626Y-102490D01*
X92936Y-102199D01*
X94246Y-102490D01*
X95556Y-103657D01*
X96429Y-105698D01*
X96648Y-108032D01*
X96429Y-110365D01*
X95556Y-112407D01*
X94246Y-113573D01*
X92936Y-113865D01*
G01X106724D02*
Y-102199D01*
G01Y-105115D02*
X107598Y-103657D01*
X108908Y-102490D01*
X110654Y-102199D01*
X112182Y-102490D01*
X113493Y-103657D01*
X114148Y-105698D01*
Y-113865D01*
G01X124661Y-105990D02*
X131648D01*
X130993Y-103948D01*
X129901Y-102782D01*
X128373Y-102199D01*
X126844Y-102490D01*
X125534Y-103365D01*
X124661Y-105407D01*
X124224Y-107157D01*
Y-108907D01*
X124661Y-110657D01*
X125753Y-112407D01*
X127063Y-113573D01*
X128591Y-113865D01*
X130119Y-113282D01*
X131648Y-111532D01*
G01X140851Y-119115D02*
X142161Y-119698D01*
X143908Y-119115D01*
X144999Y-117949D01*
X145873Y-116490D01*
X147182Y-111824D01*
X150021Y-102199D01*
G01X143034D02*
X147182Y-111824D01*
G01X182182Y-104532D02*
X183056Y-103657D01*
X183711Y-102199D01*
X184148Y-100156D01*
X183711Y-98407D01*
X182838Y-97240D01*
X181309Y-96365D01*
X175414D01*
Y-113865D01*
X182619D01*
X184148Y-112699D01*
X185021Y-110948D01*
X185458Y-108907D01*
X185021Y-106865D01*
X183711Y-105115D01*
X182182Y-104532D01*
X175414D01*
G01X201866Y-113865D02*
Y-102199D01*
G01Y-104240D02*
X200993Y-103074D01*
X199682Y-102490D01*
X198154Y-102199D01*
X196626Y-102782D01*
X195316Y-103948D01*
X194442Y-105698D01*
X194006Y-108032D01*
X194442Y-110365D01*
X195316Y-112115D01*
X196626Y-113282D01*
X198154Y-113865D01*
X199682Y-113573D01*
X200993Y-112699D01*
X201866Y-111532D01*
G01X219366Y-96365D02*
Y-113865D01*
G01Y-111241D02*
X218493Y-112699D01*
X217182Y-113573D01*
X215654Y-113865D01*
X213908Y-113282D01*
X212598Y-111824D01*
X211724Y-110074D01*
X211506Y-108032D01*
X211724Y-105990D01*
X212598Y-104240D01*
X213908Y-102782D01*
X215654Y-102199D01*
X217182Y-102490D01*
X218274Y-103074D01*
X219366Y-104240D01*
G01X229879Y-118240D02*
X231408Y-119407D01*
X233154Y-119698D01*
X234682Y-119407D01*
X235993Y-117949D01*
X236866Y-115907D01*
Y-102199D01*
G01Y-104532D02*
X235993Y-103365D01*
X234682Y-102490D01*
X233154Y-102199D01*
X231408Y-102782D01*
X230316Y-103948D01*
X229442Y-105990D01*
X229006Y-108032D01*
X229224Y-109782D01*
X230098Y-111824D01*
X231408Y-113282D01*
X233154Y-113865D01*
X234464Y-113573D01*
X235993Y-112407D01*
X236866Y-111241D01*
G01X247161Y-105990D02*
X254148D01*
X253493Y-103948D01*
X252401Y-102782D01*
X250873Y-102199D01*
X249344Y-102490D01*
X248034Y-103365D01*
X247161Y-105407D01*
X246724Y-107157D01*
Y-108907D01*
X247161Y-110657D01*
X248253Y-112407D01*
X249563Y-113573D01*
X251091Y-113865D01*
X252619Y-113282D01*
X254148Y-111532D01*
G01X264879Y-113865D02*
Y-102199D01*
G01Y-104532D02*
X265971Y-103365D01*
X267063Y-102490D01*
X268591Y-102199D01*
X269682Y-102490D01*
X270993Y-103365D01*
G01X298569Y-113865D02*
Y-96365D01*
X303809D01*
X305556Y-97240D01*
X306866Y-99282D01*
X307303Y-101615D01*
X306866Y-103948D01*
X305774Y-105698D01*
X303809Y-106574D01*
X298569D01*
G01X324366Y-113865D02*
Y-102199D01*
G01Y-104240D02*
X323493Y-103074D01*
X322182Y-102490D01*
X320654Y-102199D01*
X319126Y-102782D01*
X317816Y-103948D01*
X316942Y-105698D01*
X316506Y-108032D01*
X316942Y-110365D01*
X317816Y-112115D01*
X319126Y-113282D01*
X320654Y-113865D01*
X322182Y-113573D01*
X323493Y-112699D01*
X324366Y-111532D01*
G01X334224Y-113865D02*
Y-102199D01*
G01Y-105115D02*
X335098Y-103657D01*
X336408Y-102490D01*
X338154Y-102199D01*
X339682Y-102490D01*
X340993Y-103657D01*
X341648Y-105698D01*
Y-113865D01*
G01X355436Y-96365D02*
Y-113865D01*
G01X352379Y-102199D02*
X358493D01*
G01X369224Y-113865D02*
Y-96365D01*
G01Y-104823D02*
X370316Y-103365D01*
X371408Y-102490D01*
X373154Y-102199D01*
X374464Y-102490D01*
X375993Y-103657D01*
X376648Y-105407D01*
Y-113865D01*
G01X387161Y-105990D02*
X394148D01*
X393493Y-103948D01*
X392401Y-102782D01*
X390873Y-102199D01*
X389344Y-102490D01*
X388034Y-103365D01*
X387161Y-105407D01*
X386724Y-107157D01*
Y-108907D01*
X387161Y-110657D01*
X388253Y-112407D01*
X389563Y-113573D01*
X391091Y-113865D01*
X392619Y-113282D01*
X394148Y-111532D01*
G01X404879Y-113865D02*
Y-102199D01*
G01Y-104532D02*
X405971Y-103365D01*
X407063Y-102490D01*
X408591Y-102199D01*
X409682Y-102490D01*
X410993Y-103365D01*
G01X437259Y-113865D02*
Y-96365D01*
X442936Y-110948D01*
X448613Y-96365D01*
Y-113865D01*
G01X462182Y-104532D02*
X463056Y-103657D01*
X463711Y-102199D01*
X464148Y-100156D01*
X463711Y-98407D01*
X462838Y-97240D01*
X461309Y-96365D01*
X455414D01*
Y-113865D01*
X462619D01*
X464148Y-112699D01*
X465021Y-110948D01*
X465458Y-108907D01*
X465021Y-106865D01*
X463711Y-105115D01*
X462182Y-104532D01*
X455414D01*
G01X227259Y-68865D02*
Y-51365D01*
X232936Y-65948D01*
X238613Y-51365D01*
Y-68865D01*
G01X250436D02*
X249126Y-68573D01*
X247816Y-67407D01*
X246942Y-65365D01*
X246506Y-63032D01*
X246942Y-60698D01*
X247816Y-58657D01*
X249126Y-57490D01*
X250436Y-57199D01*
X251746Y-57490D01*
X253056Y-58657D01*
X253929Y-60698D01*
X254148Y-63032D01*
X253929Y-65365D01*
X253056Y-67407D01*
X251746Y-68573D01*
X250436Y-68865D01*
G01X271866Y-51365D02*
Y-68865D01*
G01Y-66241D02*
X270993Y-67699D01*
X269682Y-68573D01*
X268154Y-68865D01*
X266408Y-68282D01*
X265098Y-66824D01*
X264224Y-65074D01*
X264006Y-63032D01*
X264224Y-60990D01*
X265098Y-59240D01*
X266408Y-57782D01*
X268154Y-57199D01*
X269682Y-57490D01*
X270774Y-58074D01*
X271866Y-59240D01*
G01X282161Y-60990D02*
X289148D01*
X288493Y-58948D01*
X287401Y-57782D01*
X285873Y-57199D01*
X284344Y-57490D01*
X283034Y-58365D01*
X282161Y-60407D01*
X281724Y-62157D01*
Y-63907D01*
X282161Y-65657D01*
X283253Y-67407D01*
X284563Y-68573D01*
X286091Y-68865D01*
X287619Y-68282D01*
X289148Y-66532D01*
G01X302936Y-68865D02*
Y-51365D01*
G01X542319Y-68865D02*
Y-51365D01*
X547559D01*
X549306Y-52240D01*
X550616Y-54282D01*
X551053Y-56615D01*
X550616Y-58948D01*
X549524Y-60698D01*
X547559Y-61574D01*
X542319D01*
G01X568989Y-52824D02*
X567679Y-51948D01*
X566151Y-51365D01*
X564404D01*
X562439Y-52240D01*
X560911Y-53698D01*
X559819Y-55449D01*
X558946Y-58365D01*
X558727Y-60990D01*
X559164Y-63615D01*
X559819Y-65365D01*
X561129Y-67115D01*
X562658Y-68282D01*
X564186Y-68865D01*
X565714D01*
X567243Y-68282D01*
X568553Y-67407D01*
X569645Y-66241D01*
G01X583432Y-59532D02*
X584306Y-58657D01*
X584961Y-57199D01*
X585398Y-55156D01*
X584961Y-53407D01*
X584088Y-52240D01*
X582559Y-51365D01*
X576664D01*
Y-68865D01*
X583869D01*
X585398Y-67699D01*
X586271Y-65948D01*
X586708Y-63907D01*
X586271Y-61865D01*
X584961Y-60115D01*
X583432Y-59532D01*
X576664D01*
G01X592636Y-74698D02*
X605736D01*
G01X611664Y-68865D02*
Y-51365D01*
X621708Y-68865D01*
Y-51365D01*
G01X634186Y-68865D02*
X632439Y-68573D01*
X630911Y-67407D01*
X629601Y-65657D01*
X628727Y-63615D01*
X628291Y-61282D01*
Y-58948D01*
X628727Y-56615D01*
X629601Y-54573D01*
X630911Y-52824D01*
X632439Y-51657D01*
X634186Y-51365D01*
X635932Y-51657D01*
X637461Y-52824D01*
X638771Y-54573D01*
X639645Y-56615D01*
X640081Y-58948D01*
Y-61282D01*
X639645Y-63615D01*
X638771Y-65657D01*
X637461Y-67407D01*
X635932Y-68573D01*
X634186Y-68865D01*
G01X555436Y-113865D02*
Y-96365D01*
X552816Y-99865D01*
G01Y-113865D02*
X558056D01*
G01X568133Y-110365D02*
X569442Y-112407D01*
X571189Y-113573D01*
X573154Y-113865D01*
X574901Y-113573D01*
X576648Y-112115D01*
X577739Y-110365D01*
X577958Y-108615D01*
X577521Y-106574D01*
X575993Y-105115D01*
X574464Y-104532D01*
X572499D01*
G01X574464D02*
X575774Y-103657D01*
X576866Y-102199D01*
X577303Y-100449D01*
X576866Y-98698D01*
X575774Y-97240D01*
X573809Y-96365D01*
X571844Y-96657D01*
X569879Y-97824D01*
G01X590436Y-113865D02*
Y-96365D01*
X587816Y-99865D01*
G01Y-113865D02*
X593056D01*
G01X603133Y-110365D02*
X604442Y-112407D01*
X606189Y-113573D01*
X608154Y-113865D01*
X609901Y-113573D01*
X611648Y-112115D01*
X612739Y-110365D01*
X612958Y-108615D01*
X612521Y-106574D01*
X610993Y-105115D01*
X609464Y-104532D01*
X607499D01*
G01X609464D02*
X610774Y-103657D01*
X611866Y-102199D01*
X612303Y-100449D01*
X611866Y-98698D01*
X610774Y-97240D01*
X608809Y-96365D01*
X606844Y-96657D01*
X604879Y-97824D01*
G01X625436Y-96365D02*
X623689Y-96948D01*
X622379Y-98407D01*
X621506Y-100156D01*
X620851Y-102490D01*
X620633Y-105115D01*
X620851Y-107740D01*
X621506Y-110074D01*
X622379Y-111824D01*
X623689Y-113282D01*
X625436Y-113865D01*
X627182Y-113282D01*
X628493Y-111824D01*
X629366Y-110074D01*
X630021Y-107740D01*
X630239Y-105115D01*
X630021Y-102490D01*
X629366Y-100156D01*
X628493Y-98407D01*
X627182Y-96948D01*
X625436Y-96365D01*
G01X685027Y-51365D02*
X690486Y-68865D01*
X695945Y-51365D01*
G01X712353Y-68865D02*
X703619D01*
Y-51365D01*
X712353D01*
G01X708859Y-59823D02*
X703619D01*
G01X721119Y-68865D02*
Y-51365D01*
X726578D01*
X728324Y-52240D01*
X729416Y-53407D01*
X729853Y-55740D01*
X729416Y-58074D01*
X728106Y-59532D01*
X726578Y-60407D01*
X721119D01*
G01X726578D02*
X729853Y-68865D01*
G01X742986Y-69448D02*
X742549Y-69157D01*
Y-68573D01*
X742986Y-68282D01*
X743423Y-68573D01*
Y-69157D01*
X742986Y-69448D01*
G01X707986Y-113865D02*
Y-96365D01*
X705366Y-99865D01*
G01Y-113865D02*
X710606D01*
G01X727232Y-104532D02*
X728106Y-103657D01*
X728761Y-102199D01*
X729198Y-100156D01*
X728761Y-98407D01*
X727888Y-97240D01*
X726359Y-96365D01*
X720464D01*
Y-113865D01*
X727669D01*
X729198Y-112699D01*
X730071Y-110948D01*
X730508Y-108907D01*
X730071Y-106865D01*
X728761Y-105115D01*
X727232Y-104532D01*
X720464D01*
G01X818569Y-51365D02*
Y-68865D01*
X827303D01*
G01X844366D02*
Y-57199D01*
G01Y-59240D02*
X843493Y-58074D01*
X842182Y-57490D01*
X840654Y-57199D01*
X839126Y-57782D01*
X837816Y-58948D01*
X836942Y-60698D01*
X836506Y-63032D01*
X836942Y-65365D01*
X837816Y-67115D01*
X839126Y-68282D01*
X840654Y-68865D01*
X842182Y-68573D01*
X843493Y-67699D01*
X844366Y-66532D01*
G01X853351Y-74115D02*
X854661Y-74698D01*
X856408Y-74115D01*
X857499Y-72949D01*
X858373Y-71490D01*
X859682Y-66824D01*
X862521Y-57199D01*
G01X855534D02*
X859682Y-66824D01*
G01X872161Y-60990D02*
X879148D01*
X878493Y-58948D01*
X877401Y-57782D01*
X875873Y-57199D01*
X874344Y-57490D01*
X873034Y-58365D01*
X872161Y-60407D01*
X871724Y-62157D01*
Y-63907D01*
X872161Y-65657D01*
X873253Y-67407D01*
X874563Y-68573D01*
X876091Y-68865D01*
X877619Y-68282D01*
X879148Y-66532D01*
G01X889879Y-68865D02*
Y-57199D01*
G01Y-59532D02*
X890971Y-58365D01*
X892063Y-57490D01*
X893591Y-57199D01*
X894682Y-57490D01*
X895993Y-58365D01*
G01X844819Y-96365D02*
Y-113865D01*
X853553D01*
G01X866686D02*
Y-96365D01*
X864066Y-99865D01*
G01Y-113865D02*
X869306D01*
G01X943619Y-110365D02*
X944711Y-112115D01*
X946021Y-113282D01*
X947549Y-113865D01*
X949296Y-113282D01*
X950606Y-112115D01*
X951916Y-110365D01*
X952353Y-108032D01*
Y-96365D01*
G01X965486Y-113865D02*
X963739Y-113573D01*
X962211Y-112407D01*
X960901Y-110657D01*
X960027Y-108615D01*
X959591Y-106282D01*
Y-103948D01*
X960027Y-101615D01*
X960901Y-99573D01*
X962211Y-97824D01*
X963739Y-96657D01*
X965486Y-96365D01*
X967232Y-96657D01*
X968761Y-97824D01*
X970071Y-99573D01*
X970945Y-101615D01*
X971381Y-103948D01*
Y-106282D01*
X970945Y-108615D01*
X970071Y-110657D01*
X968761Y-112407D01*
X967232Y-113573D01*
X965486Y-113865D01*
G01X978401Y-111532D02*
X980148Y-112990D01*
X982113Y-113865D01*
X983859D01*
X985606Y-112990D01*
X986916Y-111532D01*
X987571Y-109490D01*
X987134Y-107449D01*
X986043Y-105698D01*
X984078Y-104532D01*
X981458Y-103948D01*
X979929Y-102782D01*
X979274Y-100740D01*
X979711Y-98698D01*
X980803Y-97240D01*
X982331Y-96365D01*
X983859D01*
X985388Y-96948D01*
X986698Y-98407D01*
G01X1004853Y-113865D02*
X996119D01*
Y-96365D01*
X1004853D01*
G01X1001359Y-104823D02*
X996119D01*
G01X1013619Y-113865D02*
Y-96365D01*
X1018859D01*
X1020606Y-97240D01*
X1021916Y-99282D01*
X1022353Y-101615D01*
X1021916Y-103948D01*
X1020824Y-105698D01*
X1018859Y-106574D01*
X1013619D01*
G01X1030901Y-113865D02*
Y-96365D01*
G01X1040071D02*
Y-113865D01*
G01Y-105115D02*
X1030901D01*
G01X1066119Y-96365D02*
Y-113865D01*
X1074853D01*
G01X1082527D02*
X1087986Y-96365D01*
X1093445Y-113865D01*
G01X1091479Y-107740D02*
X1084492D01*
G01X1100683Y-96365D02*
Y-108907D01*
X1101556Y-111532D01*
X1103303Y-113282D01*
X1105486Y-113865D01*
X1107669Y-113282D01*
X1109416Y-111532D01*
X1110289Y-108907D01*
Y-96365D01*
G01X960683Y-68865D02*
Y-51365D01*
X965049D01*
X966796Y-52240D01*
X968106Y-53407D01*
X969198Y-55156D01*
X970071Y-57199D01*
X970289Y-60115D01*
X970071Y-63032D01*
X969198Y-65074D01*
X968106Y-66824D01*
X966796Y-67990D01*
X965049Y-68865D01*
X960683D01*
G01X979711Y-60990D02*
X986698D01*
X986043Y-58948D01*
X984951Y-57782D01*
X983423Y-57199D01*
X981894Y-57490D01*
X980584Y-58365D01*
X979711Y-60407D01*
X979274Y-62157D01*
Y-63907D01*
X979711Y-65657D01*
X980803Y-67407D01*
X982113Y-68573D01*
X983641Y-68865D01*
X985169Y-68282D01*
X986698Y-66532D01*
G01X997211Y-66824D02*
X998303Y-67990D01*
X999831Y-68865D01*
X1001141D01*
X1002451Y-68282D01*
X1003324Y-67407D01*
X1003761Y-66241D01*
X1003543Y-64490D01*
X1002669Y-63615D01*
X998739Y-61865D01*
X997866Y-59823D01*
X998303Y-58365D01*
X999176Y-57490D01*
X1000486Y-57199D01*
X1001796Y-57490D01*
X1003106Y-58365D01*
G01X1017986Y-57199D02*
Y-68865D01*
G01Y-52532D02*
X1017549Y-52240D01*
Y-51657D01*
X1017986Y-51365D01*
X1018423Y-51657D01*
Y-52240D01*
X1017986Y-52532D01*
G01X1032429Y-73240D02*
X1033958Y-74407D01*
X1035704Y-74698D01*
X1037232Y-74407D01*
X1038543Y-72949D01*
X1039416Y-70907D01*
Y-57199D01*
G01Y-59532D02*
X1038543Y-58365D01*
X1037232Y-57490D01*
X1035704Y-57199D01*
X1033958Y-57782D01*
X1032866Y-58948D01*
X1031992Y-60990D01*
X1031556Y-63032D01*
X1031774Y-64782D01*
X1032648Y-66824D01*
X1033958Y-68282D01*
X1035704Y-68865D01*
X1037014Y-68573D01*
X1038543Y-67407D01*
X1039416Y-66241D01*
G01X1049274Y-68865D02*
Y-57199D01*
G01Y-60115D02*
X1050148Y-58657D01*
X1051458Y-57490D01*
X1053204Y-57199D01*
X1054732Y-57490D01*
X1056043Y-58657D01*
X1056698Y-60698D01*
Y-68865D01*
G01X1067211Y-60990D02*
X1074198D01*
X1073543Y-58948D01*
X1072451Y-57782D01*
X1070923Y-57199D01*
X1069394Y-57490D01*
X1068084Y-58365D01*
X1067211Y-60407D01*
X1066774Y-62157D01*
Y-63907D01*
X1067211Y-65657D01*
X1068303Y-67407D01*
X1069613Y-68573D01*
X1071141Y-68865D01*
X1072669Y-68282D01*
X1074198Y-66532D01*
G01X1084929Y-68865D02*
Y-57199D01*
G01Y-59532D02*
X1086021Y-58365D01*
X1087113Y-57490D01*
X1088641Y-57199D01*
X1089732Y-57490D01*
X1091043Y-58365D01*
G01X1131686Y-113865D02*
Y-96365D01*
X1129066Y-99865D01*
G01Y-113865D02*
X1134306D01*
G01X1149186D02*
Y-96365D01*
X1146566Y-99865D01*
G01Y-113865D02*
X1151806D01*
G01X1162756Y-114448D02*
X1170616Y-96365D01*
G01X1184186Y-113865D02*
Y-96365D01*
X1181566Y-99865D01*
G01Y-113865D02*
X1186806D01*
G01X1196883Y-110365D02*
X1198192Y-112407D01*
X1199939Y-113573D01*
X1201904Y-113865D01*
X1203651Y-113573D01*
X1205398Y-112115D01*
X1206489Y-110365D01*
X1206708Y-108615D01*
X1206271Y-106574D01*
X1204743Y-105115D01*
X1203214Y-104532D01*
X1201249D01*
G01X1203214D02*
X1204524Y-103657D01*
X1205616Y-102199D01*
X1206053Y-100449D01*
X1205616Y-98698D01*
X1204524Y-97240D01*
X1202559Y-96365D01*
X1200594Y-96657D01*
X1198629Y-97824D01*
G01X1215256Y-114448D02*
X1223116Y-96365D01*
G01X1232538Y-99282D02*
X1233848Y-97532D01*
X1235376Y-96657D01*
X1237123Y-96365D01*
X1239306Y-96948D01*
X1240834Y-98407D01*
X1241271Y-100156D01*
X1241053Y-101907D01*
X1240179Y-103365D01*
X1235813Y-106282D01*
X1233848Y-108323D01*
X1232538Y-111241D01*
X1232101Y-113865D01*
X1241271D01*
G01X1254186Y-96365D02*
X1252439Y-96948D01*
X1251129Y-98407D01*
X1250256Y-100156D01*
X1249601Y-102490D01*
X1249383Y-105115D01*
X1249601Y-107740D01*
X1250256Y-110074D01*
X1251129Y-111824D01*
X1252439Y-113282D01*
X1254186Y-113865D01*
X1255932Y-113282D01*
X1257243Y-111824D01*
X1258116Y-110074D01*
X1258771Y-107740D01*
X1258989Y-105115D01*
X1258771Y-102490D01*
X1258116Y-100156D01*
X1257243Y-98407D01*
X1255932Y-96948D01*
X1254186Y-96365D01*
G01X1271686Y-113865D02*
Y-96365D01*
X1269066Y-99865D01*
G01Y-113865D02*
X1274306D01*
G01X1291806D02*
Y-96365D01*
X1283727Y-108907D01*
X1294645D01*
G01X1179383Y-68865D02*
Y-51365D01*
X1183749D01*
X1185496Y-52240D01*
X1186806Y-53407D01*
X1187898Y-55156D01*
X1188771Y-57199D01*
X1188989Y-60115D01*
X1188771Y-63032D01*
X1187898Y-65074D01*
X1186806Y-66824D01*
X1185496Y-67990D01*
X1183749Y-68865D01*
X1179383D01*
G01X1205616D02*
Y-57199D01*
G01Y-59240D02*
X1204743Y-58074D01*
X1203432Y-57490D01*
X1201904Y-57199D01*
X1200376Y-57782D01*
X1199066Y-58948D01*
X1198192Y-60698D01*
X1197756Y-63032D01*
X1198192Y-65365D01*
X1199066Y-67115D01*
X1200376Y-68282D01*
X1201904Y-68865D01*
X1203432Y-68573D01*
X1204743Y-67699D01*
X1205616Y-66532D01*
G01X1219186Y-51365D02*
Y-68865D01*
G01X1216129Y-57199D02*
X1222243D01*
G01X1233411Y-60990D02*
X1240398D01*
X1239743Y-58948D01*
X1238651Y-57782D01*
X1237123Y-57199D01*
X1235594Y-57490D01*
X1234284Y-58365D01*
X1233411Y-60407D01*
X1232974Y-62157D01*
Y-63907D01*
X1233411Y-65657D01*
X1234503Y-67407D01*
X1235813Y-68573D01*
X1237341Y-68865D01*
X1238869Y-68282D01*
X1240398Y-66532D01*
G01X379212Y131601D02*
Y131541D01*
X380443Y130310D01*
Y130102D01*
G01X387032Y130101D02*
X388332Y128801D01*
Y121639D01*
X389932Y120039D01*
Y112595D01*
X389700Y112363D01*
G01X381280Y191550D02*
X381320D01*
X382309Y190561D01*
X383332D01*
G01X381140Y187960D02*
X382933D01*
X383332Y187561D01*
G01X392092Y131601D02*
Y131971D01*
X390205Y133858D01*
G01X394852Y131601D02*
X393279Y130028D01*
X391680D01*
X390100Y128448D01*
Y127600D01*
G01X391152Y180061D02*
X389852Y181361D01*
Y187148D01*
X389300Y187700D01*
G54D31*
X39000Y158000D03*
X46300Y212700D03*
Y207800D03*
X43500Y198800D03*
Y203700D03*
X46500D03*
Y198800D03*
X35000Y222500D03*
Y219000D03*
Y229500D03*
Y226000D03*
Y236500D03*
Y233000D03*
Y243500D03*
Y240000D03*
Y250500D03*
Y247000D03*
Y257500D03*
Y254000D03*
X49300Y212700D03*
Y207800D03*
X64700Y198300D03*
Y201800D03*
X73900Y207200D03*
X80000Y85000D03*
X92300Y207100D03*
X80500Y249800D03*
X89500Y261500D03*
X183000Y75500D03*
X225800Y89900D03*
X440000Y278000D03*
X538500Y234100D03*
X611500Y96000D03*
Y93000D03*
X705000Y192500D03*
X721700Y119700D03*
Y116400D03*
X739200Y111100D03*
X745800Y108100D03*
X748000Y155500D03*
X779500Y16000D03*
G54D133*
X794500Y77800D03*
Y93200D03*
G54D13*
X20000Y103800D03*
Y97200D03*
X32200Y98400D03*
Y91800D03*
X26100Y109800D03*
Y116400D03*
X33200Y109800D03*
Y116400D03*
X28550Y161900D03*
Y168500D03*
X62200Y131700D03*
Y138300D03*
X74000Y52700D03*
Y59300D03*
X79100Y89000D03*
Y95600D03*
X130500Y213100D03*
X137600D03*
X130500Y219700D03*
X137600D03*
X144700Y213100D03*
Y219700D03*
X165900Y208700D03*
Y215300D03*
X184500Y259800D03*
Y253200D03*
X188500Y264700D03*
Y271300D03*
X181000Y264700D03*
Y271300D03*
X192000Y259800D03*
Y253200D03*
X211500Y264700D03*
Y271300D03*
X219000Y264700D03*
Y271300D03*
X233500Y226800D03*
Y220200D03*
X226000Y226800D03*
Y220200D03*
X228500Y247700D03*
Y254300D03*
X236700Y207600D03*
Y201000D03*
X243800Y207600D03*
Y201000D03*
X241000Y226800D03*
Y220200D03*
X248500Y226800D03*
Y220200D03*
X236000Y247700D03*
Y254300D03*
X250600Y247700D03*
Y254300D03*
X243500Y247700D03*
Y254300D03*
X257700Y247700D03*
Y254300D03*
X339000Y56200D03*
Y62800D03*
X346500Y56200D03*
Y62800D03*
X377000Y52200D03*
Y58800D03*
X583000Y229700D03*
Y236300D03*
X590500Y229700D03*
Y236300D03*
X617000Y47707D03*
Y54307D03*
X624500Y47707D03*
Y54307D03*
X630000Y230200D03*
Y236800D03*
X637500Y230200D03*
Y236800D03*
X661000Y47707D03*
Y54307D03*
X668100Y47707D03*
Y54307D03*
G54D22*
X25800Y146500D03*
X19200D03*
X25800Y139400D03*
X19200D03*
X44450Y255500D03*
X64300Y118500D03*
X57700D03*
X60300Y171900D03*
X55800Y259000D03*
X62400D03*
X51050Y255500D03*
X66900Y171900D03*
X114200Y196500D03*
X120800D03*
X114200Y204000D03*
X120800D03*
X153200Y61000D03*
X159800D03*
X222200Y191000D03*
X228800D03*
X457200Y162200D03*
X463800D03*
X457200Y155100D03*
X463800D03*
X664300Y105000D03*
X657700D03*
X664300Y97500D03*
X657700D03*
X664300Y133000D03*
X657700D03*
X664300Y125500D03*
X657700D03*
X787700Y114000D03*
Y123000D03*
X780700Y256200D03*
X774100D03*
X794300Y114000D03*
Y123000D03*
X797800Y229400D03*
X804400D03*
X797800Y222300D03*
X804400D03*
G54D115*
X662362Y167248D03*
X653638D03*
X662362Y160752D03*
X653638D03*
G54D40*
X73057Y113500D03*
X93943D03*
G54D124*
X741167Y124313D03*
X739592D03*
Y143213D03*
X741167D03*
X750616Y124313D03*
X749041D03*
X747466D03*
X745891D03*
X744317D03*
X742742D03*
Y143213D03*
X744317D03*
X745891D03*
X747466D03*
X749041D03*
X750616D03*
G54D106*
X551500Y187500D03*
X562000Y85000D03*
X570500Y190500D03*
X558500Y194500D03*
X572100Y196600D03*
X595350Y193050D03*
X609500Y200500D03*
X806200Y91000D03*
Y97000D03*
Y103000D03*
Y109000D03*
G54D143*
G01X49200Y244400D02*
X45900D01*
X43500Y242000D01*
G01X44000Y234000D02*
Y236200D01*
X49200Y241400D01*
G01X52500Y234800D02*
Y231000D01*
X51000Y229500D01*
G01X66800Y275200D02*
X63900D01*
X61200Y272500D01*
G01X64200Y269500D02*
X64700Y270000D01*
Y272500D01*
G01X92600Y207100D02*
X92100Y206600D01*
Y204808D01*
X92900Y204008D01*
G01X92600Y207100D02*
X92700Y207200D01*
X91400Y208500D01*
Y209615D01*
X90365Y210650D01*
X87865D01*
X85200Y213315D01*
Y216413D01*
X85287Y216500D01*
Y218689D01*
G01X92900Y204008D02*
X92800Y203908D01*
Y203907D01*
X91700Y202807D01*
Y201500D01*
X92600Y200600D01*
G01X89600D02*
X89800Y200800D01*
Y203700D01*
X89500Y204000D01*
G01D02*
X89700Y204200D01*
Y206400D01*
X89000Y207100D01*
G01D02*
X90400Y208500D01*
Y209200D01*
X89950Y209650D01*
X87450D01*
X84200Y212900D01*
Y216513D01*
X83713Y217000D01*
Y218689D01*
G01X165755Y132105D02*
X161267D01*
X157975Y135397D01*
Y145933D01*
X154450Y149458D01*
Y157100D01*
X156070Y158720D01*
G01X145000Y155700D02*
Y155744D01*
X144500Y156244D01*
Y158900D01*
G01X175600Y94500D02*
X175100Y95000D01*
X172383D01*
X170955Y96428D01*
Y97536D01*
X169851Y98640D01*
X165755D01*
G01X218500Y49500D02*
X221717Y46283D01*
Y36796D01*
X221850Y36663D01*
Y24392D01*
G01X246600Y73700D02*
Y75050D01*
X251100Y79550D01*
X258000D01*
G01X246465Y164600D02*
X244600D01*
X244000Y164000D01*
Y161687D01*
X242865Y160552D01*
Y159018D01*
X244073Y157810D01*
X249000D01*
G01X258000Y79550D02*
X259750D01*
X264900Y84700D01*
X267000D01*
G01X257977Y163423D02*
X256800Y164600D01*
X254335D01*
G01D02*
Y159035D01*
X253110Y157810D01*
X249000D01*
G01X284500Y167300D02*
X283200Y166000D01*
X277643D01*
X276500Y164857D01*
Y162400D01*
X275316Y161216D01*
X269784D01*
X268500Y162500D01*
X258900D01*
X257977Y163423D01*
G01X270000Y81300D02*
X272000D01*
X273700Y83000D01*
X280631D01*
X282306Y84675D01*
X291106D01*
X293031Y86600D01*
X297234D01*
X305026Y94392D01*
Y96874D01*
X303400Y98500D01*
G01X267000Y84700D02*
X270000D01*
G01X273791Y200740D02*
Y196818D01*
X279100Y191509D01*
Y187600D01*
X280700Y186000D01*
G01X274162Y243180D02*
X273450Y242468D01*
Y235192D01*
X276700Y231942D01*
Y228900D01*
X277000Y228600D01*
G01D02*
X278900Y226700D01*
Y222200D01*
X275700Y219000D01*
G01X274000Y228600D02*
X271300D01*
X271000Y228900D01*
G01X280950Y243180D02*
X274162D01*
G01X271000Y228900D02*
Y232000D01*
X270900Y232100D01*
G01D02*
Y235433D01*
X271200Y235733D01*
G01X280950Y245740D02*
X273539D01*
X271912Y244113D01*
Y236445D01*
X271200Y235733D01*
G01X280950Y248300D02*
X277800D01*
X275150Y250950D01*
Y253950D01*
X275300Y254100D01*
G01X278700Y254240D02*
X278000Y253540D01*
Y252000D01*
X279145Y250855D01*
X280950D01*
G01X291700Y147500D02*
X295700D01*
X297200Y146000D01*
G01X286800Y164000D02*
Y165500D01*
X285000Y167300D01*
X284500D01*
G01Y170700D02*
X284850Y171050D01*
Y173767D01*
X286433Y175350D01*
X291650D01*
X293500Y173500D01*
X293700D01*
G01D02*
X294500D01*
X303297Y164703D01*
X304303D01*
G01X282209Y197000D02*
Y197209D01*
X286500Y201500D01*
G01X289800Y185500D02*
X281200D01*
X280700Y186000D01*
G01X282209Y206760D02*
X280000Y204551D01*
Y195292D01*
X282460Y192832D01*
Y189400D01*
G01X286500Y201500D02*
X288125Y203125D01*
X305300D01*
G01X285800Y219000D02*
X286100Y218700D01*
X289500D01*
G01D02*
X289940D01*
X292685Y221445D01*
G01X280950Y235500D02*
X283343D01*
X293051Y225792D01*
Y221811D01*
X292685Y221445D01*
G01X280950Y240620D02*
X283620D01*
X284500Y241500D01*
Y255700D01*
X286236Y257436D01*
X305300D01*
X305664Y257800D01*
X308000D01*
G01X306000Y253600D02*
Y254100D01*
X303950Y256150D01*
X286365D01*
X285500Y255285D01*
Y240530D01*
X283030Y238060D01*
X280950D01*
G01X298800Y95400D02*
X299000D01*
X299200Y95200D01*
X303376D01*
G01X297200Y146000D02*
X299856Y148656D01*
X311985D01*
X312740Y149411D01*
X315020D01*
X317570Y146861D01*
X318702D01*
G01Y164591D02*
X317882Y163771D01*
Y163740D01*
X316653Y162511D01*
X308017D01*
X307915Y162409D01*
X306547D01*
X304303Y164653D01*
Y164703D01*
G01X302650Y235500D02*
X309200D01*
X310500Y234200D01*
G01X302650Y240620D02*
X308020D01*
X313000Y245600D01*
Y250000D01*
G01X302650Y243180D02*
X307080D01*
X309700Y245800D01*
G01X309400Y253600D02*
Y256400D01*
X308000Y257800D01*
G01X309700Y245800D02*
Y249883D01*
X311500Y251683D01*
Y257800D01*
G01X330812Y204091D02*
Y204586D01*
X331621Y205395D01*
Y207452D01*
X328673Y210400D01*
X322200D01*
X321600Y211000D01*
G01X330932Y201181D02*
X329562Y203700D01*
Y204609D01*
X330721Y205768D01*
Y207079D01*
X328300Y209500D01*
X322400D01*
X321600Y208700D01*
G01X334432Y201181D02*
X332696Y204100D01*
Y207650D01*
X326646Y213700D01*
X325146D01*
X324756Y213310D01*
X323256D01*
X322866Y213700D01*
X317800D01*
X317200Y213100D01*
G01X334462Y204101D02*
X333596Y204967D01*
Y208023D01*
X327019Y214600D01*
X317900D01*
X317200Y215300D01*
G01X310500Y234200D02*
X313600D01*
X314100Y233700D01*
G01X322000Y257800D02*
X319000D01*
G01D02*
X317150Y255950D01*
X314733D01*
X313600Y254817D01*
Y250600D01*
X313000Y250000D01*
G01X314500Y257800D02*
X311500D01*
G01X322700Y277700D02*
X323900Y276500D01*
X337168D01*
X347969Y287301D01*
X759099D01*
X765400Y281000D01*
G01X762000D02*
X756699Y286301D01*
X348384D01*
X337583Y275500D01*
X321700D01*
X319400Y277800D01*
Y278800D01*
G01X329322Y129021D02*
X329022Y128721D01*
Y125437D01*
X329031Y125428D01*
G01X325763Y141958D02*
X325863Y141858D01*
Y141560D01*
X327822Y139601D01*
G01X329322Y144661D02*
X327958Y143297D01*
Y142013D01*
X327963Y142008D01*
G01X336822Y155241D02*
X335964Y156099D01*
Y158512D01*
G01X343000Y126200D02*
X343800Y127000D01*
X346331D01*
X347932Y128601D01*
G01X342822Y170881D02*
X342893D01*
X344100Y169674D01*
Y169531D01*
X344165Y169466D01*
G01X368632Y118101D02*
Y117931D01*
X370000Y116563D01*
G01X368632Y121101D02*
Y121217D01*
X367321Y122528D01*
G01X368632Y127101D02*
X370121Y125612D01*
Y125528D01*
G01X371392Y130101D02*
X372821Y128672D01*
Y125628D01*
G01X360042Y154331D02*
X358673Y155700D01*
X358500D01*
G01X375782Y170081D02*
X374103Y168402D01*
X371398D01*
X371100Y168700D01*
G01X382082Y157481D02*
X382093D01*
X383500Y158888D01*
Y159000D01*
G01X382082Y160631D02*
X382132D01*
X383700Y162199D01*
G01X380500Y162025D02*
X380336D01*
X378942Y160631D01*
G01X377500Y165240D02*
X377300Y165440D01*
Y170700D01*
X375782Y172218D01*
Y173231D01*
G01Y157481D02*
X374300Y155999D01*
Y155800D01*
G01X374100Y159150D02*
X374301D01*
X375782Y160631D01*
G01X394682Y144881D02*
Y144958D01*
X393204Y146436D01*
G01X391542Y144881D02*
X391535D01*
X389848Y146568D01*
G01X400982Y166931D02*
X400984D01*
X402064Y168011D01*
X405182D01*
X405764Y167429D01*
X407100D01*
G01X465500Y146763D02*
X466500Y145763D01*
X484348D01*
X490000Y151415D01*
Y157000D01*
X476550Y170450D01*
Y190484D01*
X455550Y211484D01*
Y223450D01*
X442500Y236500D01*
X408200D01*
X400861Y243839D01*
X399438D01*
G01X465500Y143763D02*
X466500Y144763D01*
X484763D01*
X491000Y151000D01*
Y157415D01*
X477550Y170865D01*
Y190899D01*
X456550Y211899D01*
Y223865D01*
X442915Y237500D01*
X408615D01*
X401838Y244277D01*
Y246248D01*
G01X404302Y166761D02*
X405134Y165929D01*
X408066D01*
X409300Y167163D01*
G01X442100Y7006D02*
Y5400D01*
X443500Y4000D01*
X460151D01*
X467500Y11349D01*
X475622D01*
X505000Y40727D01*
Y42425D01*
X505882Y43307D01*
X584807D01*
X615469Y73969D01*
G01X437372Y149981D02*
X438042Y150651D01*
X440500D01*
X440849Y151000D01*
X444000D01*
X448189Y146811D01*
X450800D01*
G01X439382Y151901D02*
X439481Y152000D01*
X444415D01*
X448604Y147811D01*
X453900D01*
G01X462200Y147063D02*
X465200D01*
X465500Y146763D01*
G01X450800Y145400D02*
Y146811D01*
G01X458800Y143563D02*
X457863Y144500D01*
X455796D01*
X453485Y146811D01*
X450800D01*
G01X462200Y143563D02*
X465300D01*
X465500Y143763D01*
G01X453900Y149150D02*
Y147811D01*
G01X458800Y147063D02*
X457237Y145500D01*
X456211D01*
X453900Y147811D01*
G01X562000Y80069D02*
Y85000D01*
G01Y80069D02*
X565269D01*
X566500Y81300D01*
G01X562000Y85000D02*
Y89000D01*
X564955Y91955D01*
Y94200D01*
G01X582670D02*
Y89030D01*
X582000Y88360D01*
Y74000D01*
G01X578795Y183300D02*
Y182355D01*
X580700Y180450D01*
Y177800D01*
G01X622500Y78300D02*
X620700Y76500D01*
X618000D01*
X615469Y73969D01*
G01X617931Y133000D02*
X611976Y138955D01*
X610955D01*
G01X623500Y150000D02*
X611000D01*
X608270Y152730D01*
X603800D01*
G01X610955Y138955D02*
X603800D01*
G01X613590Y162596D02*
X611692Y164494D01*
Y164545D01*
X603800D01*
G01X618500Y159000D02*
X617186D01*
X613590Y162596D01*
G01X636719Y154972D02*
X634833Y156858D01*
X632552D01*
X628344Y152650D01*
X617500D01*
G01D02*
X611350D01*
X609300Y154700D01*
X603800D01*
G01X643500Y155000D02*
X639642Y158858D01*
X631475D01*
X629767Y157150D01*
X612500D01*
G01D02*
X611010Y158640D01*
X603800D01*
G01X618500Y162800D02*
X614790Y166510D01*
X603800D01*
G01X626500Y154900D02*
X611567D01*
X609797Y156670D01*
X603800D01*
G01X623700Y162399D02*
X617619Y168480D01*
X603800D01*
G01Y170450D02*
X621497D01*
X624900Y167047D01*
G01X622500Y85300D02*
X620600Y83400D01*
Y80200D01*
X622500Y78300D01*
G01X631500Y117823D02*
Y120000D01*
X635225Y123725D01*
Y125500D01*
G01X626800Y133000D02*
Y129500D01*
X625800Y128500D01*
G01X623069Y133000D02*
Y129331D01*
X623900Y128500D01*
X625800D01*
G01X633319Y155008D02*
X628312Y150000D01*
X623500D01*
G01X625500Y159000D02*
Y160599D01*
X623700Y162399D01*
G01X622000Y159000D02*
Y159300D01*
X618500Y162800D01*
G01X626500Y154900D02*
X628932D01*
X631890Y157858D01*
X637524D01*
X640110Y155272D01*
G01X629000Y159000D02*
Y162947D01*
X624900Y167047D01*
G01X633000Y162500D02*
X636300D01*
X636800Y163000D01*
G01X633000Y162500D02*
Y166069D01*
X634431Y167500D01*
G01X624209Y183260D02*
X625800Y181669D01*
Y178500D01*
G01X626300Y198250D02*
X622009Y193959D01*
Y185460D01*
X624209Y183260D01*
G01X635150Y185000D02*
X628650D01*
G01D02*
X625949D01*
X624209Y183260D01*
G01X634000Y129300D02*
X635225Y128075D01*
Y125500D01*
G01X639569Y167500D02*
X642919Y170850D01*
X658050D01*
X661000Y173800D01*
G01X651750Y182500D02*
X658250D01*
G01D02*
X665000D01*
X666500Y184000D01*
G01X661600Y197300D02*
X663400D01*
X666500Y194200D01*
Y184000D01*
G01X691500Y213750D02*
Y219500D01*
G01D02*
Y223300D01*
G01D02*
X688500D01*
G01X694500D02*
X697500D01*
G01X682544Y219456D02*
X682500Y219500D01*
Y223300D01*
G01X686500Y213750D02*
Y215500D01*
X682544Y219456D01*
G01X682500Y223300D02*
X685500D01*
G01X696500Y213750D02*
Y218900D01*
X697200Y219600D01*
G01X697500Y223300D02*
Y219900D01*
X697200Y219600D01*
G54D41*
X84500Y230000D03*
G54D50*
X104700Y259800D03*
Y263800D03*
X109900Y261800D03*
G54D23*
X19200Y156200D03*
X25800D03*
G54D116*
X683000Y104500D03*
Y132500D03*
G54D134*
X790015Y154371D03*
X795015D03*
X800015D03*
G54D107*
X562000Y74931D03*
Y80069D03*
G54D32*
X48000Y217500D03*
X49500Y116000D03*
X79400Y139200D03*
X74200Y194000D03*
X71100Y252600D03*
X102500Y197000D03*
Y194000D03*
X179100Y127700D03*
X180100Y176000D03*
X189500Y193500D03*
X262000Y49500D03*
X282500Y219000D03*
X423000Y260500D03*
X471200Y245500D03*
X503500Y155000D03*
X511500Y176000D03*
Y179000D03*
X520500Y215500D03*
X565000Y227000D03*
X601000Y46000D03*
X617500Y208000D03*
X667500Y161000D03*
Y171500D03*
G54D125*
X735654Y128251D03*
Y129826D03*
Y131401D03*
Y132976D03*
Y134550D03*
Y136125D03*
Y137700D03*
Y139275D03*
X754554Y136125D03*
Y134550D03*
Y132976D03*
Y131401D03*
Y129826D03*
Y128251D03*
Y139275D03*
Y137700D03*
G54D14*
G01X10636Y-27865D02*
G02I-12000J0D01*
G01X14636D02*
X-17364D01*
G01X5486D02*
G02I-6850J0D01*
G01X-1364Y-43865D02*
Y-11865D01*
G01X14636Y-43865D02*
Y-123865D01*
G01D02*
X1309236D01*
G01X14636Y-79365D02*
X1309236D01*
G01X14636Y-43865D02*
X1309236D01*
G01X26100Y97900D02*
X26600Y98400D01*
X32200D01*
G01D02*
X32352Y98248D01*
X38464D01*
G01X20000Y129600D02*
Y133400D01*
X20300Y133700D01*
G01D02*
X22200D01*
X25800Y137300D01*
Y139400D01*
G01X37500Y124300D02*
X40500D01*
G01X49200Y250400D02*
X44400D01*
G01X52800Y116000D02*
X55200D01*
X57700Y118500D01*
G01X62200Y131700D02*
X67100D01*
X68800Y133400D01*
G01X57600Y214200D02*
X57500Y214300D01*
X54000D01*
G01X79100Y89000D02*
X76880D01*
X74580Y86700D01*
X73100D01*
G01D02*
X72500Y87300D01*
Y90900D01*
G01X70000Y97000D02*
X71600D01*
X72500Y96100D01*
G01X67200Y177500D02*
X69900D01*
X71800Y175600D01*
G01X67200Y177500D02*
X66900Y177200D01*
Y171900D01*
G01X99900Y239450D02*
X99650Y239700D01*
X98794D01*
X97183Y241311D01*
X95800D01*
G01X94420Y258000D02*
X93900Y258520D01*
Y261700D01*
G01Y265100D02*
X97000D01*
G01X104000Y214100D02*
X102200D01*
X100200Y216100D01*
X99900D01*
G01X113400Y214600D02*
X112900Y214100D01*
X109200D01*
G01X97194Y218206D02*
X99300Y216100D01*
X99900D01*
G01X109200Y224200D02*
X110400Y225400D01*
X112800D01*
G01X113500Y217800D02*
X110500D01*
X109200Y219100D01*
G01X101000Y243500D02*
Y240550D01*
X99900Y239450D01*
G01X104000Y235400D02*
X103687D01*
X100700Y232413D01*
Y231800D01*
G01X103600Y239500D02*
X104000Y239100D01*
Y235400D01*
G01X109200D02*
Y231600D01*
X109000Y231400D01*
G01X113100Y237900D02*
X111500Y239500D01*
X110166D01*
G01X107000D02*
X110166D01*
G01X97000Y261700D02*
X99420Y259280D01*
Y258000D01*
G01X101000Y248700D02*
X104800D01*
X104900Y248800D01*
G01X104700Y259800D02*
X106700D01*
G01X100700Y262900D02*
Y262800D01*
X99600Y261700D01*
X97000D01*
G01X100000Y267400D02*
X97700Y265100D01*
X97000D01*
G01X104400Y268500D02*
Y264100D01*
X104700Y263800D01*
G01X104400Y268500D02*
Y269600D01*
X101400Y272600D01*
G01D02*
X98691D01*
X96391Y270300D01*
G01X116800Y214600D02*
Y211800D01*
X116500Y211500D01*
Y211200D01*
G01X116900Y217800D02*
X116800Y217700D01*
Y214600D01*
G01X112700Y221200D02*
X113500Y220400D01*
Y217800D01*
G01X135500Y155300D02*
Y155800D01*
X132700Y158600D01*
G01X127000Y154200D02*
X127800D01*
X132100Y158500D01*
X132600D01*
X132700Y158600D01*
G01X144400Y196000D02*
X140500D01*
X140000Y195500D01*
G01X131500Y272500D02*
X132800Y271200D01*
Y269000D01*
G01X129000Y268000D02*
Y270000D01*
X131500Y272500D01*
G01X153200Y61000D02*
X153700Y60500D01*
Y55415D01*
X154615Y54500D01*
G01X149600Y196000D02*
X154000D01*
G01X160500Y195900D02*
X160400Y196000D01*
X154000D01*
G01X160500Y201100D02*
X159900Y200500D01*
X155900D01*
G01D02*
X154400D01*
X153000Y201900D01*
G01X150989Y231000D02*
X146000D01*
G01X150989Y236000D02*
X147000D01*
X146500Y236500D01*
G01X155300Y254000D02*
X151445D01*
G01D02*
X148445Y257000D01*
G01X173000Y56423D02*
X171100Y58323D01*
Y61000D01*
G01X159800D02*
X165900D01*
G01D02*
Y63100D01*
X164000Y65000D01*
G01X170760Y189000D02*
X172500D01*
X176000Y185500D01*
X183200D01*
X183500Y185200D01*
G01X158600Y208400D02*
X158900Y208700D01*
X165900D01*
G01X171900Y213500D02*
X167100Y208700D01*
X165900D01*
G01X166500Y241000D02*
X170300D01*
G01D02*
X170561Y240739D01*
Y236000D01*
G01X165700Y254000D02*
X169555D01*
G01D02*
X172555Y257000D01*
G01X175400Y61000D02*
Y57800D01*
X174124Y56524D01*
X173101D01*
X173000Y56423D01*
G01X187600Y145900D02*
Y143100D01*
X187200Y142700D01*
G01X187600Y145900D02*
X184500D01*
G01X187600D02*
X190837D01*
X192237Y147300D01*
G01X176400Y175700D02*
X176700Y176000D01*
X179800D01*
G01X183500Y185200D02*
X188800D01*
X190000Y184000D01*
G01X182100Y207900D02*
Y213650D01*
X183600Y215150D01*
G01X173700Y241000D02*
X176200D01*
X176800Y241600D01*
G01X184671Y234000D02*
X195000D01*
G01X203850Y69900D02*
X201000D01*
X199800Y68700D01*
X196900D01*
G01X190000Y184000D02*
X191200Y182800D01*
Y181068D01*
G01X193600Y197500D02*
X198101D01*
X198200Y197401D01*
G01X192800Y193500D02*
Y196700D01*
X193600Y197500D01*
G01X195630Y192770D02*
X194900Y193500D01*
X192800D01*
G01D02*
Y190100D01*
X193000Y189900D01*
G01X188800Y215150D02*
X193100D01*
G01X214000Y176200D02*
Y179700D01*
X213850Y179850D01*
G01X210800Y195700D02*
Y198100D01*
X209500Y199400D01*
G01X215329Y234000D02*
X206000D01*
G01X274800Y145500D02*
Y143300D01*
X272300Y140800D01*
Y129442D01*
G01X286600Y136000D02*
X286801Y135799D01*
X289501D01*
X289800Y135500D01*
G01D02*
Y132500D01*
G01X470900Y245500D02*
X467700D01*
G01X469100Y254500D02*
Y249500D01*
G01D02*
X470900Y247700D01*
Y245500D01*
G01X482874Y67286D02*
X498031D01*
X500787Y70042D01*
G01X502000Y89000D02*
Y83713D01*
X500787Y82500D01*
Y70042D01*
G01X503996Y272181D02*
Y269819D01*
X505315Y268500D01*
G01X521736Y-43865D02*
Y-123865D01*
G01X539574Y88990D02*
Y85874D01*
X538500Y84800D01*
G01X556800Y186800D02*
Y185978D01*
X558300Y184478D01*
Y184218D01*
X558915Y183603D01*
G01X546710Y228500D02*
Y229992D01*
X547700Y230982D01*
G01X551900Y236000D02*
X551880Y235980D01*
Y230982D01*
G01X547700D02*
X551880D01*
G01X624726Y107395D02*
Y110574D01*
X623000Y112300D01*
G01X634000Y139700D02*
X636290D01*
X639500Y136490D01*
G01X635000Y110500D02*
X639875Y115375D01*
Y132375D01*
X648500Y141000D01*
Y144000D01*
G01X657500Y218700D02*
X655000D01*
X654300Y218000D01*
X649111D01*
G01X659236Y-43865D02*
Y-123865D01*
G01X653000Y93000D02*
X655000Y95000D01*
X655200D01*
X657700Y97500D01*
G01D02*
Y105000D01*
G01X657400Y119100D02*
X656724D01*
X653600Y122224D01*
Y122400D01*
G01X657700Y133000D02*
Y125500D01*
G01D02*
X657476Y125724D01*
X650726D01*
G01X665400Y153500D02*
X663189Y151289D01*
X660500D01*
G01D02*
X656783D01*
X656642Y151430D01*
G01X661600Y156700D02*
X661500Y156800D01*
Y159890D01*
X662362Y160752D01*
G01X663800Y199900D02*
X663950Y199750D01*
X664415D01*
X664728Y199437D01*
X667523D01*
X671457Y203371D01*
Y209543D01*
X669500Y211500D01*
X668000D01*
G01X657500Y218700D02*
X660800D01*
X668000Y211500D01*
G01X672000Y113500D02*
X672500Y114000D01*
X677900D01*
X678400Y114500D01*
G01X685161Y166000D02*
X680500D01*
G01X675839Y169740D02*
Y171661D01*
X673900Y173600D01*
G01X670800Y171500D02*
X672900Y173600D01*
X673900D01*
G01X690500Y171000D02*
Y165500D01*
X687260Y162260D01*
X685161D01*
G01Y169740D02*
Y171861D01*
X685261D01*
X686400Y173000D01*
G01D02*
X688500D01*
X690500Y171000D01*
G01X701245Y183800D02*
Y179840D01*
X692405Y171000D01*
X690500D01*
G01X696500Y194250D02*
Y192000D01*
X701245Y187255D01*
Y183800D01*
G01X696500Y194250D02*
Y201000D01*
X701700Y206200D01*
Y224800D01*
X699800Y226700D01*
X697500D01*
G01X724100Y90000D02*
Y85000D01*
G01D02*
Y84500D01*
X722600Y83000D01*
Y80500D01*
G01X718900Y94000D02*
Y90000D01*
G01X724200Y108400D02*
Y104300D01*
G01D02*
X728000D01*
G01X718700Y126600D02*
X717800D01*
X715700Y124500D01*
Y124200D01*
G01X744000Y165200D02*
X740800D01*
X740300Y164700D01*
G01X754000Y120000D02*
Y115100D01*
G01X749800Y110900D02*
X754000Y115100D01*
G01X769400Y136800D02*
X765074D01*
X763674Y138200D01*
X760587D01*
G01X758300Y122000D02*
Y124300D01*
X757900Y124700D01*
G01X788000Y87500D02*
X777000D01*
X766000Y98500D01*
Y111500D01*
X765500Y112000D01*
G01X761700Y122000D02*
Y115800D01*
X765500Y112000D01*
G01X769400Y136800D02*
X771577D01*
X774400Y139623D01*
Y143829D01*
X771600Y146629D01*
Y152200D01*
X773900Y154500D01*
G01X774100Y133000D02*
X769800D01*
G01X774236Y-43865D02*
Y-123865D01*
G01X785015Y132549D02*
X779751D01*
X779300Y133000D01*
G01X779700Y128600D02*
Y130000D01*
X779300Y130400D01*
Y133000D01*
G01D02*
X778000Y134300D01*
Y138000D01*
G01X785015Y152121D02*
Y158185D01*
X783600Y159600D01*
X780600D01*
X779100Y158100D01*
Y154500D01*
G01X775665Y146865D02*
X777500Y148700D01*
X779500D01*
G01X807500Y82800D02*
Y69929D01*
X808532Y68897D01*
Y61532D01*
X804032Y57032D01*
G01X941736Y-43865D02*
Y-123865D01*
G01X1111736Y-43865D02*
Y-123865D01*
G01X1309236Y-43865D02*
Y-123865D01*
G01X1341236Y-27865D02*
X1309236D01*
G01X1337236D02*
G02I-12000J0D01*
G01X1332086D02*
G02I-6850J0D01*
G01X1325236Y-43865D02*
Y-11865D01*
X17500Y190200D03*
X17301Y212401D03*
X16844Y203100D03*
X17300Y218307D03*
X10000Y229500D03*
X16400Y224212D03*
X16118Y230118D03*
X10194Y243106D03*
X9500Y234200D03*
X13090Y231129D03*
Y234899D03*
X7600Y240861D03*
Y237091D03*
X16899Y241929D03*
X16300Y236023D03*
X13590Y242940D03*
X10190Y258510D03*
X10194Y254917D03*
X10190Y246699D03*
X16899Y247834D03*
Y253740D03*
X13590Y254751D03*
X7600Y252672D03*
X16899Y259645D03*
X7600Y248902D03*
Y260713D03*
X13590Y258521D03*
Y246710D03*
X16900Y269000D03*
X7600Y264483D03*
Y268100D03*
X16899Y265551D03*
X28400Y81400D03*
X32800Y120400D03*
X25800Y120300D03*
X29200D03*
X30000Y136000D03*
X29700Y141200D03*
X26500Y181800D03*
X33500Y178100D03*
X33150Y181500D03*
X29400Y180000D03*
X23100Y181800D03*
X30000Y196200D03*
X33500Y196100D03*
X21900Y205400D03*
X31500Y207500D03*
X32000Y203200D03*
Y199300D03*
X41200Y90300D03*
X42000Y96000D03*
X41500Y100800D03*
X40500Y127700D03*
Y124300D03*
X38500Y148000D03*
X48500D03*
X41000Y152300D03*
Y143300D03*
X46000D03*
Y152300D03*
X43500Y148000D03*
Y138500D03*
X48500D03*
X38500D03*
X45800Y158100D03*
X37600Y198800D03*
X34800D03*
X37900Y195300D03*
X40400Y212700D03*
X34800Y208300D03*
X40400Y207800D03*
X34800Y203700D03*
X37600Y212700D03*
X34800Y212200D03*
X37600Y207800D03*
Y203700D03*
X34500Y216000D03*
X40400Y217100D03*
X40700Y224000D03*
X44861Y227261D03*
X37900Y219000D03*
Y222500D03*
Y229500D03*
Y226000D03*
X40200Y238300D03*
Y231300D03*
X37900Y240000D03*
Y243500D03*
X40200Y245300D03*
X37900Y233000D03*
X38000Y236500D03*
X44400Y250400D03*
X40500Y260000D03*
X37900Y257500D03*
Y254000D03*
X40600Y252500D03*
X37900Y247000D03*
X38000Y250500D03*
X46800Y274500D03*
X62900Y79900D03*
X60800Y87500D03*
X52500Y96500D03*
Y106500D03*
X57500Y96500D03*
X60000Y101500D03*
X50000D03*
X55000D03*
X57500Y106500D03*
X53500Y120400D03*
X60000Y111300D03*
X50000D03*
X55000D03*
X57600Y136900D03*
X56100Y130700D03*
X52643Y130800D03*
X58000Y141750D03*
X58800Y177000D03*
X54700Y192200D03*
X52700Y184800D03*
X62800Y184300D03*
X51860Y187640D03*
Y191410D03*
X59379Y184380D03*
X55720D03*
X57600Y214200D03*
X57400Y210700D03*
X57009Y230009D03*
X57600Y226600D03*
X57500Y223200D03*
X57287Y219806D03*
X56724Y243300D03*
X56800Y249613D03*
X58102Y246471D03*
X57800Y253900D03*
X50000Y270000D03*
X57800Y264100D03*
X64700Y272500D03*
X57800Y267500D03*
X80031Y40357D03*
X76411D03*
X74000Y37642D03*
X66500D03*
X79700Y67500D03*
X79115Y60979D03*
X78300Y64300D03*
X69235Y99735D03*
X68200Y94900D03*
Y91500D03*
X66500Y128000D03*
X65500Y123800D03*
X74800Y191000D03*
X72137Y210237D03*
X79500Y230000D03*
X72600Y244800D03*
X78700Y259800D03*
X75600Y246700D03*
X79000Y246900D03*
X69400Y246000D03*
X67600Y255800D03*
X75300Y259900D03*
X66300Y259300D03*
X78200Y275600D03*
X71800Y268800D03*
X66800Y275200D03*
X74000Y271400D03*
X67000Y263200D03*
X82211Y37747D03*
X92159Y40357D03*
X89862Y37849D03*
X89400Y58200D03*
X83600Y57600D03*
X88700Y54400D03*
X85300D03*
X90600Y63200D03*
X94000Y63300D03*
X82885Y60979D03*
X90000Y91000D03*
X91500Y84000D03*
X94500Y76200D03*
X89800Y87300D03*
X86100Y97700D03*
X90500Y101000D03*
X86500Y113500D03*
X80500D03*
X85500Y135400D03*
X83500Y191000D03*
X86900D03*
X84700Y197100D03*
X92900Y204008D03*
X89500Y204000D03*
X85898Y200598D03*
X95200Y216200D03*
X90812Y215000D03*
X80563Y214700D03*
X84500Y230000D03*
X89500D03*
X84500Y225000D03*
Y235000D03*
X88900Y246700D03*
X82400Y246600D03*
X82100Y259600D03*
X80500Y269500D03*
X91400Y270300D03*
X83900Y269500D03*
X95779Y40357D03*
X98500Y37642D03*
X107907Y40357D03*
X105794Y37692D03*
X109700Y60000D03*
X104400Y57700D03*
X96800Y53300D03*
X103450Y54400D03*
X100050D03*
X109600Y63700D03*
X96200Y60700D03*
X97900Y76200D03*
X106100Y158700D03*
X95700Y197200D03*
X97100Y189200D03*
X110000Y201900D03*
X107740Y204460D03*
X102000Y203200D03*
X99600Y225700D03*
X100600Y221100D03*
X110166Y239500D03*
X99328Y235370D03*
X109000Y231400D03*
X109500Y258300D03*
X97600Y246500D03*
X104900Y248800D03*
X120000Y40700D03*
X113605Y37665D03*
X121500Y37642D03*
X123655Y40357D03*
X111527D03*
X121400Y60100D03*
X120200Y45610D03*
X119200Y57400D03*
X115800D03*
X111200Y67200D03*
X114800Y60700D03*
X121170Y80900D03*
X121295Y77502D03*
X126000Y86200D03*
X125787Y78813D03*
X120700Y135500D03*
X118500Y125500D03*
X112550Y142800D03*
X119600Y143300D03*
X120500Y139000D03*
X125000Y178000D03*
X119760Y191419D03*
X115760D03*
X123760D03*
X111900Y209000D03*
X112800Y225400D03*
X112700Y221200D03*
Y231400D03*
X136600Y44800D03*
X139403Y40357D03*
X129336Y37652D03*
X127275Y40357D03*
X137300Y37642D03*
X138000Y49800D03*
X138574Y57924D03*
X131600Y57400D03*
X135000D03*
X136400Y60600D03*
X130400D03*
X136469Y89902D03*
X130315Y90533D03*
X134200Y86100D03*
X137138Y76512D03*
X129300Y84900D03*
X136600Y93300D03*
X133558Y91779D03*
X136500Y104923D03*
Y101523D03*
X130000Y121000D03*
X136770Y113000D03*
X136540Y108620D03*
X133975Y129141D03*
X130563Y125200D03*
X127500Y129180D03*
X126950Y125200D03*
X133786Y134700D03*
X130300Y135000D03*
X136500Y126300D03*
X135412Y141400D03*
X138600Y146300D03*
X131500Y149000D03*
X136156Y138025D03*
X131762Y141796D03*
X127200Y158700D03*
X137300Y158900D03*
X132700Y158600D03*
X140800Y158900D03*
X140000Y195500D03*
X137100Y188900D03*
X128000Y203300D03*
X143023Y40357D03*
X153088Y37653D03*
X145070Y37642D03*
X155151Y40357D03*
X144995Y57995D03*
X143700Y54503D03*
X154615Y54500D03*
X155290Y48610D03*
X143688Y48350D03*
X147400Y60400D03*
X147315Y54400D03*
X150715D03*
X153000Y67800D03*
X152811Y84300D03*
X150894Y76497D03*
X154294Y76506D03*
X150670Y102720D03*
X154550Y106200D03*
X151080Y99344D03*
X154550Y102800D03*
X157175Y115462D03*
X150670Y115500D03*
Y118900D03*
Y112100D03*
X157229Y119218D03*
X150670Y122300D03*
X153693Y124807D03*
X147808Y145208D03*
X142900Y138595D03*
X146400D03*
X150804Y158896D03*
X144500Y158900D03*
X150500Y183000D03*
X157000Y169194D03*
X146980Y200580D03*
X153000Y201900D03*
X153500Y210000D03*
X146396Y207675D03*
X142997Y207891D03*
X150000Y210100D03*
X146500Y236500D03*
X146000Y231000D03*
X155300Y254000D03*
X144200Y270700D03*
X168791Y37689D03*
X158771Y40357D03*
X170899D03*
X160898Y37704D03*
X169600Y53000D03*
X159957Y51932D03*
X159060Y48610D03*
X170290Y49600D03*
X166463Y54400D03*
X163063D03*
X167500Y68000D03*
X164000Y65000D03*
X158105Y96775D03*
X172199Y91591D03*
X172300Y107189D03*
X158305Y112180D03*
X171800Y126600D03*
X157500Y149025D03*
X162900Y152200D03*
X158500Y161820D03*
X161900Y161700D03*
X167602Y160684D03*
X167581Y164084D03*
X170910Y173840D03*
X167140D03*
X165900Y181500D03*
X163700Y178900D03*
X169800Y181448D03*
X165700Y203400D03*
X162000Y226000D03*
X167000D03*
Y221500D03*
X162000D03*
Y230500D03*
X167000D03*
X162000Y235000D03*
X165700Y254000D03*
X174519Y40357D03*
X176640Y37699D03*
X184500Y37700D03*
X186647Y40357D03*
X185000Y51600D03*
X175758Y52879D03*
X174060Y49600D03*
X186865Y54300D03*
X181800Y54400D03*
X179000D03*
X179800Y65700D03*
X176900Y67500D03*
X180700Y78500D03*
X184300D03*
X174900Y77700D03*
X183726Y106353D03*
X187500Y106500D03*
X173000Y97000D03*
X183344Y94056D03*
X179400Y94200D03*
X181732Y97500D03*
X178000Y97300D03*
X175787Y127000D03*
X177200Y130575D03*
X187597Y133697D03*
X176700Y144875D03*
X177200Y148700D03*
X181000Y167500D03*
X180931Y172985D03*
X177159Y172900D03*
X176400Y175700D03*
X186300Y172400D03*
X185546Y192509D03*
X180546D03*
X175546D03*
X174739Y207381D03*
X177500Y209500D03*
X187000D03*
X176800Y241600D03*
X198073Y40395D03*
X194445D03*
X192400Y37642D03*
X200300D03*
X190267Y40357D03*
X191700Y52100D03*
X201500Y54500D03*
X189700Y54300D03*
X197700Y54400D03*
X194700D03*
X190100Y68700D03*
X196900D03*
X193500D03*
X194075Y80360D03*
X197845D03*
X202200Y89500D03*
X198500Y83800D03*
X193485Y83724D03*
X191500Y94100D03*
X188900Y91800D03*
X202500Y97000D03*
X193005Y97155D03*
X195989Y95300D03*
X189106Y97235D03*
X188363Y116137D03*
X201650Y111200D03*
X201899Y134200D03*
X194900Y124200D03*
X197140Y152010D03*
X194623Y149723D03*
X201252Y137766D03*
X192237Y147300D03*
X199900Y154200D03*
X191200Y181068D03*
X200900Y177000D03*
X199441Y187547D03*
X199392Y190947D03*
X202761Y186811D03*
X195630Y192770D03*
X202800Y191400D03*
X196000Y186897D03*
X198198Y206374D03*
X194800Y206100D03*
X201596Y206504D03*
X191400Y206100D03*
X195000Y234000D03*
X207600Y37642D03*
X216085Y37649D03*
X210900Y57600D03*
X205300Y54900D03*
X208700D03*
X214942Y67242D03*
X211600Y82100D03*
X212300Y85500D03*
X207200Y106000D03*
X213558Y98500D03*
X205689Y112879D03*
X205850Y118175D03*
X209259Y113771D03*
Y117430D03*
X206605Y121741D03*
X209900Y120900D03*
X205380Y134200D03*
X210100Y135800D03*
X210547Y139028D03*
X206790Y139040D03*
X213850Y179850D03*
X215100Y194200D03*
X207861Y188540D03*
X215100Y199400D03*
X205000Y206500D03*
X215384Y202984D03*
X205920Y221550D03*
X216000Y219500D03*
X208800D03*
X212500D03*
X206000Y234000D03*
X229300Y42950D03*
X232591Y43057D03*
X219900Y39100D03*
X223868Y37686D03*
X231780Y37691D03*
X223475Y53300D03*
X219899Y56800D03*
X233981Y59125D03*
X221400Y64500D03*
X230400Y63000D03*
X223800Y61700D03*
X230000Y66400D03*
X229036Y83000D03*
X226500Y94450D03*
X227850Y97575D03*
X230875Y106300D03*
X227894Y104600D03*
X232600Y95300D03*
X227800Y101200D03*
X233452Y108588D03*
X228000Y108304D03*
X231562Y143827D03*
X231611Y138336D03*
X226452Y147300D03*
X228000Y139700D03*
X232921Y167505D03*
X233350Y180700D03*
X227870Y170252D03*
X224200Y180200D03*
X232225Y193275D03*
X232560Y204250D03*
X227000Y275500D03*
X236211Y43057D03*
X239599Y37673D03*
X245385Y40357D03*
X241765D03*
X247500Y37642D03*
X244400Y50600D03*
X238800Y45300D03*
X240200Y59275D03*
X247500Y60000D03*
X235400Y63400D03*
X240297D03*
X243200Y73700D03*
X240300Y67200D03*
X246600Y73700D03*
X244759Y85200D03*
X236700Y88500D03*
X241200Y94900D03*
X244800Y100700D03*
X235075Y105600D03*
X244463Y130655D03*
X234875Y139290D03*
Y143060D03*
X244715Y159785D03*
X242950Y155800D03*
X239900Y180600D03*
X247596Y174667D03*
X236477Y179357D03*
X240119Y183993D03*
X240100Y191000D03*
X236861Y184967D03*
X246689Y196687D03*
X254600Y41100D03*
X261900Y44900D03*
X265140Y40490D03*
X255000Y37642D03*
X263100Y37700D03*
X264700Y59400D03*
X256200Y59200D03*
X259000Y57800D03*
X250500Y57900D03*
X262000Y57800D03*
X253500Y57900D03*
X264500Y73100D03*
X253700Y75875D03*
X250300Y73800D03*
X264125Y79350D03*
X264189Y98252D03*
X259820Y103454D03*
X262131Y100959D03*
X258634Y95850D03*
X263775Y140327D03*
X257977Y163423D03*
X264600Y173100D03*
X257687Y169870D03*
X253500Y174360D03*
X261300Y188300D03*
X253300Y189834D03*
X262700Y191500D03*
X261200Y209700D03*
X263600Y239850D03*
Y252700D03*
X257500Y266645D03*
X260500Y264630D03*
X269800Y44800D03*
X275300Y44900D03*
X278700Y44800D03*
X271000Y37800D03*
X278800Y37700D03*
X268910Y40490D03*
X278868Y56000D03*
X274000Y55800D03*
X271000Y57500D03*
X268000D03*
X275200Y78700D03*
X275900Y88200D03*
X280100Y89100D03*
X268928Y112625D03*
X272200Y108352D03*
X268895Y107350D03*
X272185Y111831D03*
X278075Y116475D03*
X272300Y129442D03*
X268900Y129386D03*
X280400Y129225D03*
X272300Y149900D03*
X267187Y149800D03*
X268300Y141869D03*
X278000Y141900D03*
X273900Y156198D03*
X270500Y163200D03*
X274100Y163300D03*
X267456Y160156D03*
X267100Y156200D03*
X272380Y159240D03*
X270500Y156250D03*
X268283Y173035D03*
X278300Y173300D03*
X269772Y188274D03*
X276910Y189400D03*
X273060Y189374D03*
X266140Y191850D03*
X270341Y211835D03*
X278450Y216800D03*
X265259Y216659D03*
X270774Y222226D03*
X274700Y222100D03*
X275400Y237900D03*
X267275Y253400D03*
X265500Y249300D03*
X269800Y250700D03*
X278700Y254240D03*
X275300Y254100D03*
X267000Y271300D03*
X284758Y40490D03*
X280988D03*
X286900Y37800D03*
X294500Y37900D03*
X292500Y60500D03*
X284000Y55800D03*
X286800Y57900D03*
X290200D03*
X288700Y71100D03*
X292100D03*
X295300Y66200D03*
X288400Y94200D03*
X288100Y99500D03*
X281005Y99105D03*
X281475Y116475D03*
X286500Y119900D03*
X286600Y136000D03*
X285100Y129510D03*
X281500Y142100D03*
X295900Y154200D03*
X287071Y173154D03*
X282950Y181350D03*
X282460Y189400D03*
X286300Y191885D03*
X287700Y211900D03*
X293300Y212400D03*
X291201Y225025D03*
X287802Y225200D03*
X295300Y238100D03*
X287600D03*
X287400Y254100D03*
X295500Y253500D03*
X285000Y261700D03*
X281599Y261799D03*
X287250Y269250D03*
X310348Y37900D03*
X296736Y40490D03*
X300506D03*
X302600Y37800D03*
X302400Y59500D03*
X300900Y46900D03*
X308200Y57400D03*
X304800D03*
X297150Y91100D03*
X309400Y82100D03*
X299800Y85950D03*
Y82300D03*
X304400Y88400D03*
X306100Y90600D03*
X301300Y97000D03*
X301600Y93300D03*
X303400Y98500D03*
X303376Y95200D03*
X299300Y98500D03*
X296564Y136311D03*
Y127500D03*
X296531Y133061D03*
X301109Y146156D03*
X300700Y142850D03*
X297000Y160200D03*
X307231Y164059D03*
X297250Y163700D03*
X310579Y182800D03*
X306612Y171882D03*
X304400Y182000D03*
X302591Y173906D03*
X309112Y171960D03*
X309200Y180500D03*
X305091Y173888D03*
X301745Y181788D03*
X307200Y182000D03*
X296600Y189100D03*
X305300Y203125D03*
X307300Y224900D03*
X304400D03*
X309900D03*
X298900Y253300D03*
X309400Y253600D03*
X306000D03*
X302600D03*
X304300Y262900D03*
X309000Y266700D03*
X311300Y277800D03*
X321900Y44000D03*
X326096Y37900D03*
X318048Y37700D03*
X312484Y40690D03*
X316254D03*
X314800Y48625D03*
X311950Y50800D03*
X320400Y48600D03*
X311598Y57522D03*
X322548Y58300D03*
X324000Y54900D03*
X324176Y48600D03*
X315800Y57400D03*
X319200D03*
X323882Y71643D03*
X318882D03*
X312400Y79700D03*
X312150Y100682D03*
X326000Y254100D03*
X315500D03*
X322500Y254200D03*
X319000D03*
X311400Y269200D03*
X326100Y267000D03*
X322000Y264300D03*
X318600D03*
X313824Y280255D03*
X316945Y281606D03*
X316400Y276800D03*
X319400Y278800D03*
X322700Y277700D03*
X321600Y282500D03*
X325100Y281500D03*
X331931Y40995D03*
X328303D03*
X333700Y38000D03*
X331300Y48475D03*
X327577D03*
X328300Y58200D03*
X327400Y54900D03*
X333600Y63800D03*
X337000Y74202D03*
X328882Y71643D03*
X356432Y43657D03*
X356971Y37700D03*
X349900Y263800D03*
X342600Y277900D03*
X364600Y44298D03*
X363583Y37642D03*
X367497Y41042D03*
X363604D03*
X371457Y37642D03*
X367520D03*
X366484Y47129D03*
X362626Y47068D03*
X366700Y68700D03*
X369500Y237200D03*
Y240600D03*
X373000Y242300D03*
X369500Y234600D03*
X373000Y236000D03*
Y238900D03*
X369500Y244000D03*
X365800Y264900D03*
X362400D03*
X369300D03*
X375400Y37700D03*
X385300Y47000D03*
X388000Y72963D03*
X382700Y275300D03*
X380000Y263461D03*
X383500D03*
X376500D03*
X386100Y275300D03*
X379300D03*
X394229Y241128D03*
X391788Y238760D03*
X393000Y236200D03*
X397400Y239700D03*
X399438Y243839D03*
X401838Y246248D03*
X390500Y268800D03*
X393000Y275000D03*
X400900Y273000D03*
X391000Y265000D03*
X389500Y275300D03*
X405700Y246500D03*
X417000Y258000D03*
X416128Y272896D03*
X425400Y9103D03*
X422000D03*
X428800D03*
X432200D03*
X430500Y17000D03*
X430000Y21500D03*
Y27358D03*
X424543Y22208D03*
Y27900D03*
X426405Y25054D03*
X427000Y17000D03*
X423500Y16885D03*
X423000Y43900D03*
X430000Y30758D03*
X424536Y34800D03*
X430000Y34158D03*
X424599Y31300D03*
X422986Y40350D03*
X430000Y244450D03*
X426600D03*
X420000Y244000D03*
X420500Y257800D03*
X433129Y245783D03*
X423600Y246700D03*
X423900Y257500D03*
X423000Y274000D03*
X433300Y274100D03*
X426600D03*
X429900Y274940D03*
X442100Y7006D03*
X437061Y10393D03*
X434900Y6925D03*
X446800Y9900D03*
X438300Y6925D03*
X449600Y5900D03*
X446200D03*
X446100Y18700D03*
X441390Y28680D03*
X444783Y28451D03*
X436240Y26300D03*
X449734Y18681D03*
X441281Y17025D03*
X436100Y30900D03*
X436106Y34506D03*
X435700Y243250D03*
X445300Y274400D03*
X440600Y274300D03*
X449400Y273700D03*
X436600Y275000D03*
X450200Y9800D03*
X451300Y21700D03*
X451000Y257413D03*
X464000Y275200D03*
X456300Y275300D03*
X460400Y275200D03*
X452500D03*
X480400Y154050D03*
X467100Y154200D03*
X477000Y154050D03*
X470100Y154200D03*
X473500Y154050D03*
X467700Y245500D03*
X469000Y275200D03*
X472400Y275100D03*
X466500Y272800D03*
X472101Y266090D03*
X475500Y265900D03*
X479000D03*
X493000Y119299D03*
X483800Y154050D03*
X487200Y154100D03*
X495400Y183500D03*
X482400Y266200D03*
X502000Y89000D03*
X498500Y88995D03*
X508000Y119500D03*
X511500D03*
X511200Y183400D03*
X500900D03*
X504400D03*
X510675Y209700D03*
X505315Y268500D03*
X497002Y275400D03*
X525740Y88960D03*
X522280Y89810D03*
X515502Y88998D03*
X518902Y88987D03*
X524700Y119500D03*
X515000Y119270D03*
X524700Y145041D03*
X518200Y183400D03*
X526600Y183500D03*
X514800Y183400D03*
X513100Y234500D03*
X516500D03*
X528985Y89975D03*
X533267Y89634D03*
X539574Y88990D03*
X533000Y119500D03*
X536400D03*
X528100D03*
X528400Y145041D03*
X541550Y183550D03*
X534750Y183600D03*
X538150D03*
X530214Y183481D03*
X531500Y219500D03*
X531000Y228350D03*
X541500Y234900D03*
X551800Y69600D03*
X548400Y69700D03*
X555199D03*
X556500Y89000D03*
X546349Y89512D03*
X552900Y89100D03*
X542950Y89400D03*
X552100Y136000D03*
X557100D03*
X555500Y183500D03*
X548354Y183600D03*
X544954D03*
X551754D03*
X548300Y209700D03*
X551700Y209800D03*
X550400Y222285D03*
X561999Y69700D03*
X558599D03*
X570715Y89100D03*
X566000D03*
X572100Y136000D03*
X567100D03*
X562000Y127800D03*
X562100Y136000D03*
X562000Y144900D03*
X572845Y183300D03*
X566897Y183405D03*
X561900Y183600D03*
X564398Y183481D03*
X569395Y183300D03*
X558915Y183603D03*
X558300Y210000D03*
X561000Y222700D03*
X561196Y227366D03*
X569200Y223600D03*
X564200Y224000D03*
X575000Y89100D03*
X587500Y88913D03*
X578400Y89100D03*
X588600Y124700D03*
X584800Y183300D03*
X582254Y183313D03*
X576295Y183400D03*
X588475Y183300D03*
X578795D03*
X573600Y190100D03*
X586800Y213200D03*
X583800Y207200D03*
X580350Y207250D03*
X599500Y87500D03*
X590898Y89045D03*
X596845Y89624D03*
X599300Y119270D03*
X593400Y126000D03*
X588800Y145000D03*
X592200D03*
X599200D03*
X595744Y145041D03*
X599150Y180300D03*
X593475Y183275D03*
X601750Y182500D03*
X590975Y183275D03*
X594350Y187725D03*
X591850D03*
X588800Y205900D03*
X591363Y208387D03*
X602800Y203225D03*
X601200Y207700D03*
X603964Y210400D03*
X612120Y121750D03*
X608360Y121800D03*
X617700Y125500D03*
X608300Y144890D03*
X618500Y159000D03*
X605600Y186650D03*
X609345Y190100D03*
X607500Y188300D03*
X616100Y197400D03*
X634000Y97500D03*
X630700Y100500D03*
X627500Y104900D03*
X620000Y112575D03*
X624726Y107395D03*
X621100Y124900D03*
X625500Y159000D03*
X629000D03*
X622000D03*
X633319Y155008D03*
X631900Y175850D03*
X634748Y177708D03*
X633100Y198300D03*
X626300Y198250D03*
X629700Y198300D03*
X622873Y204200D03*
X642823Y88477D03*
X640677Y91115D03*
X638500Y94000D03*
X635000Y110500D03*
X638000Y107400D03*
X639500Y136490D03*
X648500Y144000D03*
X636719Y154972D03*
X643500Y155000D03*
X648500Y162600D03*
X640110Y155272D03*
X640461Y181410D03*
X642600Y186400D03*
X646000D03*
X636500Y198300D03*
X653600Y122400D03*
X656477Y148033D03*
X656642Y151430D03*
X656200Y144000D03*
X661600Y156700D03*
X650500Y155000D03*
X661000Y173800D03*
X657722Y193800D03*
X661600Y197300D03*
X654851Y191978D03*
X663800Y199900D03*
X654100Y221800D03*
X673100Y179455D03*
X676200Y181600D03*
X673044Y190456D03*
X668732Y204555D03*
X666446Y202037D03*
X682600Y114300D03*
X684700Y179800D03*
X689400Y178900D03*
X689547Y175500D03*
X686700Y187400D03*
X687456Y183944D03*
X694600Y229800D03*
X705145Y93500D03*
X707209Y97500D03*
X698970Y118149D03*
X699241Y114759D03*
X709500Y143500D03*
X709900Y139900D03*
X698000Y181500D03*
X701245Y183800D03*
X704700D03*
X718900Y94000D03*
X726800Y95500D03*
X724200Y108400D03*
X714000Y118500D03*
X727448Y128893D03*
X715700Y124200D03*
X714900Y131900D03*
X727187Y140000D03*
X718200Y147000D03*
Y150400D03*
X718825Y155453D03*
X712700Y155978D03*
X724400Y176025D03*
X717000Y187500D03*
X725500Y195500D03*
X715500Y205837D03*
X727400Y227400D03*
X738000Y65700D03*
X738500Y90000D03*
X731340Y82515D03*
X736900Y98500D03*
X730200Y94900D03*
X739500Y114900D03*
X742100Y118200D03*
X736300Y118000D03*
X729400Y120200D03*
X732000Y122700D03*
X728900Y132976D03*
X727800Y136600D03*
X741104Y133763D03*
X740300Y164700D03*
X736900Y162300D03*
X729500D03*
X733400D03*
X727800Y176600D03*
X733000Y176200D03*
X737000Y188315D03*
X739900Y212800D03*
X734000Y205000D03*
X731000Y210200D03*
X739800Y216300D03*
X750100Y16100D03*
X752500Y49007D03*
X756000Y106000D03*
X749500Y101500D03*
X751300Y118200D03*
X754000Y115100D03*
X748800Y115800D03*
X758176Y135024D03*
X757900Y124700D03*
X745104Y129763D03*
X749104Y133763D03*
X745104D03*
X752191Y146613D03*
X745104Y137763D03*
X747000Y162000D03*
X750500D03*
X746000Y182300D03*
X743100Y195500D03*
X743000Y211000D03*
X744100Y221900D03*
X743800Y215900D03*
X758916Y104250D03*
X762304Y103957D03*
X768500Y114000D03*
X765500Y112000D03*
X769800Y133000D03*
X759400Y131000D03*
X771300Y140200D03*
X766600Y139800D03*
X762000Y281000D03*
X765400D03*
X774500Y31307D03*
X778000D03*
X779000Y142000D03*
X788515Y144060D03*
X784515D03*
X787600Y183300D03*
X787800Y179900D03*
X796515Y144060D03*
X792515D03*
X800515D03*
Y148060D03*
X796515D03*
X792515D03*
X793000Y174500D03*
X805500Y128000D03*
G54D144*
G01X386092Y178561D02*
Y179092D01*
X387700Y180700D01*
Y188658D01*
X389484Y190442D01*
G01X394852Y122601D02*
X396276Y121177D01*
Y120948D01*
G01X400592Y175991D02*
X401220D01*
X402600Y174611D01*
G01X404142Y175991D02*
X405952D01*
X406232Y175711D01*
X408209D01*
X410620Y173300D01*
G01X429902Y122141D02*
X430472Y122711D01*
X434129D01*
X435442Y124024D01*
G01X431700Y128300D02*
X430063D01*
X428402Y129961D01*
G01Y132721D02*
X428879D01*
X430100Y131500D01*
G01X426902Y124901D02*
X426920D01*
X428255Y126236D01*
G01X434834Y163817D02*
X434717D01*
X434431Y163531D01*
X432722D01*
X432104Y162913D01*
X430074D01*
X428402Y161241D01*
G01Y164001D02*
Y164903D01*
X430120Y166620D01*
X431090D01*
X431130Y166660D01*
G01X432532Y194971D02*
X435495D01*
X435642Y194824D01*
G01X432732Y192211D02*
X431518Y193425D01*
X431270D01*
G01X439592Y122271D02*
X441395D01*
X442842Y120824D01*
G01X439400Y120100D02*
X439218D01*
X438199Y119081D01*
X437612D01*
G01X438500Y116400D02*
X437764D01*
X434883Y119281D01*
X434612D01*
G01X438942Y126321D02*
X442245D01*
X444242Y124324D01*
G01X437400Y121600D02*
X437039Y121961D01*
X435442D01*
G01Y192871D02*
X435527Y192956D01*
X437921D01*
G01X505315Y6630D02*
Y11192D01*
X504000Y12507D01*
G01X510039Y6630D02*
Y13268D01*
X508700Y14607D01*
G01X508858Y38966D02*
Y31381D01*
X507839Y30362D01*
G01X519488Y6630D02*
Y9385D01*
X520750Y10647D01*
Y11013D01*
X521410Y11673D01*
Y14097D01*
X520700Y14807D01*
G01X512401Y6630D02*
Y11906D01*
X511800Y12507D01*
G01X521850Y6630D02*
Y10557D01*
X523400Y12107D01*
Y12307D01*
X523453Y12360D01*
G01X515945Y38966D02*
Y36035D01*
X516500Y35480D01*
Y23923D01*
X515484Y22907D01*
G01X518307Y38966D02*
Y36041D01*
X517700Y35434D01*
Y23976D01*
X518769Y22907D01*
G01X525393Y38966D02*
Y35093D01*
X525000Y34700D01*
Y32807D01*
X524450Y32257D01*
Y31343D01*
X524900Y30893D01*
X525753D01*
G01X523031Y38966D02*
Y35876D01*
X523700Y35207D01*
Y33432D01*
X523100Y32832D01*
X522733D01*
G01X511220Y38966D02*
Y30687D01*
X511589Y30318D01*
Y30295D01*
G01X511221Y246430D02*
Y255481D01*
X511640Y255900D01*
Y255956D01*
G01X527756Y246430D02*
Y249339D01*
X525700Y251395D01*
Y253500D01*
X526715Y254515D01*
Y254700D01*
G01X520670Y246430D02*
Y249456D01*
X520089Y250037D01*
Y261447D01*
X521131Y262489D01*
G01X518307Y246430D02*
Y249459D01*
X518889Y250041D01*
Y261446D01*
X517846Y262489D01*
G01X525394Y246430D02*
Y249206D01*
X523500Y251100D01*
Y254500D01*
X522908Y255092D01*
Y255117D01*
G01X513583Y246430D02*
Y255535D01*
X514137Y256089D01*
G01X512402Y278766D02*
Y273791D01*
X511736Y273125D01*
Y273001D01*
G01X524213Y278766D02*
Y275974D01*
X525800Y274387D01*
Y272908D01*
X525845Y272863D01*
G01X521851Y278766D02*
Y276049D01*
X523850Y274050D01*
Y271757D01*
X522992Y270900D01*
Y270700D01*
G01X514764Y278766D02*
Y271486D01*
X514900Y271350D01*
G01X533661Y6630D02*
Y9458D01*
X534242Y10039D01*
Y21865D01*
X533200Y22907D01*
G01X540748Y6630D02*
Y9455D01*
X542814Y11521D01*
Y14393D01*
X542100Y15107D01*
G01X526575Y6630D02*
Y10582D01*
X528525Y12532D01*
Y12549D01*
G01X536023Y6630D02*
Y9594D01*
X535442Y10175D01*
Y21864D01*
X536485Y22907D01*
G01X528937Y6630D02*
Y10469D01*
X530600Y12132D01*
Y15307D01*
X530700Y15407D01*
G01X530118Y38966D02*
Y35649D01*
X529106Y34637D01*
Y34613D01*
X528400Y33907D01*
Y33175D01*
X529000Y32575D01*
X529120D01*
G01X532480Y38966D02*
Y35687D01*
X530842Y34049D01*
Y32304D01*
X532339Y30807D01*
X532350D01*
G01X541929Y246430D02*
Y250724D01*
X542600Y251395D01*
Y253005D01*
X541005Y254600D01*
Y254800D01*
G01X534843Y246430D02*
Y249163D01*
X531775Y252231D01*
G01X532481Y246430D02*
Y249119D01*
X530000Y251600D01*
Y254985D01*
X530015Y255000D01*
G01X543110Y278766D02*
Y274573D01*
X542437Y273900D01*
Y271837D01*
X541500Y270900D01*
G01X528937Y278766D02*
Y274989D01*
X530737Y273189D01*
Y273163D01*
X530900Y273000D01*
G01X538386Y278766D02*
Y275938D01*
X537805Y275357D01*
Y263531D01*
X538847Y262489D01*
G01X536024Y278766D02*
Y275802D01*
X536605Y275221D01*
Y263532D01*
X535562Y262489D01*
G01X531299Y278766D02*
Y275027D01*
X533180Y273146D01*
Y271620D01*
X534100Y270700D01*
G01X557283Y6630D02*
Y9594D01*
X556702Y10175D01*
Y21864D01*
X557745Y22907D01*
G01X550197Y6630D02*
Y10294D01*
X551900Y11997D01*
Y13907D01*
X552800Y14807D01*
G01X547834Y6630D02*
Y10241D01*
X550000Y12407D01*
Y12507D01*
G01X543110Y6630D02*
Y10217D01*
X544860Y11967D01*
Y12407D01*
G01X554921Y6630D02*
Y9458D01*
X555502Y10039D01*
Y21865D01*
X554460Y22907D01*
G01X546653Y38966D02*
Y35360D01*
X545300Y34007D01*
Y31675D01*
X545928Y31047D01*
G01X551378Y38966D02*
Y35685D01*
X549500Y33807D01*
Y31607D01*
G01X553740Y38966D02*
Y36247D01*
X551550Y34057D01*
Y32241D01*
X553079Y30712D01*
G01X544291Y38966D02*
Y34930D01*
X543700Y34339D01*
Y31607D01*
X543012Y30919D01*
X542444D01*
X542407Y30882D01*
G01X549016Y246430D02*
Y254316D01*
X550200Y255500D01*
G01X556103Y246430D02*
Y249355D01*
X556684Y249936D01*
Y261446D01*
X555641Y262489D01*
G01X544292Y246430D02*
Y250708D01*
X543800Y251200D01*
Y253672D01*
X544800Y254672D01*
Y255100D01*
G01X551378Y246430D02*
Y251662D01*
X551000Y252040D01*
Y252056D01*
G01X550197Y278766D02*
Y273649D01*
X549016Y272468D01*
Y271216D01*
X548800Y271000D01*
G01X552559Y278766D02*
Y273411D01*
X551937Y272789D01*
G01X545473Y278766D02*
Y274173D01*
X544428Y273128D01*
X544292D01*
G01X562008Y6630D02*
Y11699D01*
X561200Y12507D01*
G01X569094Y6630D02*
Y11868D01*
X568555Y12407D01*
G01X564370Y6630D02*
Y10937D01*
X563800Y11507D01*
Y13707D01*
X564400Y14307D01*
G01X571456Y6630D02*
Y10551D01*
X570700Y11307D01*
Y13307D01*
X571600Y14207D01*
G01X563189Y38966D02*
Y35608D01*
X563660Y35137D01*
Y32246D01*
X565091Y30815D01*
G01X567913Y38966D02*
Y31694D01*
X569800Y29807D01*
G01X560827Y38966D02*
Y35990D01*
X562335Y34482D01*
Y31781D01*
X561456Y30902D01*
G01X570275Y38966D02*
Y33781D01*
X570852Y33204D01*
G01X565551Y246430D02*
Y249631D01*
X564400Y250782D01*
Y254119D01*
X565054Y254773D01*
G01X558465Y246430D02*
Y249361D01*
X557884Y249942D01*
Y261447D01*
X558926Y262489D01*
G01X572638Y246430D02*
Y249142D01*
X570450Y251330D01*
Y253268D01*
X571867Y254685D01*
G01X563189Y246430D02*
Y253311D01*
X561700Y254800D01*
X561469D01*
X561419Y254850D01*
G01X570276Y246430D02*
Y249524D01*
X568312Y251488D01*
Y253212D01*
X568327Y253227D01*
Y253348D01*
G01X562008Y278766D02*
Y275218D01*
X563700Y273526D01*
Y271500D01*
X564100Y271100D01*
G01X566733Y278766D02*
Y274985D01*
X567800Y273918D01*
Y270500D01*
G01X559646Y278766D02*
Y275354D01*
X561300Y273700D01*
Y271000D01*
X560600Y270300D01*
G01X569095Y278766D02*
Y274505D01*
X570200Y273400D01*
Y273100D01*
G01X578543Y6630D02*
Y9620D01*
X580790Y11867D01*
Y13817D01*
X579800Y14807D01*
G01X580905Y6630D02*
Y9722D01*
X582655Y11472D01*
Y12407D01*
G01X585630Y6630D02*
Y10107D01*
X587940Y12417D01*
G01X575000Y38966D02*
Y36035D01*
X575581Y35454D01*
Y23949D01*
X574539Y22907D01*
G01X577362Y38966D02*
Y36041D01*
X576781Y35460D01*
Y23950D01*
X577824Y22907D01*
G01X584449Y38966D02*
Y34999D01*
X583678Y34228D01*
Y31929D01*
X584740Y30867D01*
X585179D01*
G01X582086Y38966D02*
Y35693D01*
X581000Y34607D01*
Y33207D01*
X581700Y32507D01*
Y30957D01*
X581450Y30707D01*
G01X589173Y246430D02*
Y251032D01*
X589492Y251351D01*
Y252973D01*
X587700Y254765D01*
Y255300D01*
G01X579725Y246430D02*
Y250320D01*
X580500Y251095D01*
Y253555D01*
X579205Y254850D01*
G01X582087Y246430D02*
Y251239D01*
X582200Y251352D01*
Y252206D01*
G01X573819Y278766D02*
Y275802D01*
X574400Y275221D01*
Y263532D01*
X573357Y262489D01*
G01X580906Y278766D02*
Y273706D01*
X580200Y273000D01*
G01X583268Y278766D02*
Y273622D01*
X582600Y272954D01*
Y270300D01*
G01X576181Y278766D02*
Y275938D01*
X575600Y275357D01*
Y263531D01*
X576642Y262489D01*
G01X602165Y6630D02*
Y9458D01*
X602746Y10039D01*
Y21865D01*
X601704Y22907D01*
G01X587992Y6630D02*
X594523D01*
X594600Y6707D01*
G01X600984Y38966D02*
X597159D01*
X594400Y36207D01*
G01X589173Y38966D02*
Y36234D01*
X590800Y34607D01*
Y33707D01*
X590100Y33007D01*
X589300D01*
G01X591536Y246430D02*
Y249783D01*
X593100Y251347D01*
Y253210D01*
X591300Y255010D01*
G01X587992Y278766D02*
Y273234D01*
X588036Y273190D01*
Y273089D01*
G01X590355Y278766D02*
Y274283D01*
X589786Y273714D01*
Y271621D01*
X588565Y270400D01*
X588500D01*
X588400Y270300D01*
G01X604527Y6630D02*
Y9594D01*
X603946Y10175D01*
Y21864D01*
X604989Y22907D01*
G01X611614Y6630D02*
Y11645D01*
X610952Y12307D01*
G01X609252Y6630D02*
Y12555D01*
X607300Y14507D01*
G01X616338Y6630D02*
Y11745D01*
X616600Y12007D01*
Y12307D01*
G01X618701Y6630D02*
Y13622D01*
X616707Y15616D01*
G01X610433Y38966D02*
Y33844D01*
X610944Y33333D01*
G01X608071Y38966D02*
Y35546D01*
X609244Y34372D01*
Y32451D01*
X607800Y31007D01*
Y30407D01*
G01X643504Y246430D02*
Y251484D01*
X642802Y252186D01*
G01X645866Y246430D02*
Y254076D01*
X645920Y254130D01*
G01X635236Y278766D02*
Y272152D01*
X637288Y270100D01*
G01X642323Y278766D02*
Y273703D01*
X642937Y273089D01*
G01X644685Y278766D02*
Y273205D01*
X646360Y271530D01*
G01X637599Y278766D02*
Y273206D01*
X637337Y272944D01*
G01X649410Y278766D02*
Y275802D01*
X649991Y275221D01*
Y263532D01*
X648948Y262489D01*
G01X663582Y6630D02*
Y11113D01*
X664151Y11682D01*
Y13032D01*
X665926Y14807D01*
X666175D01*
G01X664764Y38966D02*
Y35251D01*
X662820Y33307D01*
X662603D01*
X662503Y33207D01*
G01X662401Y38966D02*
Y36207D01*
X661688Y34955D01*
X659278Y31951D01*
X659181Y31854D01*
X657900Y30690D01*
G01X664764Y246430D02*
Y248446D01*
X663770Y249440D01*
Y250459D01*
X665500Y252189D01*
G01X652953Y246430D02*
X659396D01*
X659437Y246389D01*
G01X651772Y278766D02*
Y275938D01*
X651191Y275357D01*
Y263531D01*
X652233Y262489D01*
G01X665945Y278766D02*
Y276245D01*
X663700Y274000D01*
X659500D01*
G01X677756Y6630D02*
Y9458D01*
X678337Y10039D01*
Y21765D01*
X677295Y22807D01*
G01X680118Y6630D02*
Y9594D01*
X679537Y10175D01*
Y21764D01*
X680580Y22807D01*
G01X673031Y6630D02*
Y12930D01*
X674320Y14219D01*
G01X665945Y6630D02*
Y12162D01*
X665901Y12206D01*
Y12307D01*
G01X670669Y6630D02*
Y11836D01*
X671290Y12457D01*
G01X674212Y38966D02*
Y34119D01*
X673700Y33607D01*
Y32007D01*
X674400Y31307D01*
G01X671850Y38966D02*
Y34157D01*
X671295Y33602D01*
Y33190D01*
G01X669488Y246430D02*
Y249288D01*
X671630Y251430D01*
Y253270D01*
X670200Y254700D01*
G01X671851Y246430D02*
Y249351D01*
X672730Y250230D01*
Y253712D01*
X673770Y254752D01*
G01X678937Y246430D02*
Y249361D01*
X678356Y249942D01*
Y261447D01*
X679398Y262489D01*
G01X676575Y246430D02*
Y249355D01*
X677156Y249936D01*
Y261446D01*
X676113Y262489D01*
G01X673032Y278766D02*
Y275532D01*
X669700Y272200D01*
Y270900D01*
G01X675394Y278766D02*
Y275894D01*
X672800Y273300D01*
Y272700D01*
G01X668307Y278766D02*
Y275707D01*
X665300Y272700D01*
X665100D01*
G01X684842Y6630D02*
Y9585D01*
X683060Y11367D01*
Y13747D01*
X682013Y14794D01*
Y14848D01*
G01X691929Y6630D02*
Y10178D01*
X690200Y11907D01*
Y12404D01*
X690102Y12502D01*
G01X687204Y6630D02*
Y9812D01*
X684760Y12256D01*
G01X694291Y6630D02*
Y9456D01*
X692200Y11547D01*
Y15357D01*
G01X695472Y38966D02*
Y36035D01*
X696053Y35454D01*
Y23849D01*
X695057Y22853D01*
X695029D01*
G01X683661Y38966D02*
Y35576D01*
X685238Y33999D01*
Y31369D01*
X685700Y30907D01*
Y30807D01*
G01X681299Y38966D02*
Y36028D01*
X683040Y34287D01*
Y32047D01*
X681900Y30907D01*
G01X690748Y38966D02*
Y34959D01*
X691700Y34007D01*
Y31507D01*
X692600Y30607D01*
X693300D01*
G01X688386Y38966D02*
Y35421D01*
X690100Y33707D01*
Y30859D01*
X689624Y30383D01*
G01X686024Y246430D02*
Y251547D01*
X685382Y252189D01*
Y252200D01*
G01X683662Y246430D02*
Y251427D01*
X683670Y251435D01*
Y254130D01*
X682900Y254900D01*
X682800D01*
G01X693110Y246430D02*
Y249534D01*
X692150Y250494D01*
Y255600D01*
X692250Y255700D01*
G01X690748Y246430D02*
Y252467D01*
X688800Y254415D01*
Y254600D01*
G01X684843Y278766D02*
Y273357D01*
X685100Y273100D01*
G01X689567Y278766D02*
Y270933D01*
X689700Y270800D01*
G01X682481Y278766D02*
Y270700D01*
G01X691929Y278766D02*
Y273597D01*
X692537Y272989D01*
G01X701378Y6630D02*
Y11985D01*
X702000Y12607D01*
G01X710827Y6630D02*
Y12769D01*
X712182Y14124D01*
G01X703740Y6630D02*
Y12527D01*
X705031Y13818D01*
Y14515D01*
G01X708464Y6630D02*
Y11871D01*
X709000Y12407D01*
G01X697834Y38966D02*
Y36041D01*
X697253Y35460D01*
Y23850D01*
X698248Y22855D01*
X698277D01*
G01X709645Y38966D02*
Y31152D01*
X708900Y30407D01*
G01X702559Y38966D02*
Y35304D01*
X702730Y35133D01*
Y31407D01*
X702130Y30807D01*
X701800D01*
G01X704921Y38966D02*
Y33804D01*
X704430Y33313D01*
G01X712008Y38966D02*
Y35303D01*
X710750Y34045D01*
Y32357D01*
X712171Y30936D01*
X712271D01*
X712400Y30807D01*
G01X705580Y157480D02*
X704609Y156509D01*
Y94036D01*
X705145Y93500D01*
G01X707209Y97500D02*
Y155265D01*
X719087Y167143D01*
G01X726800Y172000D02*
X726400Y171600D01*
X719700D01*
X705580Y157480D01*
G01X702559Y246430D02*
Y249509D01*
X704178Y251128D01*
Y252189D01*
G01X709646Y246430D02*
Y249771D01*
X710500Y250625D01*
Y254172D01*
X711400Y255072D01*
G01X707284Y246430D02*
Y249504D01*
X709190Y251410D01*
Y253610D01*
X707800Y255000D01*
G01X700197Y246430D02*
Y249217D01*
X702000Y251020D01*
Y254698D01*
X701649Y255049D01*
G01X703740Y278766D02*
Y274927D01*
X702100Y273287D01*
Y271500D01*
X701377Y270777D01*
X701300D01*
G01X706103Y278766D02*
Y274815D01*
X704277Y272989D01*
G01X710827Y278766D02*
Y274839D01*
X709400Y273412D01*
Y272600D01*
G01X699016Y278766D02*
Y275938D01*
X698435Y275357D01*
Y263531D01*
X699477Y262489D01*
G01X696654Y278766D02*
Y275802D01*
X697235Y275221D01*
Y263532D01*
X696192Y262489D01*
G01X725000Y6630D02*
Y10407D01*
X723700Y11707D01*
Y13966D01*
X723586Y14080D01*
G01X722638Y6630D02*
Y10369D01*
X720810Y12197D01*
Y13997D01*
X720100Y14707D01*
G01X715551Y6630D02*
Y9458D01*
X716132Y10039D01*
Y15275D01*
X715500Y15907D01*
Y18875D01*
X716132Y19507D01*
Y21865D01*
X715090Y22907D01*
G01X717913Y6630D02*
Y9594D01*
X717332Y10175D01*
Y15773D01*
X716700Y16405D01*
Y18377D01*
X717332Y19009D01*
Y21864D01*
X718375Y22907D01*
G01X721456Y38966D02*
Y35651D01*
X723500Y33607D01*
Y29907D01*
G01X719094Y38966D02*
Y35436D01*
X721523Y33007D01*
X721694D01*
X721747Y32954D01*
G01X726181Y38966D02*
Y35802D01*
X727900Y34083D01*
Y31307D01*
X727000Y30407D01*
G01X726800Y169000D02*
X720944D01*
X719087Y167143D01*
G01X718500Y220700D02*
X722300Y224500D01*
X723500D01*
G01D02*
X724500D01*
X727400Y227400D01*
G01X730000Y223900D02*
X726900Y220800D01*
X725000D01*
X724900Y220700D01*
X722000D01*
G01X721457Y246430D02*
Y249217D01*
X723095Y250855D01*
Y253343D01*
X721500Y254938D01*
Y255000D01*
G01X723819Y246430D02*
Y249079D01*
X724740Y250000D01*
Y251378D01*
X724195Y251923D01*
Y254336D01*
X724374Y254515D01*
G01X727362Y278766D02*
Y274862D01*
X725300Y272800D01*
G01X717914Y278766D02*
Y275802D01*
X718495Y275221D01*
Y263532D01*
X717452Y262489D01*
G01X725000Y278766D02*
Y274927D01*
X723500Y273427D01*
Y271756D01*
X722544Y270800D01*
X722400D01*
G01X720276Y278766D02*
Y275938D01*
X719695Y275357D01*
Y263531D01*
X720737Y262489D01*
G01X713189Y278766D02*
Y275589D01*
X711400Y273800D01*
Y271300D01*
X712200Y270500D01*
G01X739173Y6630D02*
Y11780D01*
X739700Y12307D01*
Y13707D01*
X739000Y14407D01*
G01X741535Y6630D02*
Y11742D01*
X742200Y12407D01*
G01X732086Y6630D02*
Y9541D01*
X730410Y11217D01*
Y13717D01*
X731169Y14476D01*
Y14584D01*
G01X729724Y6630D02*
Y9733D01*
X728030Y11427D01*
Y12657D01*
X728010Y12677D01*
Y12857D01*
G01X733267Y38966D02*
Y36047D01*
X735174Y34140D01*
Y32035D01*
X735800Y31409D01*
Y29505D01*
X733548Y27253D01*
Y24349D01*
X732806Y23607D01*
G01X735630Y38966D02*
Y35396D01*
X736374Y34652D01*
Y32533D01*
X737000Y31907D01*
Y29007D01*
X734748Y26755D01*
Y24459D01*
X735600Y23607D01*
X736091D01*
G01X740354Y38966D02*
Y32161D01*
X739800Y31607D01*
Y30307D01*
X740200Y29907D01*
G01X728543Y38966D02*
Y35364D01*
X730500Y33407D01*
Y29907D01*
G01X730000Y223900D02*
Y228600D01*
X740000Y238600D01*
G01D02*
X740700Y239300D01*
X744500D01*
G01X735630Y246430D02*
Y249355D01*
X736637Y250362D01*
Y255663D01*
X735800Y256500D01*
Y261857D01*
X735168Y262489D01*
G01X730906Y246430D02*
Y250906D01*
X732200Y252200D01*
G01X742717Y246430D02*
Y252283D01*
X741560Y253440D01*
Y255000D01*
G01X728544Y246430D02*
Y251344D01*
X730400Y253200D01*
Y255400D01*
G01X737992Y246430D02*
Y249361D01*
X737837Y249516D01*
Y256161D01*
X737000Y256998D01*
Y261036D01*
X738453Y262489D01*
G01X741536Y278766D02*
Y273490D01*
X741900Y273126D01*
Y271200D01*
X741200Y270500D01*
G01X732087Y278766D02*
Y275587D01*
X730400Y273900D01*
Y272850D01*
G01X734449Y278766D02*
Y276049D01*
X732740Y274340D01*
Y270200D01*
G01X742716Y38966D02*
Y33623D01*
X742100Y33007D01*
G01X748622Y278766D02*
Y275378D01*
X750800Y273200D01*
Y243107D01*
X746993Y239300D01*
X744500D01*
G01X745079Y246430D02*
Y251547D01*
X744437Y252189D01*
G01X743898Y278766D02*
Y272902D01*
X744200Y272600D01*
G54D126*
X745104Y133763D03*
G54D117*
X672000Y95500D03*
Y113500D03*
Y123500D03*
Y141500D03*
G54D24*
X28209Y175152D03*
X30769D03*
X25649D03*
X23089D03*
Y190832D03*
X25649D03*
X28209D03*
X30769D03*
G54D51*
X109600Y268500D03*
X104400D03*
X126100Y121000D03*
X120900D03*
X171100Y61000D03*
X165900D03*
X171900Y213500D03*
X170000Y203300D03*
X180600Y61000D03*
X175400D03*
X177100Y213500D03*
X175200Y203300D03*
X183600Y215150D03*
X195600Y177000D03*
X190400D03*
X193600Y197500D03*
X188400D03*
X195851Y210150D03*
X190651D03*
X188800Y215150D03*
X198300D03*
X193100D03*
X249400Y207000D03*
X254600D03*
X441600Y75500D03*
X436400D03*
X474300Y254500D03*
X469100D03*
X474300Y249500D03*
X469100D03*
X557080Y230982D03*
X551880D03*
X663600Y91000D03*
X658400D03*
X662600Y119100D03*
X657400D03*
X665400Y153500D03*
X670600D03*
X724100Y85000D03*
X718900D03*
G54D108*
X577000Y197705D03*
Y195735D03*
Y193765D03*
Y191795D03*
Y189830D03*
Y199670D03*
X590400Y189830D03*
Y191795D03*
Y193765D03*
Y195735D03*
Y197705D03*
Y199670D03*
G54D15*
X18000Y197000D03*
X54700Y269600D03*
X76000Y129000D03*
X67400Y249800D03*
X77100Y262900D03*
X73600Y262809D03*
X96500Y169000D03*
X98500Y192500D03*
X121500Y128500D03*
X164500Y193500D03*
X181000Y81500D03*
X174500Y99800D03*
X182200Y134000D03*
X205600Y49000D03*
X208600D03*
X218500Y212500D03*
X248500Y116500D03*
X242000Y174500D03*
X293300Y160500D03*
X310500Y234500D03*
X423500Y251500D03*
X465500Y147063D03*
X511500Y170000D03*
X633500Y49007D03*
X636800D03*
X645300D03*
X648500Y165500D03*
X650800Y49007D03*
X657500Y219000D03*
X686400Y173300D03*
X717000Y68000D03*
Y200000D03*
X741500Y87000D03*
X737000Y155500D03*
X744700Y70000D03*
X766500Y129500D03*
X805500Y138500D03*
G54D135*
X792700Y165671D03*
Y196329D03*
G54D33*
X60433Y24392D03*
X64370D03*
X68307D03*
X72244D03*
X76181D03*
X80118D03*
X84055D03*
X87992D03*
X91929D03*
X95866D03*
X99803D03*
X103740D03*
X107677D03*
X111614D03*
X115551D03*
X119488D03*
X123425D03*
X127362D03*
X131299D03*
X135236D03*
X139173D03*
X143110D03*
X147047D03*
X150984D03*
X154921D03*
X158858D03*
X162795D03*
X166732D03*
X170669D03*
X174606D03*
X178543D03*
X182480D03*
X186417D03*
X190354D03*
X194291D03*
X198228D03*
X202165D03*
X206102D03*
X210039D03*
X213976D03*
X217913D03*
X221850D03*
X225787D03*
X229724D03*
X233661D03*
X237598D03*
X241535D03*
X245472D03*
X249409D03*
X253346D03*
X257283D03*
X261220D03*
X265157D03*
X269094D03*
X273031D03*
X276968D03*
X280905D03*
X284842D03*
X288779D03*
X292716D03*
X296653D03*
X300590D03*
X304527D03*
X308464D03*
X312401D03*
X316338D03*
X320275D03*
X324212D03*
X328149D03*
X332086D03*
X336023D03*
X347835D03*
X351772D03*
X355709D03*
X359646D03*
X363583D03*
X367520D03*
X371457D03*
X375394D03*
X379331D03*
X383268D03*
G54D60*
X155720Y228500D03*
G54D42*
X78988Y218689D03*
X77413D03*
X75839D03*
Y241311D03*
X77413D03*
X78988D03*
X93161Y218689D03*
X91587D03*
X90012D03*
X88437D03*
X86862D03*
X85287D03*
X83713D03*
X82138D03*
X80563D03*
Y241311D03*
X82138D03*
X83713D03*
X85287D03*
X86862D03*
X88437D03*
X90012D03*
X91587D03*
X93161D03*
G54D145*
G01X407732Y125601D02*
X406200Y127400D01*
G54D34*
X59750Y84300D03*
G54D52*
X125000Y49250D03*
X122440D03*
X125000Y55750D03*
X122440D03*
X127560Y49250D03*
Y55750D03*
X209060Y175750D03*
X206500D03*
X203940D03*
X209060Y182250D03*
X206500D03*
X203940D03*
X231260Y50950D03*
X228700D03*
X226140D03*
X231260Y57450D03*
X228700D03*
X226140D03*
X219940Y168750D03*
X222500D03*
X225060D03*
X219940Y162250D03*
X222500D03*
X225060D03*
X437940Y269750D03*
X440500D03*
X443060D03*
X437940Y263250D03*
X440500D03*
X443060D03*
G54D61*
X150989Y221000D03*
Y226000D03*
Y231000D03*
Y236000D03*
G54D118*
X675839Y162260D03*
Y166000D03*
Y169740D03*
X685161Y166000D03*
Y162260D03*
Y169740D03*
G54D109*
X580745Y187050D03*
X586655D03*
X580745Y202450D03*
X586655D03*
G54D16*
X18000Y200000D03*
X54700Y272600D03*
X76000Y132000D03*
X67400Y252800D03*
X77100Y265900D03*
X73600Y265809D03*
X96500Y172000D03*
X98500Y195500D03*
X121500Y131500D03*
X164500Y196500D03*
X181000Y84500D03*
X174500Y102800D03*
X182200Y137000D03*
X205600Y52000D03*
X208600D03*
X218500Y215500D03*
X248500Y119500D03*
X242000Y177500D03*
X293300Y163500D03*
X310500Y237500D03*
X423500Y254500D03*
X465500Y150063D03*
X511500Y173000D03*
X633500Y52007D03*
X636800D03*
X645300D03*
X648500Y168500D03*
X650800Y52007D03*
X657500Y222000D03*
X686400Y176300D03*
X717000Y71000D03*
Y203000D03*
X741500Y90000D03*
X737000Y158500D03*
X744700Y73000D03*
X766500Y132500D03*
X805500Y141500D03*
G54D70*
X184671Y234000D03*
X215329D03*
G54D127*
X792515Y137280D03*
G54D25*
X18500Y173300D03*
Y176700D03*
Y180300D03*
X21900Y197300D03*
X18500Y183700D03*
X21900Y200700D03*
X51000Y123800D03*
Y127200D03*
X60000Y123800D03*
Y127200D03*
X63800Y205300D03*
Y208700D03*
X54000Y220900D03*
Y224300D03*
Y214300D03*
Y217700D03*
X67000Y82800D03*
Y86200D03*
X77100Y269000D03*
Y272400D03*
X92600Y197200D03*
X89600D03*
X92600Y200600D03*
X83400Y203400D03*
Y206800D03*
X89600Y200600D03*
X86400Y254900D03*
Y258300D03*
X83200Y262800D03*
Y266200D03*
X93900Y261700D03*
Y265100D03*
X95900Y200500D03*
Y203900D03*
X97000Y261700D03*
Y265100D03*
X113500Y50800D03*
Y54200D03*
X125000Y60300D03*
Y63700D03*
X124500Y128300D03*
Y131700D03*
X123700Y140900D03*
Y144300D03*
X115450Y137800D03*
Y141200D03*
X125000Y215300D03*
Y218700D03*
X113100Y234500D03*
Y237900D03*
X135000Y49800D03*
Y53200D03*
X131500Y49800D03*
Y53200D03*
X129500Y70800D03*
Y74200D03*
X142000Y152300D03*
X148000D03*
X151000D03*
X145000D03*
X153000Y163800D03*
Y167200D03*
X142000Y155700D03*
X148000D03*
X151000D03*
X145000D03*
X167000Y167300D03*
Y170700D03*
X190000Y80800D03*
Y84200D03*
X200000Y180800D03*
Y184200D03*
X212000Y48800D03*
Y52200D03*
X210800Y192300D03*
Y195700D03*
X215500Y212300D03*
Y215700D03*
X222500Y173800D03*
Y177200D03*
X219500Y173800D03*
Y177200D03*
X226000Y212300D03*
Y215700D03*
X239000Y98800D03*
Y102200D03*
X259000Y49300D03*
Y52700D03*
X261000Y165800D03*
Y169200D03*
X263000Y225300D03*
Y228700D03*
X275300Y170200D03*
Y173600D03*
X266000Y225300D03*
Y228700D03*
X271000Y225500D03*
Y228900D03*
X290500Y78300D03*
Y81700D03*
X291800Y97200D03*
Y100600D03*
X284500Y167300D03*
Y170700D03*
X290000Y192300D03*
Y195700D03*
X308000Y257800D03*
Y261200D03*
X319000Y257800D03*
X314500D03*
X319000Y261200D03*
X314500D03*
X368000Y50300D03*
Y53700D03*
X365000Y50300D03*
Y53700D03*
X362000Y50300D03*
Y53700D03*
X359000Y50300D03*
Y53700D03*
X382500Y53800D03*
Y57200D03*
X397900Y269400D03*
Y272800D03*
X444600Y251400D03*
Y254800D03*
X443000Y278300D03*
Y281700D03*
X452000Y278300D03*
Y281700D03*
X526500Y74800D03*
Y78200D03*
X522500Y201800D03*
Y205200D03*
X518500Y201800D03*
Y205200D03*
X530000Y72300D03*
X536500D03*
X533500D03*
X530000Y75700D03*
X536500D03*
X533500D03*
X566500Y74300D03*
Y77700D03*
X577000Y79800D03*
Y83200D03*
X612500Y204800D03*
Y208200D03*
Y216300D03*
Y219700D03*
X622500Y78300D03*
Y81700D03*
X634000Y129300D03*
Y132700D03*
X645000Y165300D03*
Y168700D03*
X643500Y178800D03*
Y182200D03*
X639800Y189500D03*
Y192900D03*
X694900Y181400D03*
X691900D03*
X694900Y184800D03*
X691900D03*
X688500Y223300D03*
Y226700D03*
X685500Y223300D03*
Y226700D03*
X697500Y223300D03*
Y226700D03*
X721300Y130200D03*
Y133600D03*
X718000Y130200D03*
Y133600D03*
X721700Y123200D03*
Y126600D03*
X715000Y140300D03*
Y143700D03*
X728000Y88400D03*
X731000D03*
X736500Y104600D03*
X728000Y91800D03*
X731000D03*
X736500Y108000D03*
X734000Y155300D03*
Y158700D03*
X731000Y155300D03*
Y158700D03*
X741500Y179300D03*
Y182700D03*
X738500Y179300D03*
Y182700D03*
X737000Y197800D03*
X728000Y210300D03*
Y213700D03*
X737000Y201200D03*
X751500Y155300D03*
Y158700D03*
X766500Y122800D03*
Y126200D03*
X779500Y34807D03*
Y38207D03*
X782500Y34807D03*
Y38207D03*
X805500Y131300D03*
Y134700D03*
G54D43*
X73189Y221339D03*
Y222913D03*
Y224488D03*
Y226063D03*
Y227638D03*
Y229213D03*
Y230787D03*
Y232362D03*
Y233937D03*
Y235512D03*
Y237087D03*
Y238661D03*
X95811Y227638D03*
Y226063D03*
Y224488D03*
Y222913D03*
Y221339D03*
Y238661D03*
Y237087D03*
Y235512D03*
Y233937D03*
Y232362D03*
Y230787D03*
Y229213D03*
G54D136*
X792900Y180250D03*
Y179750D03*
X792800Y183850D03*
Y184350D03*
G54D146*
G01X60600Y208800D02*
X63700D01*
X63800Y208700D01*
G01X61400Y201800D02*
Y198300D01*
G01Y201800D02*
Y204400D01*
X60600Y205200D01*
G01X63800Y205300D02*
X60700D01*
X60600Y205200D01*
G01X54000Y217700D02*
X51500D01*
X51300Y217500D01*
G01X73189Y226063D02*
X71327D01*
X69489Y224225D01*
Y221800D01*
X66189Y218500D01*
X61560D01*
X60127Y217067D01*
G01D02*
X59994Y217200D01*
X54500D01*
X54000Y217700D01*
G01X61300Y249900D02*
X62400Y248800D01*
Y245049D01*
X67549Y239900D01*
X67576D01*
X67988Y239488D01*
G01X74800Y191000D02*
Y193100D01*
X73900Y194000D01*
G01D02*
Y196500D01*
X72400Y198000D01*
G01X77500Y194000D02*
Y191800D01*
X78900Y190400D01*
X79000D01*
G01X77500Y194000D02*
Y197900D01*
X77400Y198000D01*
G01X66900Y192500D02*
Y195400D01*
X68000Y196500D01*
Y198300D01*
G01X76900Y207200D02*
X74200D01*
G01D02*
Y209612D01*
X74544Y209956D01*
Y213236D01*
G01X73189Y221339D02*
Y218989D01*
X68652Y214452D01*
Y212848D01*
G01X63800Y208700D02*
X64700D01*
X68652Y212652D01*
Y212848D01*
G01X77413Y218689D02*
Y216323D01*
X78400Y215336D01*
Y210927D01*
X78623Y210704D01*
G01X77400Y203200D02*
X72400D01*
G01X77400D02*
X80300Y206100D01*
Y207200D01*
G01D02*
Y209027D01*
X78623Y210704D01*
G01X65000Y201800D02*
X67900D01*
X68000Y201700D01*
G01D02*
X68500Y202200D01*
X69078D01*
X70078Y203200D01*
X72400D01*
G01X67400Y205500D02*
X68300Y206400D01*
Y209101D01*
X71052Y211853D01*
Y213152D01*
X75839Y217939D01*
Y218689D01*
G01X67400Y205500D02*
X67200Y205300D01*
X63800D01*
G01X68000Y198300D02*
X65000D01*
G01X64100Y211800D02*
Y215001D01*
X64768Y215669D01*
G01X64100Y220800D02*
X66289D01*
X68000Y222511D01*
Y224778D01*
X70860Y227638D01*
X73189D01*
G01Y229213D02*
X70513D01*
X69287Y227987D01*
X67813D01*
G01X73189Y224488D02*
X71591D01*
X70789Y223686D01*
Y220289D01*
X67000Y216500D01*
X65599D01*
X64768Y215669D01*
G01X71067Y249509D02*
X70758Y249200D01*
X69900D01*
X67500Y246800D01*
Y245212D01*
X71800Y240912D01*
Y239400D01*
X72539Y238661D01*
X73189D01*
G01X64800Y246073D02*
X70500Y240373D01*
Y238177D01*
X71590Y237087D01*
X73189D01*
G01X67988Y239488D02*
X68476Y239000D01*
Y237415D01*
X70379Y235512D01*
X73189D01*
G01X77413Y241311D02*
Y243087D01*
X76600Y243900D01*
X73500D01*
X72600Y244800D01*
G01X75839Y241311D02*
X73389D01*
X69400Y245300D01*
Y246000D01*
G01X78988Y241311D02*
Y243412D01*
X75700Y246700D01*
X75600D01*
G01X82100Y259600D02*
X79000Y256500D01*
X77700D01*
G01X80800Y249800D02*
Y248700D01*
X79000Y246900D01*
G01X80563Y241311D02*
Y243676D01*
X79000Y245239D01*
Y246900D01*
G01X70800Y252600D02*
Y252500D01*
X71067Y252233D01*
Y249509D01*
G01X74100Y256200D02*
X73500D01*
X70800Y253500D01*
Y252600D01*
G01X67400Y249500D02*
X67000Y249900D01*
X64400D01*
G01D02*
Y246473D01*
X64800Y246073D01*
G01X70100Y259300D02*
Y262400D01*
X70200Y262500D01*
G01X74400Y252600D02*
X74467Y252533D01*
Y249509D01*
G01X69400Y246000D02*
X70958D01*
X74467Y249509D01*
G01X77700Y253100D02*
X77200Y252600D01*
Y249800D01*
G01D02*
Y248300D01*
X75600Y246700D01*
G01X73600Y266109D02*
X77009D01*
X77100Y266200D01*
G01D02*
X80200D01*
G01D02*
Y266800D01*
X78000Y269000D01*
X77100D01*
G01X71800Y268800D02*
X73600Y267000D01*
Y266109D01*
G01X81700Y272600D02*
X77300D01*
X77100Y272400D01*
G01Y262600D02*
X80000D01*
X80200Y262800D01*
G01X77100Y262600D02*
X73691D01*
X73600Y262509D01*
G01X70200Y262500D02*
X73591D01*
X73600Y262509D01*
G01X89600Y197200D02*
X84800D01*
X84700Y197100D01*
G01X80300Y186500D02*
Y186800D01*
X83500Y190000D01*
Y191000D01*
G01X80300Y194000D02*
X80327D01*
X83327Y191000D01*
X83500D01*
G01X83700Y194000D02*
X83673D01*
X81960Y195713D01*
Y199734D01*
G01X83700Y186500D02*
X88000D01*
G01D02*
X102700D01*
X104700Y188500D01*
G01X91800Y192500D02*
X88400D01*
X86900Y191000D01*
G01X86862Y218689D02*
Y214423D01*
X89485Y211800D01*
X92802D01*
X94002Y210600D01*
G01X95600Y207100D02*
Y209002D01*
X94002Y210600D01*
G01X86400Y203300D02*
Y201100D01*
X85898Y200598D01*
G01X86400Y206900D02*
X86300Y206800D01*
X83400D01*
G01X82138Y218689D02*
Y215835D01*
X82463Y215510D01*
Y211455D01*
X83447Y210471D01*
G01X83400Y206800D02*
X83447Y206847D01*
Y210471D01*
G01X83400Y203400D02*
X81960Y201960D01*
Y199734D01*
G01X105700Y200000D02*
Y207795D01*
X104295Y209200D01*
X100500D01*
X96700Y213000D01*
X93661D01*
X93561Y213100D01*
X90024D01*
X88437Y214687D01*
Y218689D01*
G01X93161D02*
Y217839D01*
X94800Y216200D01*
X95200D01*
G01X80563Y218689D02*
Y214700D01*
G01X107462Y209526D02*
X105788Y211200D01*
X100600D01*
X97500Y214300D01*
X94200D01*
X91587Y216913D01*
Y218689D01*
G01X90012D02*
Y216000D01*
X90812Y215200D01*
Y215000D01*
G01X82138Y241311D02*
Y246338D01*
X82400Y246600D01*
G01X95800Y241311D02*
X93161D01*
G01X86600Y249500D02*
X86300Y249200D01*
Y245939D01*
X85562Y245201D01*
Y245135D01*
X85287Y244860D01*
Y241311D01*
G01X88437D02*
Y243438D01*
X91400Y246401D01*
Y250800D01*
G01X93800Y246400D02*
X93238D01*
X90012Y243174D01*
Y241311D01*
G01X88900Y246700D02*
X86862Y244662D01*
Y241311D01*
G01X97600Y246500D02*
Y245400D01*
X96000Y243800D01*
X92477D01*
X91587Y242910D01*
Y241311D01*
G01X83713D02*
Y245125D01*
X84300Y245712D01*
Y247388D01*
X82300Y249388D01*
Y251173D01*
X82000Y251473D01*
Y254500D01*
G01X89500Y258300D02*
Y261200D01*
X89800Y261500D01*
G01X86200D02*
Y258500D01*
X86400Y258300D01*
G01Y254900D02*
X82400D01*
X82000Y254500D01*
G01X89500Y254900D02*
X86400D01*
G01X89800Y261500D02*
Y263700D01*
X88500Y265000D01*
G01X80500Y269500D02*
X81700Y270700D01*
Y272600D01*
G01X80200Y262800D02*
X83200D01*
G01D02*
X84900D01*
X86200Y261500D01*
G01X83200Y266200D02*
Y268800D01*
X83900Y269500D01*
G01X102200Y197000D02*
Y194000D01*
G01X95200Y192500D02*
X98200D01*
X98500Y192200D01*
G01X102200Y194000D02*
X100400Y192200D01*
X98500D01*
G01X102300Y200000D02*
X102200Y199900D01*
Y197000D01*
G01X105800Y194000D02*
Y197000D01*
G01D02*
X105700Y197100D01*
Y200000D01*
G01X108300Y188500D02*
Y191500D01*
X105800Y194000D01*
G01X104700Y188500D02*
X108300D01*
G01X101300D02*
X97800D01*
X97100Y189200D01*
G01X95900Y203900D02*
X95600Y204200D01*
Y207100D01*
G01X98900Y204000D02*
Y207000D01*
X99000Y207100D01*
G01D02*
X99100Y207200D01*
X102900D01*
X103300Y206800D01*
G01X95900Y200500D02*
X96000Y200400D01*
X98900D01*
G01D02*
X101900D01*
X102300Y200000D01*
G01D02*
Y202900D01*
X102000Y203200D01*
G01X121000Y214900D02*
X120687Y214587D01*
Y210750D01*
X120650Y210713D01*
Y210500D01*
X118950Y208800D01*
X114930D01*
X112530Y211200D01*
X109136D01*
X107462Y209526D01*
G01X95811Y224488D02*
X98112D01*
X100600Y222000D01*
Y221100D01*
G01X95811Y221339D02*
Y219589D01*
X97194Y218206D01*
G01X95811Y222913D02*
X97410D01*
X98600Y221723D01*
Y220412D01*
X100112Y218900D01*
X103800D01*
X104000Y219100D01*
G01X108800Y228400D02*
X105813D01*
X105000Y229213D01*
G01X95811Y227638D02*
X100562D01*
X104000Y224200D01*
G01X95811Y226063D02*
X99237D01*
X99600Y225700D01*
G01X95811Y229213D02*
X105000D01*
G01X100700Y231800D02*
X98422D01*
X97409Y230787D01*
X95811D01*
G01Y233937D02*
X97895D01*
X99328Y235370D01*
G01X125000Y215300D02*
X124600Y214900D01*
X121000D01*
G01X112200Y228400D02*
Y230900D01*
X112700Y231400D01*
G01D02*
X113100Y231800D01*
Y234500D01*
G01X208800Y216000D02*
Y219500D01*
G01X212200Y216000D02*
Y219200D01*
X212500Y219500D01*
G01X317352Y158681D02*
X317255D01*
X317225Y158711D01*
X314448D01*
X313570Y159589D01*
X313390D01*
G01X355282Y106129D02*
X354402Y105249D01*
Y103989D01*
X354382Y103969D01*
Y102171D01*
G01X381550Y117400D02*
X383500Y119350D01*
Y120329D01*
X384272Y121101D01*
G01X394400Y266100D02*
Y269800D01*
X394300Y269900D01*
G01X397900Y269400D02*
X397400Y269900D01*
X394300D01*
G01D02*
X391600D01*
X390500Y268800D01*
G01X423496Y144000D02*
X423902Y144406D01*
Y146861D01*
X425402Y148361D01*
G01X608300Y52007D02*
X607500Y52807D01*
Y58873D01*
X620627Y72000D01*
X630000D01*
G01X623500Y74500D02*
X619874D01*
X605200Y59826D01*
Y51734D01*
X607927Y49007D01*
X608300D01*
G01X739500Y108000D02*
X739529D01*
X745900Y101629D01*
Y98663D01*
X741737Y94500D01*
X734000D01*
X731000Y97500D01*
X719193D01*
X704043Y82350D01*
X641350D01*
X631000Y72000D01*
X630000D01*
G01X739900Y101500D02*
Y98400D01*
X738000Y96500D01*
X734829D01*
X731829Y99500D01*
X717940D01*
X703090Y84650D01*
X640650D01*
X630500Y74500D01*
X623500D01*
G01X718400Y119700D02*
Y122900D01*
X718700Y123200D01*
G01X718400Y119700D02*
Y116400D01*
G01D02*
Y112800D01*
G01X725200Y116500D02*
Y113500D01*
X724400Y112700D01*
G01D02*
X723000D01*
X722000Y113700D01*
Y116400D01*
G01Y119700D02*
X725000D01*
X725200Y119900D01*
G01D02*
X729100D01*
X729400Y120200D01*
G01X735654Y126676D02*
X734015D01*
X731939Y124600D01*
X731212D01*
X729342Y122730D01*
X725270D01*
X724900Y123100D01*
X724700D01*
G01X721700Y123200D02*
X721900D01*
X722000Y123100D01*
X724700D01*
G01X718700Y123200D02*
X721700D01*
G01X724700Y126700D02*
X724900D01*
X726470Y125130D01*
X728130D01*
X728224Y125224D01*
X728440D01*
G01X721700Y126600D02*
X721800Y126700D01*
X724700D01*
G01X721300Y133600D02*
X724900D01*
G01D02*
Y133500D01*
X727500Y130900D01*
X730312D01*
X730813Y131401D01*
X735654D01*
G01X715000Y143700D02*
X718000D01*
G01X721000Y143800D02*
X722000Y142800D01*
X724600D01*
G01D02*
X727216D01*
X729187Y140829D01*
Y137901D01*
X730963Y136125D01*
X735654D01*
G01X718000Y143700D02*
X720900D01*
X721000Y143800D01*
G01X736500Y104600D02*
X739500D01*
G01X736500Y101500D02*
Y104600D01*
G01X743500Y100500D02*
Y101200D01*
X740100Y104600D01*
X739500D01*
G01X732300Y102100D02*
X735900Y98500D01*
X736900D01*
G01X735900Y111100D02*
Y108600D01*
X736500Y108000D01*
G01X735900Y111100D02*
Y114129D01*
X739771Y118000D01*
X741900D01*
X742100Y118200D01*
G01X739500Y111100D02*
Y108000D01*
G01X747466Y124313D02*
Y120737D01*
X741500Y114771D01*
Y114071D01*
X739500Y112071D01*
Y111100D01*
G01X744317Y124313D02*
Y122495D01*
X742222Y120400D01*
X738592D01*
X736300Y118108D01*
Y118000D01*
G01X732300Y107300D02*
Y114000D01*
X736300Y118000D01*
G01X729500Y111500D02*
Y114400D01*
X737113Y122013D01*
X741940D01*
X742742Y122815D01*
Y124313D01*
G01X728000Y107700D02*
Y110000D01*
X729500Y111500D01*
G01X729400Y120200D02*
X730100Y119500D01*
X731894D01*
X736719Y124313D01*
X738017D01*
G01X727448Y128893D02*
X727693D01*
X727700Y128900D01*
X732100D01*
X733026Y129826D01*
X735654D01*
G01X728900Y132976D02*
X735654D01*
G01Y134550D02*
X730514D01*
X728464Y136600D01*
X727800D01*
G01X728440Y125224D02*
X729916Y126700D01*
X732200D01*
X733751Y128251D01*
X735654D01*
G01X741167Y153000D02*
Y143213D01*
G01X728000Y155300D02*
Y155044D01*
X731794Y151250D01*
X733600D01*
X734000Y150850D01*
G01X738017Y143213D02*
Y145587D01*
X736100Y147504D01*
Y148750D01*
X734000Y150850D01*
G01X731000Y155300D02*
Y155000D01*
X732750Y153250D01*
X734995D01*
X738500Y149745D01*
Y148500D01*
G01X739592Y143213D02*
Y147408D01*
X738500Y148500D01*
G01X741167Y153000D02*
X738967Y155200D01*
X737000D01*
G01X734000Y155300D02*
X736900D01*
X737000Y155200D01*
G01X741000Y158500D02*
X744800D01*
G01X746100Y108100D02*
Y104258D01*
X748858Y101500D01*
X749500D01*
G01X745891Y124313D02*
Y121991D01*
X742100Y118200D01*
G01X749041Y124313D02*
Y119141D01*
X745100Y115200D01*
Y114900D01*
G01X742500Y108100D02*
Y110800D01*
X742200Y111100D01*
G01D02*
Y111400D01*
X745100Y114300D01*
Y114900D01*
G01X752191Y124313D02*
Y121809D01*
X754000Y120000D01*
G01X750616Y124313D02*
Y121004D01*
X751200Y120420D01*
Y118300D01*
X751300Y118200D01*
G01X745600Y111100D02*
Y111900D01*
X748800Y115100D01*
Y115800D01*
G01X754554Y132976D02*
X758876D01*
X760900Y135000D01*
X762100D01*
G01X760587Y138200D02*
X758664D01*
X756589Y136125D01*
X754554D01*
G01Y126676D02*
X755924D01*
X757900Y124700D01*
G01X766500Y126200D02*
X766300Y126000D01*
X759288D01*
X757037Y128251D01*
X754554D01*
G01Y131401D02*
X758099D01*
X758500Y131000D01*
X759400D01*
G01X754554Y129826D02*
X757674D01*
X759000Y128500D01*
G01X754554Y134550D02*
X757702D01*
X758176Y135024D01*
G01X754554Y137700D02*
X756325D01*
X759700Y141075D01*
Y141100D01*
G01X754554Y139275D02*
X756061D01*
X757000Y140214D01*
Y143000D01*
X758100Y144100D01*
G01X745891Y143213D02*
Y144891D01*
X752500Y151500D01*
G01X754500Y155300D02*
Y153500D01*
X752500Y151500D01*
G01X751500Y155300D02*
Y154000D01*
X746782Y149282D01*
G01X744317Y143213D02*
Y146817D01*
X746782Y149282D01*
G01X742742Y143213D02*
Y149742D01*
X744700Y151700D01*
Y155500D01*
G01X752191Y143213D02*
Y146613D01*
G01X744000Y161800D02*
X744800Y161000D01*
Y158500D01*
G01D02*
X744700Y158400D01*
Y155500D01*
G01X763300Y142900D02*
X761500D01*
X759700Y141100D01*
G01X787800Y179900D02*
X789000Y181100D01*
X792050D01*
X792900Y180250D01*
G01X787600Y183300D02*
X787800Y183100D01*
X792050D01*
X792800Y183850D01*
G01X792900Y179750D02*
Y174600D01*
G01D02*
X793000Y174500D01*
G01X792800Y184350D02*
Y186369D01*
G01D02*
X794110Y187679D01*
G01X805500Y131300D02*
Y128000D01*
G54D137*
G01X143220Y96675D02*
X141124D01*
X141119Y96680D01*
X138596D01*
X136500Y98776D01*
Y101523D01*
G01X143220Y102580D02*
X137610D01*
X136553Y101523D01*
X136500D01*
G01X130000Y121000D02*
X130710Y120290D01*
X137490D01*
X137495Y120295D01*
X143220D01*
G01Y114390D02*
X138160D01*
X136770Y113000D01*
G01X143220Y126200D02*
X136600D01*
X136500Y126300D01*
G01X152811Y84300D02*
Y82011D01*
X149755Y78955D01*
X143220D01*
G01Y90770D02*
X149230D01*
X152811Y87189D01*
Y84300D01*
G01D02*
X152251Y84860D01*
X143220D01*
G01X165755D02*
X153371D01*
X152811Y84300D01*
G01X143220Y108485D02*
X148585D01*
X149600Y109500D01*
Y111030D01*
X150670Y112100D01*
G01X165755Y108485D02*
X161169D01*
X160954Y108700D01*
X154070D01*
X150670Y112100D01*
G01X165755Y78955D02*
Y69745D01*
X167500Y68000D01*
G01X158105Y96775D02*
Y99911D01*
X160774Y102580D01*
X165755D01*
G01Y90770D02*
X160035D01*
X158105Y92700D01*
Y96775D01*
G01X165755Y96675D02*
X158205D01*
X158105Y96775D01*
G01X165755Y102580D02*
X173980D01*
X174500Y103100D01*
G01X165755Y120295D02*
X158306D01*
X157229Y119218D01*
G01X157175Y115462D02*
X158247Y114390D01*
X165755D01*
G01X171800Y126600D02*
X171400Y126200D01*
X165755D01*
G01X162000Y146889D02*
Y137050D01*
X163000Y136050D01*
X165750D01*
X165755Y136045D01*
G54D26*
X32000Y222500D03*
Y219000D03*
Y229500D03*
Y226000D03*
Y236500D03*
Y233000D03*
Y243500D03*
Y240000D03*
Y250500D03*
Y247000D03*
Y257500D03*
Y254000D03*
X36000Y158000D03*
X43300Y212700D03*
Y207800D03*
X40500Y198800D03*
Y203700D03*
X43500D03*
Y198800D03*
X46300Y212700D03*
Y207800D03*
X61700Y198300D03*
Y201800D03*
X77000Y85000D03*
X70900Y207200D03*
X77500Y249800D03*
X89300Y207100D03*
X86500Y261500D03*
X180000Y75500D03*
X222800Y89900D03*
X437000Y278000D03*
X535500Y234100D03*
X608500Y96000D03*
Y93000D03*
X702000Y192500D03*
X718700Y119700D03*
Y116400D03*
X736200Y111100D03*
X742800Y108100D03*
X745000Y155500D03*
X776500Y16000D03*
G54D80*
X281000Y152654D03*
Y162346D03*
G54D128*
X785015Y132549D03*
X800015D03*
X795015D03*
X790015D03*
G54D44*
X93200Y142200D03*
Y152800D03*
X101700Y142200D03*
Y152800D03*
X102500Y165700D03*
Y176300D03*
X107900Y243700D03*
Y254300D03*
G54D119*
X681500Y194250D03*
X686500D03*
X691500D03*
Y213750D03*
X686500D03*
X681500D03*
X696500Y194250D03*
Y213750D03*
G54D35*
X62250Y84300D03*
G54D53*
X117500Y228100D03*
X127300D03*
X117500Y239900D03*
X127300D03*
X784400Y103000D03*
X794200D03*
X804400Y212800D03*
X794600D03*
G54D62*
X148445Y257000D03*
X172555D03*
G54D71*
G01X194800Y206100D02*
Y209099D01*
X195851Y210150D01*
G01X194800Y206100D02*
Y205100D01*
X197299Y202601D01*
X198200D01*
X196800Y62600D03*
X199600Y160100D03*
X239300Y196800D03*
X317132Y102711D03*
X313932Y105911D03*
Y102711D03*
Y202751D03*
X317132Y205951D03*
X313932D03*
X437592Y105911D03*
X434392Y102711D03*
X440792Y109111D03*
Y202751D03*
Y205951D03*
X437592D03*
X502500Y6200D03*
X538300Y15200D03*
X699000Y162255D03*
X756400Y110500D03*
X786500Y13500D03*
X784000Y31000D03*
X782000Y137000D03*
X790500Y11000D03*
X799000Y121500D03*
Y125500D03*
X800400Y158500D03*
X799900Y168800D03*
X811000Y130000D03*
Y134000D03*
X809000Y149200D03*
X811000Y138000D03*
X811200Y141600D03*
X809500Y156900D03*
X809600Y160500D03*
X809700Y164300D03*
G54D17*
X31300Y87500D03*
X27900D03*
X22000Y169300D03*
X18600D03*
X24400Y210100D03*
X21000D03*
X28400Y206900D03*
X25000D03*
X38900Y184000D03*
X35500D03*
X52600Y244400D03*
X49200D03*
X52600Y241400D03*
X49200D03*
X64100Y232800D03*
X60700D03*
X52600Y250400D03*
X49200D03*
X64200Y269500D03*
X60800D03*
X61200Y272500D03*
X57800D03*
X76400Y139200D03*
X73000D03*
X95200Y192500D03*
X91800D03*
X83700Y194000D03*
X80300D03*
X83700Y186500D03*
X80300D03*
X108300Y188500D03*
X99000Y207100D03*
X95600D03*
X123800Y134800D03*
Y147500D03*
X111700Y188500D03*
X127200Y134800D03*
Y147500D03*
X136200Y269000D03*
X132800D03*
X156300Y152200D03*
X159700D03*
X164300Y155200D03*
X160900D03*
X183200Y72500D03*
X179800D03*
X197200D03*
X193800D03*
X200800Y92500D03*
X204200D03*
X211200D03*
X207800D03*
X212200Y216000D03*
X208800D03*
X233800Y70000D03*
Y67000D03*
X237200Y70000D03*
Y67000D03*
X262300Y53000D03*
X254700Y130000D03*
X251300D03*
X264600Y166300D03*
X278800Y59000D03*
X265700Y53000D03*
X278800Y62000D03*
X275700Y124000D03*
X272300D03*
X278200Y145500D03*
X274800D03*
X268000Y166300D03*
X273700Y178400D03*
X270300D03*
X271700Y170000D03*
X268300D03*
X275700Y219000D03*
X272300D03*
X270900Y232100D03*
X267500D03*
X282200Y59000D03*
Y62000D03*
X293200Y118000D03*
X289800D03*
X293200Y121000D03*
X289800D03*
X293200Y135500D03*
X289800D03*
X293200Y132500D03*
X289800D03*
X291700Y147500D03*
X288300D03*
X291700Y144000D03*
X288300D03*
X293700Y167000D03*
X290300D03*
X293700Y173500D03*
X290300D03*
X293700Y170500D03*
X290300D03*
X293300Y188800D03*
X289900D03*
X284700Y225000D03*
X281300D03*
X284700Y222000D03*
X281300D03*
X308700Y54000D03*
X305300D03*
X397800Y263100D03*
X394400D03*
X418600Y81500D03*
X415200D03*
X431900Y79500D03*
X428500D03*
X425200Y81500D03*
X421800D03*
X433200Y228000D03*
X429800D03*
X433700Y278000D03*
X430300D03*
X441200Y228000D03*
X437800D03*
X462200Y143563D03*
X458800D03*
X462200Y147063D03*
X458800D03*
X506200Y132000D03*
X502800D03*
X506200Y135000D03*
X502800D03*
X538700Y237100D03*
X535300D03*
X546600Y204600D03*
X543200D03*
X611700Y49007D03*
X608300D03*
X611700Y52007D03*
X608300D03*
X617300Y128500D03*
X615800Y178500D03*
X630200Y133000D03*
X626800D03*
X620700Y128500D03*
X619200Y178500D03*
X625800D03*
X622400D03*
X640200Y163000D03*
X636800D03*
X646500Y189400D03*
X643100D03*
X647200Y237500D03*
X643800D03*
X664200Y189500D03*
X660800D03*
X680800Y183000D03*
X669900Y184000D03*
X666500D03*
X684200Y183000D03*
X711300Y150000D03*
X724700Y147000D03*
X721300D03*
X714700Y150000D03*
X739900Y101500D03*
X736500D03*
X742200Y111100D03*
X745600D03*
X748200Y158500D03*
X744800D03*
X761700Y122000D03*
X758300D03*
X781700Y19000D03*
X778300D03*
X781700Y28000D03*
X778300D03*
X779700Y128600D03*
X776300D03*
G54D147*
G01X33150Y181500D02*
Y181589D01*
X28489Y186250D01*
X18041D01*
X16775Y184984D01*
Y178425D01*
X18500Y176700D01*
G01X16844Y203100D02*
Y207644D01*
X17300Y208100D01*
G01X21000Y210100D02*
X19300D01*
X17300Y208100D01*
G01X33500Y178100D02*
X31225Y180375D01*
Y180756D01*
X27681Y184300D01*
X19100D01*
X18500Y183700D01*
G01X22000Y169300D02*
X24200Y171500D01*
X27500D01*
X28209Y172209D01*
Y175152D01*
G01X23100Y181800D02*
X23900D01*
X28209Y177491D01*
Y175152D01*
G01X18500Y180300D02*
X19900Y178900D01*
X23900D01*
X25649Y177151D01*
Y175152D01*
G01X23089D02*
X20352D01*
X18500Y173300D01*
G01X28209Y190832D02*
Y195409D01*
X28175Y195443D01*
Y199875D01*
X28400Y200100D01*
G01X35500Y187000D02*
Y188600D01*
X33268Y190832D01*
X30769D01*
G01X24900Y197300D02*
X21900D01*
G01X25649Y190832D02*
Y196551D01*
X24900Y197300D01*
G01X28400Y203800D02*
Y200100D01*
G01Y206900D02*
Y203800D01*
G01X35500Y184000D02*
Y187000D01*
G01X58800Y177000D02*
X64625Y182825D01*
Y187775D01*
X60900Y191500D01*
Y195046D01*
X58500Y197446D01*
Y209218D01*
X60700Y211418D01*
Y211800D01*
G01Y232800D02*
X60574D01*
X56825Y236549D01*
Y243199D01*
X56724Y243300D01*
G01X52500Y238200D02*
X52526D01*
X56225Y241899D01*
Y242801D01*
X56724Y243300D01*
G01X49500Y238200D02*
X52500D01*
G01X60700Y238800D02*
X60425Y239075D01*
Y247649D01*
X58461Y249613D01*
X56800D01*
G01X60700Y229800D02*
X57218D01*
X57009Y230009D01*
G01X60700Y235800D02*
X60600D01*
X58625Y237775D01*
Y245946D01*
X58102Y246469D01*
Y246471D01*
G01D02*
X57313D01*
X54425Y243583D01*
Y243099D01*
X54001Y242675D01*
X53875D01*
X52600Y241400D01*
G01Y247400D02*
X54587D01*
X56800Y249613D01*
G01X52600Y247400D02*
Y244400D01*
G01X64100Y235800D02*
X65284D01*
X67892Y233192D01*
G01X73189Y232362D02*
X68722D01*
X67892Y233192D01*
G01X64100Y238800D02*
X65500D01*
X70363Y233937D01*
X73189D01*
G01X64100Y232800D02*
X64935D01*
X66948Y230787D01*
X73189D01*
G01X109700Y60000D02*
X107775Y61925D01*
Y78393D01*
X111065Y81683D01*
X114699D01*
X117625Y84609D01*
Y90344D01*
X127925Y100644D01*
Y117975D01*
X126100Y119800D01*
Y121000D01*
G01X136600Y44800D02*
X125442D01*
X122440Y47802D01*
Y49250D01*
G01X118000Y50800D02*
X119550Y49250D01*
X122440D01*
G01X120200Y45610D02*
X117568D01*
X116089Y47089D01*
G01X113500Y50800D02*
Y49678D01*
X116089Y47089D01*
G01X113500Y50800D02*
X116900Y54200D01*
X118000D01*
G01D02*
X118582D01*
X120132Y55750D01*
X122440D01*
G01X125000Y60300D02*
Y55750D01*
G01Y49250D02*
Y48000D01*
X126375Y46625D01*
X139985D01*
X140026Y46584D01*
G01X125000Y55750D02*
Y49250D01*
G01Y63700D02*
X149300D01*
X153000Y67400D01*
Y67800D01*
G01X121170Y80900D02*
X117500Y77230D01*
Y72481D01*
X115669Y70650D01*
G01X125787Y78813D02*
Y83013D01*
X124175Y84625D01*
Y86974D01*
X131576Y94375D01*
X135022D01*
X135772Y95125D01*
X137357D01*
X137777Y94705D01*
X143220D01*
G01Y112420D02*
X138630D01*
X137485Y111275D01*
X136755D01*
X134525Y109045D01*
Y100172D01*
X122625Y88272D01*
Y83975D01*
X122995Y83605D01*
Y79202D01*
X121295Y77502D01*
G01X124500Y128300D02*
X121600D01*
X121500Y128200D01*
G01X130563Y125200D02*
X130400D01*
X128500Y127100D01*
X125700D01*
X124500Y128300D01*
G01X126950Y125200D02*
X124900D01*
X120900Y121200D01*
Y121000D01*
G01D02*
X120500Y121400D01*
Y126200D01*
X118500Y128200D01*
G01X123700Y140900D02*
Y141200D01*
X126800Y144300D01*
G01X115450Y141200D02*
X123400D01*
X123700Y140900D01*
G01Y154300D02*
Y155200D01*
X127200Y158700D01*
G01X127560Y55750D02*
X128950D01*
X131500Y53200D01*
G01D02*
X133875Y55575D01*
X136375D01*
X138574Y57774D01*
Y57924D01*
G01X135000Y49800D02*
X131500D01*
G01X135000D02*
X138000D01*
G01X131500D02*
X130950Y49250D01*
X127560D01*
G01X140026Y46584D02*
X141922D01*
X143688Y48350D01*
G01X126000Y72500D02*
X127500Y74000D01*
Y76000D01*
X129300Y77800D01*
X129500D01*
G01Y70800D02*
X133938D01*
X137138Y74000D01*
Y76512D01*
G01X129500Y74200D02*
X133500D01*
G01D02*
X134500Y75200D01*
Y77000D01*
X138425Y80925D01*
X143220D01*
G01Y82895D02*
X136195D01*
X131100Y77800D01*
X129500D01*
G01X126000Y86200D02*
X127877Y88077D01*
X137226D01*
X137949Y88800D01*
X143220D01*
G01X134200Y86100D02*
X137442D01*
X138172Y86830D01*
X143220D01*
G01X129300Y84900D02*
X129500Y84700D01*
Y81200D01*
G01X136600Y93300D02*
X137165Y92735D01*
X143220D01*
G01Y106515D02*
X138515D01*
X136923Y104923D01*
X136500D01*
G01X143220Y110455D02*
X139164D01*
X137329Y108620D01*
X136540D01*
G01X127200Y134800D02*
X127400Y135000D01*
X130300D01*
G01X130600Y131800D02*
Y134700D01*
X130300Y135000D01*
G01X135412Y141400D02*
X136962Y139850D01*
X137622D01*
X139236Y138236D01*
Y136600D01*
X139791Y136045D01*
X143220D01*
G01X126800Y140900D02*
X127950Y139750D01*
X131495D01*
X135736Y135509D01*
Y134081D01*
X137712Y132105D01*
X143220D01*
G01Y134075D02*
X138526D01*
X137686Y134915D01*
Y136495D01*
X136156Y138025D01*
G01X133786Y134700D02*
Y133273D01*
X136919Y130140D01*
X143220D01*
G01X133786Y134700D02*
X133182D01*
X130082Y137800D01*
X127200D01*
G01X143220Y124230D02*
X132604D01*
X131634Y125200D01*
X130563D01*
G01X143220Y122265D02*
X132235D01*
X131400Y123100D01*
X128200D01*
X126100Y121000D01*
G01X130600Y128400D02*
X131341Y129141D01*
X133975D01*
G01D02*
X134941Y128175D01*
X138843D01*
X138848Y128170D01*
X143220D01*
G01X131762Y141796D02*
Y141813D01*
X129275Y144300D01*
X126800D01*
G01X142000Y152300D02*
Y150000D01*
X140500Y148500D01*
Y145000D01*
X144600Y140900D01*
X148800D01*
X150400Y139300D01*
Y131061D01*
X159196Y122265D01*
X165755D01*
G01X135500Y150100D02*
Y141500D01*
X135412Y141412D01*
Y141400D01*
G01X127000Y150800D02*
Y147700D01*
X127200Y147500D01*
G01X136156Y138025D02*
X133587Y140594D01*
Y142713D01*
X129500Y146800D01*
X127900D01*
X127200Y147500D01*
G01X146396Y207675D02*
Y206049D01*
X133113Y192766D01*
Y165909D01*
X135947Y163075D01*
X145664D01*
X148550Y160189D01*
Y158276D01*
X151000Y155826D01*
Y155700D01*
G01X148000D02*
X146600Y157100D01*
Y159381D01*
X144856Y161125D01*
X135139D01*
X131163Y165101D01*
Y193963D01*
X137757Y200557D01*
G01X142997Y207891D02*
X143025Y207863D01*
Y205825D01*
X137757Y200557D01*
G01X165755Y86830D02*
X157170D01*
X153000Y91000D01*
Y97424D01*
X151080Y99344D01*
G01X154294Y76506D02*
X158713Y80925D01*
X165755D01*
G01Y82895D02*
X157292D01*
X150894Y76497D01*
G01X143220Y104545D02*
X152861D01*
X154300Y103106D01*
Y103050D01*
X154550Y102800D01*
G01X165755Y88800D02*
X158706D01*
X154800Y92706D01*
Y98590D01*
X150670Y102720D01*
G01X165755Y110455D02*
X157590D01*
X153693Y114352D01*
Y124807D01*
G01X165755Y106515D02*
X154865D01*
X154550Y106200D01*
G01X151000Y152300D02*
X152475Y150825D01*
Y148639D01*
X156000Y145114D01*
Y134578D01*
X160438Y130140D01*
X165755D01*
G01X148000Y152300D02*
Y151500D01*
X150525Y148975D01*
Y147831D01*
X154050Y144306D01*
Y133770D01*
X159650Y128170D01*
X165755D01*
G01Y124230D02*
X159565D01*
X152100Y131695D01*
Y143498D01*
X148575Y147023D01*
Y147925D01*
X145000Y151500D01*
Y152300D01*
G01X142000Y155700D02*
X140800Y156900D01*
Y158900D01*
G01X150804Y158896D02*
Y161696D01*
X150000Y162500D01*
Y163800D01*
G01D02*
X153000D01*
G01X148800Y205000D02*
Y202400D01*
X146980Y200580D01*
G01X174300Y81500D02*
X173725Y80925D01*
X165755D01*
G01X174300Y84500D02*
X172500D01*
X170895Y82895D01*
X165755D01*
G01X176100Y106100D02*
X174645D01*
X173100Y104555D01*
X169181D01*
X169171Y104545D01*
X165755D01*
G01X178994Y90247D02*
X176753D01*
X173575Y93425D01*
X171730D01*
X170450Y94705D01*
X165755D01*
G01Y92735D02*
X169816D01*
X170960Y91591D01*
X172199D01*
G01X165755Y112420D02*
X159620D01*
X159380Y112180D01*
X158305D01*
G01X165755Y118325D02*
X171025D01*
X172014Y119314D01*
Y121686D01*
X175787Y125459D01*
Y127000D01*
G01X174800Y109600D02*
Y112900D01*
X171340Y116360D01*
X165755D01*
G01X157500Y149025D02*
X159550Y146975D01*
Y136050D01*
X161525Y134075D01*
X165755D01*
G01Y124230D02*
X169176D01*
X169181Y124225D01*
X172219D01*
X173776Y125782D01*
Y127206D01*
X172400Y128582D01*
Y138700D01*
X174275Y140575D01*
Y142450D01*
X176700Y144875D01*
G01X156300Y152200D02*
Y150225D01*
X157500Y149025D01*
G01X167000Y167300D02*
Y164665D01*
X167581Y164084D01*
G01X164300Y155200D02*
Y158700D01*
G01Y155200D02*
X166700D01*
X167400Y155900D01*
G01X171320Y158000D02*
X169490D01*
X168177Y156687D01*
Y156677D01*
X167400Y155900D01*
G01X167000Y170700D02*
X167900Y171600D01*
X173006D01*
X173545Y171061D01*
Y171055D01*
X175577Y169023D01*
Y166123D01*
X176760Y164940D01*
X178680D01*
G01X171320Y167500D02*
X172900D01*
X174100Y166300D01*
Y157400D01*
X176060Y155440D01*
X178680D01*
G01X158300Y187380D02*
Y189024D01*
X161026Y191750D01*
G01X164500Y193200D02*
X162476D01*
X161026Y191750D01*
G01X167600Y193600D02*
X167200Y193200D01*
X164500D01*
G01X179800Y72500D02*
Y65700D01*
G01X187500Y65000D02*
Y65500D01*
X186325Y66675D01*
X185978D01*
X185828Y66825D01*
X183199D01*
X181574Y65200D01*
X180300D01*
X179800Y65700D01*
G01X176900Y67500D02*
X176500Y67100D01*
X174300D01*
X173524Y66324D01*
Y65754D01*
G01X184500Y65000D02*
X183375Y63875D01*
X175403D01*
X173524Y65754D01*
G01X176200Y72500D02*
X177200Y71500D01*
Y67800D01*
X176900Y67500D01*
G01X190000Y84200D02*
X188000D01*
X186500Y82700D01*
G01X174700Y88100D02*
Y89090D01*
X172199Y91591D01*
G01X178000Y97300D02*
X176840Y98460D01*
Y105360D01*
X176100Y106100D01*
G01X179400Y94200D02*
Y90900D01*
X178994Y90494D01*
Y90247D01*
G01X189106Y97235D02*
X185551Y100790D01*
Y107110D01*
X183840Y108821D01*
Y117340D01*
G01X178200Y109600D02*
X178790Y109010D01*
Y100442D01*
X181732Y97500D01*
G01X185500Y91200D02*
Y97500D01*
X180740Y102260D01*
Y111660D01*
X177600Y114800D01*
X175774D01*
X174300Y116274D01*
Y121265D01*
X175495Y122460D01*
X176360D01*
G01X185500Y91200D02*
X188300D01*
X188900Y91800D01*
G01X172300Y107189D02*
X174711Y109600D01*
X174800D01*
G01X176360Y117340D02*
X178760D01*
X182190Y113910D01*
Y107889D01*
X183726Y106353D01*
G01X177000Y134900D02*
X174900Y132800D01*
Y129048D01*
X175787Y128161D01*
Y127000D01*
G01X180300Y131000D02*
X180100Y131200D01*
Y138300D01*
X181466Y139666D01*
Y142065D01*
G01X182400Y127700D02*
X180300Y129800D01*
Y131000D01*
G01X182400Y127700D02*
Y123300D01*
X183240Y122460D01*
X183840D01*
G01X173120Y148500D02*
X174100D01*
X176700Y145900D01*
Y144875D01*
G01X187200Y137500D02*
X183691Y141009D01*
Y142987D01*
X182388Y144290D01*
X178904D01*
X178319Y144875D01*
X176700D01*
G01X181466Y142065D02*
X178965D01*
X177000Y140100D01*
G01X177200Y148700D02*
X179960Y145940D01*
X180480D01*
G01X193500Y65000D02*
Y68700D01*
G01X193800Y72500D02*
Y69000D01*
X193500Y68700D01*
G01X190500Y65000D02*
Y68300D01*
X190100Y68700D01*
G01X190200Y72500D02*
Y68800D01*
X190100Y68700D01*
G01X186900Y68900D02*
X189900D01*
X190100Y68700D01*
G01X212300Y85500D02*
X210800Y87000D01*
X200674D01*
X199299Y85625D01*
X191425D01*
X190000Y84200D01*
G01Y80800D02*
X193675Y77125D01*
X196000D01*
G01X203850Y79900D02*
X201900D01*
X199125Y77125D01*
X196000D01*
G01X187500Y76100D02*
Y76000D01*
X188600Y74900D01*
X203850D01*
G01X193011Y97155D02*
X194000Y96166D01*
Y94200D01*
X194600Y93600D01*
Y92200D01*
G01X193005Y97155D02*
X193011D01*
G01D02*
X194881Y99025D01*
X205500D01*
X207800Y96725D01*
Y92500D01*
G01X197600Y92200D02*
Y92500D01*
X195989Y94111D01*
Y95300D01*
G01X200800Y92500D02*
Y94700D01*
X199400Y96100D01*
X196789D01*
X195989Y95300D01*
G01X194300Y135800D02*
Y131300D01*
X198978Y126622D01*
Y117978D01*
X196871Y115871D01*
X194603D01*
G01X191300Y135800D02*
X190500Y135000D01*
Y122800D01*
X192429Y120871D01*
X194197D01*
G01X197300Y135800D02*
Y131058D01*
X200928Y127430D01*
Y114628D01*
X197171Y110871D01*
X194603D01*
G01X191300Y139200D02*
Y141800D01*
X200258Y150758D01*
Y150759D01*
X201399Y151900D01*
X210788D01*
X212421Y153533D01*
Y153534D01*
X213562Y154675D01*
X229325D01*
X229832Y154168D01*
G01X194300Y139200D02*
Y142042D01*
X202208Y149950D01*
X211596D01*
X214371Y152725D01*
X227515D01*
X228738Y151502D01*
X255202D01*
X261200Y157500D01*
X262000D01*
G01X217913Y24392D02*
Y36175D01*
X218210Y36472D01*
Y38530D01*
X212201Y44539D01*
G01X212000Y48800D02*
Y44740D01*
X212201Y44539D01*
G01X212000Y52200D02*
Y53891D01*
X214300Y56191D01*
G01X205500Y59000D02*
X205925Y59425D01*
X212075D01*
X214300Y57200D01*
Y56191D01*
G01X214942Y67242D02*
X212309Y64609D01*
X210560D01*
G01X221600Y79900D02*
X219600Y77900D01*
Y72900D01*
X218400Y71700D01*
X211700D01*
X208500Y74900D01*
X203850D01*
G01Y84900D02*
X208800D01*
X211600Y82100D01*
G01X216300Y92500D02*
X218500Y90300D01*
Y82900D01*
X221500Y79900D01*
X221600D01*
G01X218800Y142000D02*
X216500D01*
X215750Y141250D01*
Y131250D01*
X214000Y129500D01*
Y116500D01*
X214050Y116450D01*
Y116192D01*
X215200Y115042D01*
Y111700D01*
X216029Y110871D01*
X220893D01*
G01X218800Y136000D02*
Y130700D01*
X216000Y127900D01*
Y117000D01*
X217129Y115871D01*
X220893D01*
G01X218800Y145000D02*
X216500D01*
X213800Y142300D01*
Y132150D01*
X212050Y130400D01*
Y115434D01*
X213250Y114234D01*
Y108750D01*
X216129Y105871D01*
X220893D01*
G01X223800Y61700D02*
X223300Y61200D01*
Y56800D01*
X221600Y55100D01*
Y52500D01*
X223150Y50950D01*
X226140D01*
G01X230400Y63000D02*
X231260Y62140D01*
Y57450D01*
G01X226400Y64609D02*
X228500Y62509D01*
Y61000D01*
X228700Y60800D01*
Y57450D01*
G01X236000Y54400D02*
X229300D01*
G01D02*
X228700Y53800D01*
Y50950D01*
G01Y57450D02*
Y55000D01*
X229300Y54400D01*
G01X219899Y56800D02*
X219574Y56475D01*
Y51726D01*
X222975Y48325D01*
X229825D01*
X231260Y49760D01*
Y50950D01*
G01X223475Y53300D02*
X226140Y55965D01*
Y57450D01*
G01X229098Y70092D02*
X228906Y69900D01*
X223350D01*
G01X233800Y67000D02*
X232190D01*
X229098Y70092D01*
G01X230000Y74900D02*
X233800Y71100D01*
Y70000D01*
G01X248975Y71125D02*
Y68475D01*
X242075Y61575D01*
X234583D01*
X230000Y66158D01*
Y66400D01*
G01X218040Y64609D02*
X219931Y66500D01*
X224509D01*
X226400Y64609D01*
G01X223350Y74900D02*
X230000D01*
G01X223350Y79900D02*
X221600D01*
G01X218800Y139000D02*
Y136000D01*
G01Y148000D02*
Y145000D01*
G01X222200Y142000D02*
X223200Y143000D01*
X224988D01*
X229590Y147602D01*
X247325D01*
X247600Y147327D01*
G01X222200Y145000D02*
X223842D01*
X224500Y145658D01*
Y150200D01*
X225075Y150775D01*
X226707D01*
X227930Y149552D01*
X256011D01*
X261204Y154745D01*
X263637D01*
X265092Y156200D01*
X267100D01*
G01X222200Y139000D02*
X222600D01*
X224500Y140900D01*
X225646D01*
X230398Y145652D01*
X242748D01*
X243298Y145102D01*
X251650D01*
X252200Y145652D01*
X259000D01*
G01X267456Y160156D02*
X266898D01*
X266843Y160101D01*
X257101D01*
X256400Y159400D01*
Y157800D01*
X257200Y157000D01*
Y156258D01*
X256342Y155400D01*
X255200D01*
X254700Y154900D01*
Y153852D01*
X254300Y153452D01*
X252823D01*
X252475Y153800D01*
Y155350D01*
X252025Y155800D01*
X250675D01*
X250225Y155350D01*
Y153902D01*
X249775Y153452D01*
X248425D01*
X247975Y153902D01*
Y155350D01*
X247525Y155800D01*
X246175D01*
X245725Y155350D01*
Y153902D01*
X245275Y153452D01*
X230548D01*
X229832Y154168D01*
G01X239400Y54400D02*
X240600D01*
X244400Y50600D01*
G01X237200Y67000D02*
X240100D01*
X240300Y67200D01*
G01D02*
X242974D01*
X243736Y66438D01*
G01X241496Y71328D02*
X240168Y70000D01*
X237200D01*
G01X243200Y73700D02*
Y73032D01*
X241496Y71328D01*
G01X248975Y71125D02*
X248475Y71625D01*
Y74556D01*
X251619Y77700D01*
X256703D01*
X257128Y77275D01*
X269875D01*
X270150Y77000D01*
G01X270500Y156250D02*
X271700D01*
X272100Y155850D01*
Y153486D01*
X271700Y153086D01*
X270800D01*
X270400Y152686D01*
Y151900D01*
X270000Y151500D01*
X268400D01*
X268000Y151900D01*
Y153850D01*
X267600Y154250D01*
X265900D01*
X265500Y153850D01*
Y151611D01*
X265100Y151211D01*
X264233D01*
X262649Y152795D01*
X262013D01*
X261058Y151840D01*
Y151204D01*
X262698Y149564D01*
Y148998D01*
X261302Y147602D01*
X260700D01*
X259261Y149041D01*
X258258D01*
X256819Y147602D01*
X247875D01*
X247600Y147327D01*
G01X238000Y166700D02*
Y168200D01*
X241525Y171725D01*
X247950D01*
X253125Y176900D01*
X255211D01*
X257125Y178814D01*
Y183883D01*
X259000Y185758D01*
Y188581D01*
X261919Y191500D01*
X262700D01*
G01X238000Y163300D02*
X239950Y165250D01*
Y166950D01*
X241500Y168500D01*
G01X248430Y164600D02*
Y160515D01*
X247700Y159785D01*
X244715D01*
G01X241500Y168500D02*
X242775Y169775D01*
X250595D01*
X252370Y168000D01*
Y164600D01*
G01X246000Y186100D02*
Y185901D01*
X246465Y185436D01*
Y180400D01*
G01X263000Y221500D02*
X267210Y217290D01*
Y215852D01*
X265350Y213992D01*
Y207508D01*
X262400Y204558D01*
Y200131D01*
X256914Y194645D01*
X252595D01*
X249325Y191375D01*
Y185395D01*
X248430Y184500D01*
Y180400D01*
G01X246000Y189800D02*
Y186100D01*
G01X240100Y191000D02*
X242100D01*
X244300Y193200D01*
X246000D01*
G01X246689Y196687D02*
X246781Y196595D01*
X256083D01*
X260000Y200512D01*
Y205500D01*
X263400Y208900D01*
Y214800D01*
X265259Y216659D01*
G01X259000Y49300D02*
Y44900D01*
X261100Y42800D01*
X273200D01*
X275300Y44900D01*
G01X250300Y73800D02*
X251025Y73075D01*
X260747D01*
X267447Y66375D01*
X292715D01*
X295765Y69425D01*
X308306D01*
X308307Y69424D01*
X309632D01*
X309633Y69425D01*
X309922D01*
X314882Y74385D01*
X332142D01*
X334694Y71833D01*
X341941D01*
X343399Y70375D01*
X348899D01*
X354774Y64500D01*
X395262D01*
X405262Y54500D01*
X445272D01*
X457749Y66977D01*
Y90260D01*
X480989Y113500D01*
X490500D01*
X506200Y129200D01*
Y132000D01*
G01X305300Y54000D02*
X303800Y55500D01*
X302840D01*
X294065Y64275D01*
X266789D01*
X259939Y71125D01*
X248975D01*
G01X253700Y75875D02*
X254250Y75325D01*
X266075D01*
X273075Y68325D01*
X291907D01*
X293815Y70233D01*
Y70234D01*
X294956Y71375D01*
X309114D01*
X314074Y76335D01*
X337449D01*
X338470Y75314D01*
X346718D01*
X355582Y66450D01*
X396070D01*
X406070Y56450D01*
X444464D01*
X455799Y67785D01*
Y91069D01*
X456940Y92210D01*
X456941D01*
X501760Y137029D01*
X504171D01*
X506200Y135000D01*
G01X259000Y145652D02*
X262452D01*
X266600Y149800D01*
X267187D01*
G01X262000Y157500D02*
X263634D01*
X264284Y158150D01*
X267650D01*
X267706Y158206D01*
X271346D01*
X272380Y159240D01*
G01X261000Y165800D02*
X258700D01*
X255500Y169000D01*
Y172360D01*
X253500Y174360D01*
G01X254335Y180400D02*
Y184135D01*
X256700Y186500D01*
G01X261000Y169200D02*
Y171822D01*
X259779Y173043D01*
G01X259750Y177440D02*
Y173072D01*
X259779Y173043D01*
G01X259750Y180000D02*
X262800D01*
G01D02*
X266250D01*
G01X262800D02*
Y182800D01*
X264500Y184500D01*
X266000D01*
X267746Y186246D01*
Y189112D01*
X268150Y189516D01*
Y193050D01*
X269500Y194400D01*
G01X252370Y180400D02*
Y182806D01*
X251350Y183826D01*
Y190465D01*
X253580Y192695D01*
X257722D01*
X264350Y199323D01*
Y203750D01*
X267300Y206700D01*
Y213184D01*
X269160Y215044D01*
Y218499D01*
X268600Y219059D01*
G01X253300Y186500D02*
Y189834D01*
G01X256700Y186500D02*
Y189428D01*
X257383Y190111D01*
G01X259750Y182560D02*
Y183750D01*
X263500Y187500D01*
X265400D01*
G01X263000Y221500D02*
Y225300D01*
G01X311300Y277800D02*
X310816D01*
X302816Y269800D01*
X292499D01*
X288824Y273475D01*
X277856D01*
X265425Y261044D01*
Y251943D01*
X263675Y250193D01*
Y243175D01*
X261775Y241275D01*
Y237725D01*
X263000Y236500D01*
Y228700D01*
G01X260500Y264630D02*
Y267381D01*
X268644Y275525D01*
X289533D01*
X293308Y271750D01*
X302008D01*
X313689Y283431D01*
X317769D01*
X320650Y280550D01*
X324150D01*
X325100Y281500D01*
G01X321600Y282500D02*
X321458D01*
X318577Y285381D01*
X312881D01*
X301200Y273700D01*
X294116D01*
X290316Y277500D01*
X267861D01*
X257500Y267139D01*
Y266645D01*
G01X269260Y47940D02*
Y45340D01*
X269800Y44800D01*
G01X276740Y47940D02*
Y46760D01*
X278700Y44800D01*
G01D02*
X280300Y43200D01*
X315509D01*
X316184Y42525D01*
X320935D01*
X321185Y42275D01*
X322615D01*
X324176Y43836D01*
Y48600D01*
G01X276740Y53060D02*
X280064D01*
X288374Y44750D01*
X315303D01*
X316578Y43475D01*
X318422D01*
X318947Y44000D01*
X321900D01*
G01X276740Y53060D02*
Y58160D01*
X275665Y59235D01*
X266975D01*
X265700Y57960D01*
Y53000D01*
G01X275300Y44900D02*
Y45800D01*
X271900Y49200D01*
Y52300D01*
X271140Y53060D01*
X269260D01*
G01X279750Y78500D02*
X277582D01*
X275682Y76600D01*
X270550D01*
X270150Y77000D01*
G01X275700Y121000D02*
Y124000D01*
G01D02*
Y130500D01*
X276654Y131454D01*
G01X307298Y132697D02*
X304208D01*
X302900Y131389D01*
X296285Y124775D01*
X284425D01*
X282900Y126300D01*
Y130200D01*
X281000Y132100D01*
X277300D01*
X276654Y131454D01*
G01X278000Y141900D02*
X278100Y142000D01*
Y145400D01*
X278200Y145500D01*
G01D02*
X278700Y146000D01*
X282000D01*
G01X271200Y166300D02*
Y163900D01*
X270500Y163200D01*
G01X268000Y166300D02*
X271200D01*
G01D02*
X273100Y168200D01*
X279247D01*
X282775Y171728D01*
Y172101D01*
X282800Y172126D01*
Y174511D01*
X285614Y177325D01*
X292469D01*
X294319Y175475D01*
X295079D01*
X296235Y174319D01*
Y173003D01*
X297386Y171852D01*
X297475D01*
X302470Y166857D01*
X309071D01*
X312542Y163386D01*
X316290D01*
X317007Y164103D01*
Y164629D01*
X318194Y165816D01*
X319210D01*
X320825Y164201D01*
X321442D01*
G01X264600Y166300D02*
Y169900D01*
G01X295290Y177645D02*
X293659Y179276D01*
X284807D01*
X280925Y175394D01*
Y175336D01*
X280850Y175261D01*
Y172561D01*
X278489Y170200D01*
X275300D01*
G01D02*
X271900D01*
X271700Y170000D01*
G01X264600Y169900D02*
Y173100D01*
G01X273700Y178400D02*
X276900D01*
G01D02*
X278575Y180075D01*
Y182356D01*
X279644Y183425D01*
X289075D01*
X290600Y181900D01*
G01X266250Y182560D02*
X270379D01*
X270866Y182073D01*
X270977D01*
G01X276700Y182700D02*
X276625D01*
X275825Y181900D01*
X271212D01*
X271039Y182073D01*
X270977D01*
G01X268300Y170000D02*
Y173018D01*
X268283Y173035D01*
G01X266250Y177440D02*
X267340D01*
X268300Y178400D01*
X270300D01*
G01D02*
X271700Y177000D01*
Y174900D01*
X271701Y174899D01*
Y174800D01*
G01X273074Y186392D02*
X273060Y186406D01*
Y189374D01*
G01X276700Y186100D02*
Y189190D01*
X276910Y189400D01*
G01X266140Y191850D02*
X265700Y191410D01*
Y187800D01*
X265400Y187500D01*
G01X269700Y198000D02*
Y194600D01*
X269500Y194400D01*
G01X273791Y210500D02*
Y209922D01*
X270336Y206467D01*
G01D02*
X266300Y202431D01*
Y201000D01*
G01D02*
Y198000D01*
G01X266000Y225300D02*
Y221700D01*
X268600Y219100D01*
Y219059D01*
G01X313824Y280255D02*
Y277524D01*
X311900Y275600D01*
X311374D01*
X303199Y267425D01*
X292116D01*
X291691Y267850D01*
X289770Y269770D01*
X288465Y271075D01*
X278214D01*
X269100Y261961D01*
Y252643D01*
X267375Y250918D01*
Y245765D01*
X266000Y244390D01*
Y238300D01*
X265000Y237300D01*
Y229700D01*
X266000Y228700D01*
G01X288291Y53000D02*
X287291Y52000D01*
X285100D01*
X285091Y52009D01*
X284262D01*
G01X282200Y59000D02*
Y56262D01*
X282175Y56237D01*
Y54034D01*
X284200Y52009D01*
X284262D01*
G01X305300Y47500D02*
X303358D01*
X297858Y53000D01*
X288291D01*
G01X284700Y72000D02*
Y75200D01*
X285440Y75940D01*
X286250D01*
G01X282200Y62000D02*
X282525Y62325D01*
X293256D01*
X296709Y58872D01*
Y56740D01*
G01X279750Y75940D02*
Y73550D01*
X281300Y72000D01*
G01D02*
Y71200D01*
X282225Y70275D01*
X285984D01*
X286525Y70816D01*
Y71506D01*
X288719Y73700D01*
X303400D01*
G01X296000Y75940D02*
X286250D01*
G01X296000Y84125D02*
X292925D01*
X290500Y81700D01*
G01D02*
X289200Y83000D01*
X283000D01*
X281060Y81060D01*
X279750D01*
G01X286250D02*
X287740D01*
X290500Y78300D01*
G01D02*
X293800D01*
X295975Y80475D01*
X303900D01*
G01X286250Y78500D02*
X279750D01*
G01X295500Y99500D02*
X295000D01*
X292700Y97200D01*
X291800D01*
G01X288300Y107000D02*
Y104000D01*
G01D02*
X283405Y99105D01*
X281005D01*
G01X293200Y121000D02*
Y118000D01*
G01X291700Y107000D02*
X293500D01*
X299000Y112500D01*
G01X293200Y126500D02*
X295564D01*
X296564Y127500D01*
G01X293200Y135500D02*
X296703Y139003D01*
X298997D01*
G01X307854Y130539D02*
X303253D01*
X293714Y121000D01*
X293200D01*
G01Y129500D02*
X295100D01*
X296531Y130931D01*
Y133061D01*
G01X280400Y129225D02*
Y123300D01*
X282700Y121000D01*
G01X289800D02*
X288675Y122125D01*
X285436D01*
X284311Y121000D01*
X282700D01*
G01X293200Y132500D02*
X295025Y134325D01*
Y134772D01*
X296564Y136311D01*
G01X315132Y150931D02*
X311756D01*
X310500Y149675D01*
X286175D01*
X282500Y146000D01*
X282000D01*
G01X291700Y144000D02*
X292200Y143500D01*
X297706D01*
X299484Y145278D01*
Y146830D01*
X300435Y147781D01*
X303119D01*
X304400Y146500D01*
G01X293700Y167000D02*
X297000D01*
X299000Y165000D01*
Y163366D01*
X300276Y162090D01*
G01X281000Y162346D02*
X283246Y160100D01*
X287500D01*
G01D02*
X289000D01*
X289100Y160200D01*
X293300D01*
G01D02*
X294600D01*
X296300Y158500D01*
X301713D01*
X303261Y156952D01*
G01X281000Y152654D02*
X283246Y154900D01*
X287500D01*
G01X293300Y157800D02*
X291100D01*
X288200Y154900D01*
X287500D01*
G01X293300Y157800D02*
X294800Y156300D01*
X297820D01*
X298717Y155403D01*
G01X293700Y170500D02*
X295500D01*
X306696Y159304D01*
Y158610D01*
G01X290600Y181900D02*
X290681Y181981D01*
X294420D01*
X299175Y177226D01*
Y172558D01*
X303176Y168557D01*
X315028D01*
X315132Y168661D01*
G01X297000Y192000D02*
X296700Y192300D01*
X293000D01*
G01D02*
X290000D01*
G01X293300Y188800D02*
Y185600D01*
X293200Y185500D01*
G01D02*
X293907D01*
X297500Y181907D01*
G01X284700Y222000D02*
X288176D01*
X291201Y225025D01*
G01X284700Y225000D02*
X287602D01*
X287802Y225200D01*
G01X308700Y54000D02*
X314000D01*
G01X314800Y48625D02*
X310701D01*
X310101Y49225D01*
X309975D01*
X308700Y50500D01*
G01D02*
X306975Y52225D01*
X303357D01*
X298842Y56740D01*
X296709D01*
G01X305300Y50500D02*
Y47500D01*
G01X296709Y49260D02*
X298540D01*
X300900Y46900D01*
G01X308700Y47500D02*
X310500Y45700D01*
X317500D01*
G01X303400Y73700D02*
X306400D01*
X312400Y79700D01*
G01X319520Y92419D02*
X319275Y92664D01*
Y94236D01*
X318411Y95100D01*
X316800D01*
X312440Y90740D01*
Y82459D01*
X305921Y75940D01*
X296000D01*
G01Y84125D02*
X304525D01*
X316350Y95950D01*
X318765D01*
X322315Y92400D01*
X323120D01*
G01X309400Y82100D02*
X307775Y80475D01*
X303900D01*
G01X303610Y110800D02*
Y106390D01*
X312825Y97175D01*
X316561D01*
X317425Y98039D01*
Y98611D01*
X318289Y99475D01*
X320938D01*
X324913Y95500D01*
X330886D01*
X333200Y93186D01*
Y91800D01*
X334900Y90100D01*
X355856D01*
X361131Y84825D01*
X368175D01*
X371612Y81388D01*
X410612D01*
X419300Y72700D01*
X443200D01*
X443949Y73449D01*
Y97083D01*
X498875Y152009D01*
Y154600D01*
G01X299300Y98500D02*
X298300Y99500D01*
X295500D01*
G01X306700Y114700D02*
X301200D01*
X299000Y112500D01*
G01X298500Y130000D02*
X299504D01*
X301879Y132375D01*
X301881D01*
X305006Y135500D01*
X310485D01*
X312601Y137616D01*
X317620D01*
X319045Y136191D01*
X320112D01*
G01X296564Y127500D02*
Y128064D01*
X298500Y130000D01*
G01X317112Y136391D02*
X315636Y134915D01*
X312306D01*
X311442Y134051D01*
Y132781D01*
X309200Y130539D01*
X307854D01*
G01X296531Y133061D02*
X297470Y134000D01*
X300500D01*
X301000Y134500D01*
G01D02*
X303000Y136500D01*
X305500D01*
X308075Y139075D01*
X315298D01*
X315342Y139031D01*
G01X313392Y136191D02*
X312379D01*
X309500Y133312D01*
Y132925D01*
G01X296564Y136311D02*
X299811D01*
X301300Y137800D01*
X305597D01*
X308053Y140256D01*
X315850D01*
X317275Y138831D01*
X319112D01*
G01X296800Y151500D02*
X298000D01*
X300382Y153882D01*
X304617D01*
X306345Y152155D01*
X307674D01*
X309217Y153698D01*
X309220D01*
G01X315782Y146881D02*
X314226Y145325D01*
X306231D01*
X305281Y144375D01*
X302890D01*
X301109Y146156D01*
G01X298997Y139003D02*
X305597D01*
X309928Y143334D01*
X313686D01*
X315014Y142006D01*
X316300D01*
X317655Y143361D01*
X318702D01*
G01X304400Y146500D02*
X311631D01*
X313392Y148261D01*
G01X304300Y141400D02*
X307084Y144184D01*
X314039D01*
X314992Y143231D01*
X315792D01*
G01X318702Y161091D02*
X317655D01*
X316300Y159736D01*
X315014D01*
X314034Y160716D01*
X310910D01*
X309000Y158806D01*
G01X300276Y162090D02*
X301130D01*
X306085Y157135D01*
X307308D01*
X308979Y158806D01*
X309000D01*
G01X309220Y153698D02*
X309250Y153728D01*
Y153740D01*
X310806Y155296D01*
X313783D01*
X315300Y153779D01*
Y152496D01*
X316960Y150836D01*
X318867D01*
X319282Y151251D01*
G01X315342Y156761D02*
X314807D01*
X314572Y156996D01*
X310100D01*
X309389Y156285D01*
X303928D01*
X303261Y156952D01*
G01X315792Y160961D02*
X314992D01*
X314387Y161566D01*
X309652D01*
X306696Y158610D01*
G01X298717Y155403D02*
X299388Y154732D01*
X304262D01*
X304803Y155273D01*
X309580D01*
X310453Y156146D01*
X314218D01*
X314675Y155690D01*
X314830Y155536D01*
X315850D01*
X316865Y156551D01*
X319112D01*
G01X315782Y164611D02*
X312520D01*
X309424Y167707D01*
X302823D01*
X298325Y172205D01*
Y174610D01*
X295290Y177645D01*
G01X305091Y173888D02*
Y173891D01*
X306536Y175336D01*
X314454D01*
X315529Y176411D01*
X317352D01*
G01X302591Y173906D02*
Y174009D01*
X302000Y174600D01*
Y176200D01*
X303000Y177200D01*
G01X321922Y176451D02*
X319045D01*
X317860Y177636D01*
X316470D01*
X316300Y177466D01*
X315314D01*
X314034Y176186D01*
X305914D01*
X304900Y177200D01*
X303000D01*
G01X309200Y180500D02*
X310085Y179615D01*
X313794D01*
X314095Y179916D01*
X316300D01*
X317405Y178811D01*
X318702D01*
G01X320112Y171651D02*
X318645D01*
X317620Y170626D01*
X316103D01*
X315993Y170736D01*
X314244D01*
X313765Y170257D01*
X303882D01*
X300875Y173264D01*
Y180359D01*
X300000Y181234D01*
Y185500D01*
X298900Y186600D01*
Y190100D01*
X297000Y192000D01*
G01X307200Y182000D02*
Y182664D01*
X309077Y184542D01*
X312457D01*
X312751Y184836D01*
X315255D01*
X315370Y184721D01*
X317332D01*
G01X304400Y182000D02*
Y181621D01*
X307330Y178691D01*
X315792D01*
G01X313392Y177311D02*
X306222D01*
X301745Y181788D01*
G01X315342Y174491D02*
X314812D01*
X314807Y174486D01*
X309190D01*
X306612Y171908D01*
Y171882D01*
G01X319112Y174281D02*
X316865D01*
X315850Y173266D01*
X313434D01*
X313150Y173550D01*
X312075D01*
X312072Y173553D01*
X310848D01*
X310845Y173550D01*
X310350D01*
X309112Y172312D01*
Y171960D01*
G01X319282Y168971D02*
X316555D01*
X315640Y169886D01*
X314624D01*
X314145Y169407D01*
X303529D01*
X300025Y172911D01*
Y179382D01*
X297500Y181907D01*
G01X309900Y224900D02*
X303500Y231300D01*
X299961D01*
X299175Y232086D01*
Y244381D01*
X300534Y245740D01*
X302650D01*
G01X307300Y224900D02*
X302700Y229500D01*
X299003D01*
X297225Y231278D01*
Y247483D01*
X298042Y248300D01*
X302650D01*
G01X347835Y24392D02*
Y34835D01*
X348894Y35894D01*
Y44106D01*
X345000Y48000D01*
X335500D01*
X334150Y46650D01*
X330544D01*
X329402Y47792D01*
Y49231D01*
X328208Y50425D01*
X324575D01*
X321000Y54000D01*
X314000D01*
G01X320400Y48600D02*
X317500Y45700D01*
G01X317641Y90956D02*
Y87541D01*
X316450Y86350D01*
Y80850D01*
X316850Y80450D01*
X318500D01*
X318950Y80900D01*
Y85600D01*
X319350Y86000D01*
X320350D01*
X320750Y85600D01*
Y80900D01*
X321200Y80450D01*
X322100D01*
X322550Y80900D01*
Y84300D01*
X322950Y84700D01*
X323950D01*
X324350Y84300D01*
Y80900D01*
X325315Y79935D01*
X338942D01*
X339963Y78914D01*
X348210D01*
X349662Y77462D01*
X351648D01*
X353100Y78914D01*
X354986D01*
X357325Y76575D01*
X364925D01*
X368500Y73000D01*
X382050D01*
X385000Y70050D01*
X397562D01*
X403162Y64450D01*
X413200D01*
G01X326162Y91438D02*
X325000Y90276D01*
Y87500D01*
X325351Y87149D01*
X326162D01*
X328811Y84500D01*
X340200D01*
X340800Y83900D01*
G01X331600Y82200D02*
X326600D01*
X326000Y82800D01*
Y84984D01*
X323700Y87284D01*
Y90600D01*
X324595Y91495D01*
Y93905D01*
X320500Y98000D01*
X318900D01*
G01X502800Y139000D02*
X500973D01*
X456133Y94160D01*
X456132D01*
X453849Y91877D01*
Y68593D01*
X443656Y58400D01*
X441462D01*
X441012Y58850D01*
Y60050D01*
X440562Y60500D01*
X438762D01*
X438312Y60050D01*
Y58850D01*
X437862Y58400D01*
X436062D01*
X435612Y58850D01*
Y61050D01*
X435162Y61500D01*
X433362D01*
X432912Y61050D01*
Y58850D01*
X432462Y58400D01*
X430662D01*
X430212Y58850D01*
Y61050D01*
X429762Y61500D01*
X427962D01*
X427512Y61050D01*
Y58850D01*
X427062Y58400D01*
X425262D01*
X424812Y58850D01*
Y61050D01*
X424362Y61500D01*
X422562D01*
X422112Y61050D01*
Y58850D01*
X421662Y58400D01*
X419862D01*
X419412Y58850D01*
Y61050D01*
X418962Y61500D01*
X417162D01*
X416712Y61050D01*
Y58850D01*
X416262Y58400D01*
X414462D01*
X414012Y58850D01*
Y61050D01*
X413562Y61500D01*
X411762D01*
X411312Y61050D01*
Y58850D01*
X410862Y58400D01*
X406878D01*
X396878Y68400D01*
X381500D01*
X379400Y70500D01*
X375500D01*
X373400Y68400D01*
X370600D01*
X364075Y74925D01*
X357872D01*
X357122Y74175D01*
X350615D01*
X347526Y77264D01*
X339279D01*
X338258Y78285D01*
X315715D01*
X314800Y79200D01*
Y88500D01*
G01X317600Y93625D02*
X314800Y90825D01*
Y88500D01*
G01X324822Y136841D02*
Y134626D01*
X325746Y133702D01*
G01X326322Y129021D02*
Y128253D01*
X325418Y127349D01*
G01X323900Y129900D02*
X323973D01*
X325854Y131781D01*
X326322D01*
G01X321442Y143721D02*
X323300Y145579D01*
Y147046D01*
G01X322192Y149151D02*
X322360Y149319D01*
X325200D01*
G01X321442Y161451D02*
X320089Y162804D01*
X319704D01*
G01X324822Y152481D02*
X323404Y153900D01*
X323000D01*
G01X322192Y166871D02*
X322671Y166392D01*
X324000D01*
X324008Y166384D01*
X324029D01*
G01X324822Y155241D02*
X324823D01*
X326095Y153969D01*
X326234D01*
G01X310579Y182800D02*
Y181890D01*
X312004Y180465D01*
X313441D01*
X314092Y181116D01*
X316290D01*
X317485Y182311D01*
X318702D01*
G01X324822Y170881D02*
X327600Y173659D01*
Y174174D01*
G01X326322Y178701D02*
X324862D01*
X323500Y180063D01*
G01X324822Y183761D02*
X326291Y182292D01*
X326408D01*
G01X322192Y184601D02*
Y183842D01*
X323121Y182913D01*
G01X318700Y250400D02*
Y250900D01*
X315500Y254100D01*
G01X311400Y269200D02*
X320700D01*
X329323Y260577D01*
X389964D01*
X403663Y246878D01*
Y245956D01*
X409844Y239775D01*
X434806D01*
X438000Y242969D01*
Y246018D01*
X441600Y249618D01*
Y251400D01*
G01X333600Y63800D02*
Y67025D01*
X336316Y69741D01*
X341275D01*
X342591Y68425D01*
X348091D01*
X354091Y62425D01*
X382551D01*
X395424Y49552D01*
X412152D01*
X419600Y42104D01*
Y27151D01*
X424543Y22208D01*
G01X502800Y148000D02*
X501868D01*
X448899Y95031D01*
Y70645D01*
X446004Y67750D01*
X416750D01*
X408062Y76438D01*
X369496D01*
X366059Y79875D01*
X358693D01*
X356354Y82214D01*
X353233D01*
X350222Y85225D01*
X344178D01*
X342853Y83900D01*
X340800D01*
G01X502800Y145000D02*
X501626D01*
X450549Y93923D01*
Y69961D01*
X446688Y66100D01*
X416000D01*
X414600Y67500D01*
X412000D01*
X410600Y66100D01*
X408950D01*
X408500Y66550D01*
Y69316D01*
X409550Y70366D01*
Y72616D01*
X407166Y75000D01*
X405500D01*
X404500Y74000D01*
Y73000D01*
X406244Y71256D01*
Y66550D01*
X405794Y66100D01*
X403846D01*
X402393Y67553D01*
Y68189D01*
X403424Y69220D01*
Y69856D01*
X402150Y71130D01*
X401514D01*
X400483Y70099D01*
X399847D01*
X398573Y71373D01*
Y72009D01*
X399250Y72686D01*
Y73322D01*
X398201Y74372D01*
X397566D01*
X394894Y71700D01*
X392800D01*
X389712Y74788D01*
X368812D01*
X365375Y78225D01*
X358009D01*
X355670Y80564D01*
X352416D01*
X351452Y79600D01*
X349858D01*
X348894Y80564D01*
X340736D01*
X339100Y82200D01*
X331600D01*
G01X328000Y92700D02*
Y91528D01*
X327825Y91353D01*
Y86689D01*
X328689Y85825D01*
X331225D01*
X332100Y86700D01*
X351081D01*
X353917Y83864D01*
X357038D01*
X359377Y81525D01*
X366743D01*
X370180Y78088D01*
X408912D01*
X417600Y69400D01*
X445320D01*
X447249Y71329D01*
Y95715D01*
X502614Y151080D01*
X513720D01*
X517975Y146825D01*
X520200D01*
G01X354141Y87158D02*
X352899Y88400D01*
X333900D01*
X330900Y91400D01*
Y93400D01*
G01X340112Y121101D02*
Y121099D01*
X338768Y119755D01*
G01X340112Y118101D02*
Y118099D01*
X338768Y116755D01*
G01X335322Y129021D02*
X335320D01*
X333977Y127678D01*
G01X338322Y129021D02*
X336979Y127678D01*
X336978D01*
X336900Y127600D01*
G01X335322Y131781D02*
Y135159D01*
X335303Y135178D01*
G01X338322Y131781D02*
Y135622D01*
X338329Y135629D01*
Y135665D01*
G01X329322Y131781D02*
X329201D01*
X327854Y130434D01*
G01X335322Y147421D02*
Y147321D01*
X333951Y145950D01*
X333750D01*
G01X330163Y142008D02*
Y142502D01*
X332322Y144661D01*
G01X338322D02*
X339830Y146169D01*
Y148670D01*
X337600Y150900D01*
X335450D01*
G01X333822Y152481D02*
X333681D01*
X332000Y150800D01*
G01X326322Y147421D02*
X326379D01*
X327692Y146108D01*
X327696D01*
G01X330822Y139601D02*
X330820Y139599D01*
X330792D01*
X329421Y138228D01*
G01X327822Y152481D02*
X329503Y150800D01*
X329800D01*
G01X329322Y147421D02*
X327637Y149106D01*
X327390D01*
G01X339491Y143163D02*
X339581D01*
X341079Y144661D01*
X341322D01*
G01X338322Y147421D02*
X337084Y146183D01*
X336973D01*
X336920Y146130D01*
G01X336822Y136841D02*
X337134D01*
X338470Y138177D01*
G01X338320Y141300D02*
X338420Y141200D01*
X338460D01*
X339822Y139838D01*
Y139601D01*
G01X336822D02*
Y139528D01*
X335514Y138220D01*
G01X333822Y136841D02*
Y136911D01*
X332478Y138255D01*
G01X327822Y136841D02*
Y136934D01*
X326322Y138434D01*
G01X332322Y163061D02*
Y163178D01*
X331000Y164500D01*
G01X332322Y160301D02*
X332055D01*
X330300Y158546D01*
G01X327822Y155241D02*
X329161Y153902D01*
Y153830D01*
G01X338322Y163061D02*
X336949Y164434D01*
X336800D01*
G01X338322Y160301D02*
X338199D01*
X336900Y161600D01*
G01X336822Y152481D02*
Y152523D01*
X335499Y153846D01*
G01X329322Y163061D02*
X330683Y161700D01*
X330900D01*
G01X333822Y155241D02*
X333700Y155363D01*
Y157600D01*
X333000Y158300D01*
G01X341322Y163061D02*
X339905Y164478D01*
X339747D01*
G01X341322Y160301D02*
X339784Y161839D01*
Y161847D01*
G01X329322Y160301D02*
X329099D01*
X327900Y161500D01*
X327800D01*
G01X338322Y175941D02*
Y176016D01*
X336915Y177423D01*
G01X327822Y170881D02*
Y171914D01*
X330027Y174119D01*
G01X332322Y178701D02*
Y179122D01*
X332500Y179300D01*
Y180900D01*
G01X336822Y170881D02*
Y173924D01*
X337000Y174102D01*
G01X330822Y168121D02*
X330952D01*
X332353Y169522D01*
G01X329322Y175941D02*
X329085D01*
X327888Y177138D01*
X327811D01*
X327708Y177241D01*
G01X330280Y180900D02*
Y179903D01*
X329322Y178945D01*
Y178701D01*
G01X327822Y168121D02*
X327824Y168119D01*
X328134D01*
X329478Y169463D01*
X329442D01*
G01X338322Y178701D02*
Y180086D01*
X337863Y180545D01*
G01X332322Y175941D02*
X332282D01*
X330821Y177402D01*
G01X333822Y170881D02*
X334700Y171759D01*
Y174100D01*
G01X327822Y183761D02*
X329313Y185252D01*
Y188000D01*
G01X351772Y24392D02*
Y36060D01*
X353412Y37700D01*
X356971D01*
G01X362626Y47068D02*
X359958Y44400D01*
Y37458D01*
X355709Y33209D01*
Y24392D01*
G01X354141Y87158D02*
X355550Y85750D01*
X357872D01*
X360447Y83175D01*
X367427D01*
X370864Y79738D01*
X409812D01*
X418500Y71050D01*
X444599D01*
X445599Y72050D01*
Y96399D01*
X501930Y152730D01*
X520200D01*
G01X345172Y113601D02*
X344610D01*
X343570Y112561D01*
G01X345172Y116601D02*
X341200Y112629D01*
Y112569D01*
G01X342533Y133822D02*
X342758D01*
X343080Y133500D01*
X344980Y131601D01*
X345172D01*
G01Y128601D02*
X343274D01*
X343146Y128473D01*
G01X352992Y127101D02*
X350032Y124141D01*
X349149D01*
G01X347932Y131601D02*
X346495Y130164D01*
Y130000D01*
G01X345822Y136841D02*
Y135298D01*
X347641Y133479D01*
G01X342822Y136841D02*
X342659D01*
X341276Y138224D01*
X341342D01*
G01X350550Y153280D02*
X351643D01*
X353742Y151181D01*
G01X344500Y141700D02*
Y140923D01*
X345822Y139601D01*
G01X347322Y144661D02*
Y144022D01*
X346300Y143000D01*
G01X353742Y141731D02*
Y142734D01*
X350476Y146000D01*
X349046D01*
X348974Y146072D01*
X348743D01*
G01X347322Y147421D02*
Y148248D01*
X346450Y149120D01*
G01X350082Y144661D02*
X348921Y143500D01*
X348849D01*
X348675Y143326D01*
G01X344322Y147421D02*
X344622D01*
X346000Y146043D01*
G01X342822Y155241D02*
X341400Y156663D01*
Y156700D01*
G01X353742Y154331D02*
X355073Y153000D01*
X355300D01*
X355400Y152900D01*
G01X350082Y163061D02*
X350361D01*
X351600Y164300D01*
G01X350082Y160301D02*
Y160318D01*
X348700Y161700D01*
G01X342822Y152481D02*
X341390Y153913D01*
Y153991D01*
G01X345822Y155241D02*
X345539D01*
X344090Y156690D01*
G01X345822Y152481D02*
X344504Y153800D01*
X344300D01*
G01X350700Y155600D02*
X350341Y155241D01*
X348822D01*
G01X347322Y160301D02*
X347299D01*
X345900Y161700D01*
G01X353742Y160631D02*
X353369D01*
X352000Y162000D01*
G01X347322Y163061D02*
X348432Y164171D01*
Y164844D01*
G01X348822Y170881D02*
X350103Y169600D01*
X351600D01*
G01X353742Y170081D02*
X353161Y169500D01*
X351700D01*
X351600Y169600D01*
G01X348822Y168121D02*
X347500Y169443D01*
Y169500D01*
G01X345822Y170881D02*
X347200Y172259D01*
Y174300D01*
G01X342600Y277900D02*
X344025Y279325D01*
X417675D01*
X423000Y274000D01*
G01X367520Y24392D02*
Y35060D01*
X365772Y36808D01*
Y43030D01*
X366325Y43583D01*
Y46970D01*
X366484Y47129D01*
G01X371457Y24392D02*
Y35060D01*
X369245Y37272D01*
Y39294D01*
X367497Y41042D01*
G01X364600Y44298D02*
X363998D01*
X360908Y41208D01*
Y36308D01*
X359646Y35046D01*
Y24392D01*
G01X363604Y41042D02*
X361858Y39296D01*
Y35707D01*
X363583Y33982D01*
Y24392D01*
G01X359000Y50300D02*
Y39729D01*
X356971Y37700D01*
G01X368000Y50300D02*
Y48195D01*
X368309Y47886D01*
Y41854D01*
X367497Y41042D01*
G01X362000Y50300D02*
Y47694D01*
X362626Y47068D01*
G01X365000Y50300D02*
Y48613D01*
X366484Y47129D01*
G01X367692Y181561D02*
X364600Y184653D01*
Y186138D01*
G01X367692Y184561D02*
X366153Y186100D01*
Y187382D01*
X364792Y188743D01*
G01X385300Y47000D02*
X386500Y45800D01*
Y35200D01*
X387000Y34700D01*
Y26547D01*
X387205Y26342D01*
G01X382500Y53800D02*
Y49800D01*
X385300Y47000D01*
G01X375782Y151181D02*
X374200Y149599D01*
Y149494D01*
G01X397100Y181000D02*
X397000Y180900D01*
X394751D01*
X393912Y180061D01*
G01X502800Y142000D02*
X501384D01*
X452199Y92815D01*
Y69277D01*
X447372Y64450D01*
X413200D01*
G01X410492Y122601D02*
X411293Y121800D01*
X413100D01*
G01X410492Y125601D02*
X411763D01*
X412462Y126300D01*
G01X412200Y192600D02*
X411400D01*
X410861Y192061D01*
X409552D01*
G01X412100Y190400D02*
X412000Y190300D01*
X411600D01*
X410361Y189061D01*
X409552D01*
G01X466100Y23900D02*
X460300D01*
X453100Y16700D01*
X445100D01*
X440618Y12218D01*
X435315D01*
X432200Y9103D01*
G01X452500Y26125D02*
X450725D01*
X444575Y19975D01*
X441534D01*
X433587Y12028D01*
X431725D01*
X428800Y9103D01*
G01X425400D02*
X429297Y13000D01*
X433215D01*
X442448Y22233D01*
X443644D01*
G01X422000Y9103D02*
X426847Y13950D01*
X430031D01*
X434000Y17919D01*
Y18500D01*
G01X520200Y117300D02*
X505464D01*
X494714Y106550D01*
X483799D01*
X464649Y87400D01*
Y64117D01*
X440441Y39909D01*
X433170D01*
X428011Y34750D01*
Y31368D01*
X424543Y27900D01*
G01X520200Y109425D02*
X504591D01*
X496766Y101600D01*
X485851D01*
X469599Y85348D01*
Y58899D01*
X464516Y53816D01*
Y41284D01*
X461882Y38650D01*
X446431D01*
X436856Y29075D01*
X434975D01*
X431225Y25325D01*
X426676D01*
X426405Y25054D01*
G01X423500Y16885D02*
Y18500D01*
X428675Y23675D01*
X436385D01*
X441390Y28680D01*
G01X520200Y101550D02*
X515197D01*
X514922Y101275D01*
X514775D01*
X506565Y93065D01*
Y82435D01*
X508412Y80588D01*
Y60691D01*
X507228Y59507D01*
X498771D01*
X489995Y50731D01*
X473431D01*
X470200Y47500D01*
Y39000D01*
X464600Y33400D01*
X452514D01*
X445614Y26500D01*
X441968D01*
X437193Y21725D01*
X433225D01*
X430325Y18825D01*
X428825D01*
X427000Y17000D01*
G01X520200Y115330D02*
X505828D01*
X495398Y104900D01*
X484483D01*
X466299Y86716D01*
Y63433D01*
X441125Y38259D01*
X434101D01*
X430000Y34158D01*
G01X424536Y34800D02*
Y38636D01*
X428875Y42975D01*
G01X520200Y127140D02*
X509640D01*
X492400Y109900D01*
X482481D01*
X461349Y88768D01*
Y65485D01*
X440597Y44733D01*
X430633D01*
X428875Y42975D01*
G01X439892Y42508D02*
X433435D01*
X426361Y35434D01*
Y33062D01*
X424599Y31300D01*
G01X431990Y49271D02*
X423119Y40400D01*
X423036D01*
X422986Y40350D01*
G01X520200Y129110D02*
X508868D01*
X491308Y111550D01*
X481797D01*
X459699Y89452D01*
Y66169D01*
X442801Y49271D01*
X431990D01*
G01X431192Y102711D02*
X432500Y101403D01*
Y97200D01*
X433200Y96500D01*
Y84500D01*
X431900Y83200D01*
G01D02*
Y79500D01*
G01D02*
Y75900D01*
X432300Y75500D01*
G01X428500Y79500D02*
Y76900D01*
X427100Y75500D01*
G01X427992Y102711D02*
X431300Y99403D01*
Y86300D01*
X428500Y83500D01*
Y79500D01*
G01X422825Y74925D02*
X426525D01*
X427100Y75500D01*
G01X429500Y93800D02*
X429800Y93500D01*
Y86800D01*
X425200Y82200D01*
Y81500D01*
G01D02*
X423200Y79500D01*
Y78500D01*
G01X418600Y85000D02*
Y81500D01*
G01Y85000D02*
X425100Y91500D01*
Y100213D01*
X426417Y101530D01*
Y102813D01*
X425137Y104093D01*
Y105453D01*
X424967Y105623D01*
Y106639D01*
X425017Y106689D01*
Y110123D01*
X424937Y110203D01*
Y110439D01*
X423000Y112376D01*
X422804D01*
X420567Y114613D01*
Y115871D01*
X422147Y117451D01*
Y121900D01*
X420902Y123145D01*
Y124901D01*
G01X418600Y81500D02*
Y79700D01*
X419800Y78500D01*
G01X428500Y224000D02*
X429092Y223408D01*
Y207051D01*
X427992Y205951D01*
G01X434392Y199551D02*
Y200700D01*
X432967Y202125D01*
Y208467D01*
X433796Y209296D01*
Y217296D01*
X435500Y219000D01*
G01X433500Y224400D02*
Y221900D01*
X430100Y218500D01*
Y207043D01*
X431192Y205951D01*
G01X429800Y228000D02*
Y229659D01*
X427396Y232063D01*
G01X428500Y224000D02*
Y226700D01*
X429800Y228000D01*
G01X432596Y232063D02*
Y228604D01*
X433200Y228000D01*
G01X433500Y224400D02*
Y227700D01*
X433200Y228000D01*
G01X426600Y244450D02*
X426700Y244550D01*
Y244773D01*
X432442Y250515D01*
X436981D01*
X437405Y250939D01*
Y258061D01*
X434966Y260500D01*
X426300D01*
G01X427820Y257060D02*
X427440D01*
X426300Y258200D01*
Y260500D01*
G01X430000Y244450D02*
X430200Y244650D01*
Y245515D01*
X433250Y248565D01*
X437789D01*
X439355Y250131D01*
Y258602D01*
X441378Y260625D01*
X441501D01*
X443060Y262184D01*
Y263250D01*
G01X435180Y254500D02*
X433669D01*
X427769Y248600D01*
X425500D01*
X423600Y246700D01*
G01X588600Y124700D02*
X565785Y101885D01*
X533785D01*
X529325Y97425D01*
X526649D01*
X526050Y96826D01*
Y96066D01*
X525084Y95100D01*
X519021D01*
X513350Y89430D01*
Y84774D01*
X515475Y82649D01*
Y58517D01*
X510015Y53057D01*
X501884D01*
X470301Y21474D01*
X460339D01*
X453915Y15050D01*
X447282D01*
X447257Y15025D01*
X446825D01*
X442281Y10481D01*
X437149D01*
X437061Y10393D01*
G01X518902Y88987D02*
X518888D01*
X517125Y87224D01*
Y57833D01*
X510699Y51407D01*
X502568D01*
X470985Y19824D01*
X461023D01*
X454599Y13400D01*
X447700D01*
X443131Y8831D01*
X440431D01*
X438525Y6925D01*
X438300D01*
G01X522280Y89810D02*
X520727Y88257D01*
Y88230D01*
X518775Y86278D01*
Y57149D01*
X511383Y49757D01*
X503252D01*
X471669Y18174D01*
X461707D01*
X455283Y11750D01*
X448650D01*
X446800Y9900D01*
G01X527000Y69500D02*
X522675Y65175D01*
Y57149D01*
X522676Y57148D01*
Y55034D01*
X513698Y46056D01*
X505067D01*
X473285Y14274D01*
X463423D01*
X456874Y7725D01*
X448024D01*
X446200Y5901D01*
Y5900D01*
G01X443644Y22233D02*
X445449D01*
X452816Y29600D01*
X472966D01*
X499973Y56607D01*
X508430D01*
X511313Y59490D01*
Y61892D01*
X511312Y61893D01*
Y79386D01*
X511313Y79387D01*
Y81789D01*
X509465Y83637D01*
Y91863D01*
X515977Y98375D01*
X516124D01*
X516399Y98650D01*
X523752D01*
X539300Y114198D01*
Y165700D01*
X533455Y171545D01*
Y177800D01*
G01X520200Y107455D02*
X504955D01*
X497450Y99950D01*
X486535D01*
X471249Y84664D01*
Y58149D01*
X466300Y53200D01*
Y40734D01*
X462566Y37000D01*
X447115D01*
X437540Y27425D01*
X437365D01*
X436240Y26300D01*
G01X531490Y177800D02*
Y170510D01*
X538350Y163650D01*
Y114592D01*
X523358Y99600D01*
X516005D01*
X515730Y99325D01*
X515583D01*
X508515Y92257D01*
Y83243D01*
X510363Y81395D01*
Y79781D01*
X510362Y79780D01*
Y61499D01*
X510363Y61498D01*
Y59884D01*
X508036Y57557D01*
X499579D01*
X473472Y31450D01*
X453322D01*
X446422Y24550D01*
X442776D01*
X438001Y19775D01*
X435275D01*
X434000Y18500D01*
G01X520200Y125175D02*
X510675D01*
X493700Y108200D01*
X483115D01*
X462999Y88084D01*
Y64801D01*
X440706Y42508D01*
X439892D01*
G01X509200Y99800D02*
X507700Y98300D01*
X487219D01*
X472899Y83980D01*
Y57299D01*
X468200Y52600D01*
Y40300D01*
X463250Y35350D01*
X448060D01*
X441390Y28680D01*
G01X436100Y30900D02*
Y31468D01*
X440666Y36034D01*
G01X520200Y113360D02*
X506192D01*
X496082Y103250D01*
X485167D01*
X467949Y86032D01*
Y62749D01*
X441234Y36034D01*
X440666D01*
G01X440700Y87000D02*
Y79500D01*
G01X434392Y109111D02*
X435867Y107636D01*
Y104880D01*
X439139Y101608D01*
X440341Y100404D01*
X440700Y100045D01*
Y87000D01*
G01Y79500D02*
Y76400D01*
X441600Y75500D01*
G01X437300Y79500D02*
Y76400D01*
X436400Y75500D01*
G01X437300Y79500D02*
Y83100D01*
G01D02*
Y102243D01*
X434392Y105151D01*
Y105911D01*
G01X440400Y224000D02*
Y211199D01*
X435867Y206666D01*
Y201276D01*
X437592Y199551D01*
G01X440400Y224000D02*
Y227200D01*
X441200Y228000D01*
G01X442096Y232063D02*
Y228896D01*
X441200Y228000D01*
G01X437800D02*
Y231159D01*
X436896Y232063D01*
G01X435500Y219000D02*
X437800Y221300D01*
Y228000D01*
G01X442500Y258600D02*
X441600Y257700D01*
Y254800D01*
G01X448000D02*
X444600D01*
G01X441600D02*
X444600D01*
G01X450500Y262820D02*
Y259495D01*
X449175Y258170D01*
Y256656D01*
X449515Y256315D01*
X448000Y254800D01*
G01X436700Y278000D02*
X438449Y276251D01*
X441585D01*
X443018Y274818D01*
Y273782D01*
X440500Y271264D01*
Y269750D01*
G01D02*
Y267100D01*
X441100Y266500D01*
G01D02*
X456995D01*
X457000Y266505D01*
X457029D01*
G01X440500Y263250D02*
Y265900D01*
X441100Y266500D01*
G01X440600Y274300D02*
X437940Y271640D01*
Y269750D01*
G01X439400Y281600D02*
X439500D01*
X439600Y281700D01*
X443000D01*
G01D02*
X446000D01*
G01X507677Y278766D02*
Y281823D01*
X504174Y285326D01*
X448326D01*
X446000Y283000D01*
Y281700D01*
G01X433700Y278000D02*
X436700D01*
G01X521500Y70700D02*
X520725Y69925D01*
Y56341D01*
X512191Y47807D01*
X504060D01*
X472477Y16224D01*
X462515D01*
X456091Y9800D01*
X450200D01*
G01X449600Y5900D02*
X457100D01*
X463249Y12049D01*
X465000D01*
G01X452500Y26125D02*
X470835D01*
X500367Y55657D01*
X508937D01*
X512875Y59595D01*
Y81571D01*
X510750Y83696D01*
Y90509D01*
X517941Y97700D01*
X524146D01*
X540250Y113804D01*
Y168250D01*
X535425Y173075D01*
Y177800D01*
G01X504134Y246430D02*
Y241134D01*
X500800Y237800D01*
X468200D01*
X461500Y244500D01*
G01X462500Y251800D02*
X461500Y250800D01*
Y244500D01*
G01X462500Y255200D02*
Y264000D01*
X469865Y271365D01*
X474535D01*
X479000Y266900D01*
Y265900D01*
G01X457300Y271400D02*
X460300D01*
X461000Y270700D01*
G01X457300Y271400D02*
X456900D01*
X455680Y270180D01*
X453060D01*
G01X461000Y267300D02*
X460200Y266500D01*
X457034D01*
X457029Y266505D01*
G01X456000Y281700D02*
X452000D01*
G01D02*
X449000D01*
G01X502953Y278766D02*
Y281854D01*
X500431Y284376D01*
X458676D01*
X456000Y281700D01*
G01X526750Y57940D02*
Y57057D01*
X514700Y45007D01*
X506069D01*
X473886Y12824D01*
X465775D01*
X465000Y12049D01*
G01X466100Y23900D02*
X470393D01*
X501200Y54707D01*
X509331D01*
X513825Y59201D01*
Y81965D01*
X511700Y84090D01*
Y90114D01*
X518336Y96750D01*
X524540D01*
X541200Y113410D01*
Y170800D01*
X537395Y174605D01*
Y177800D01*
G01X501772Y246430D02*
Y242222D01*
X499633Y240083D01*
X469417D01*
X465000Y244500D01*
Y248000D01*
G01X465500Y251800D02*
Y248500D01*
X465000Y248000D01*
G01X465500Y255200D02*
Y264242D01*
X470673Y269415D01*
X473727D01*
X475500Y267642D01*
Y265900D01*
G01X509200Y103200D02*
X513700D01*
X514000Y103500D01*
G01X520200Y136985D02*
X520180Y136965D01*
X517236D01*
X515803Y135532D01*
X510132D01*
X510000Y135400D01*
G01X506200Y135000D02*
X509302D01*
X509702Y135400D01*
X510000D01*
G01X506200Y132000D02*
X513458D01*
X513479Y132021D01*
G01X506200Y139000D02*
X506251Y138949D01*
X513794D01*
X513800Y138955D01*
G01X520200Y140920D02*
X516442D01*
X515362Y142000D01*
X509900D01*
G01D02*
X506200D01*
G01Y145000D02*
X506700Y145500D01*
X513500D01*
G01X520200Y144860D02*
X517287D01*
X513292Y148855D01*
X509900D01*
G01X506200Y148000D02*
X507055Y148855D01*
X509900D01*
G01X520200Y158640D02*
X511560D01*
X506475Y163725D01*
Y184425D01*
X505475Y185425D01*
X500060D01*
X498875Y184240D01*
Y154600D01*
G01X514000Y205200D02*
X506000D01*
X502553Y208647D01*
Y233553D01*
X506496Y237496D01*
Y246430D01*
G01D02*
Y251005D01*
X505675Y251826D01*
Y265231D01*
X507040Y266596D01*
Y271956D01*
X506496Y272500D01*
G01X526500Y74800D02*
X523800Y72100D01*
X522900D01*
X521500Y70700D01*
G01X526750Y60500D02*
X525684D01*
X524125Y62059D01*
Y64061D01*
X526064Y66000D01*
X530500D01*
X532000Y67500D01*
G01X527550Y94200D02*
Y92540D01*
X526710Y91700D01*
X517956D01*
X515502Y89247D01*
Y88998D01*
G01X525500Y83500D02*
Y84199D01*
X529551Y88250D01*
X529915D01*
X531490Y89825D01*
Y94200D01*
G01X523000Y74800D02*
X523100D01*
X526500Y78200D01*
G01D02*
Y81000D01*
X525500Y82000D01*
Y83500D01*
G01X520200Y101550D02*
X522550D01*
X536400Y115400D01*
Y119500D01*
G01X520200Y105490D02*
X522361D01*
X533000Y116129D01*
Y119500D01*
G01X520200Y103520D02*
X514020D01*
X514000Y103500D01*
G01X522400Y184500D02*
Y176389D01*
X531000Y167789D01*
Y118000D01*
X524395Y111395D01*
X520200D01*
G01Y135015D02*
X518044D01*
X515050Y132021D01*
X513479D01*
G01X520200Y138955D02*
X513800D01*
G01X520200Y142890D02*
X516923D01*
X514313Y145500D01*
X513500D01*
G01X522500Y201800D02*
Y198500D01*
X523000Y198000D01*
G01D02*
Y194100D01*
X522500Y193600D01*
G01X513500D02*
X515300D01*
X520500Y188400D01*
G01D02*
X522400Y186500D01*
Y184500D01*
G01X518500Y201800D02*
Y198500D01*
X518000Y198000D01*
G01D02*
Y194100D01*
X518500Y193600D01*
G01Y205200D02*
X514000D01*
G01X539567Y38966D02*
Y16467D01*
X538300Y15200D01*
G01X539800Y75500D02*
X539700D01*
X536500Y72300D01*
G01D02*
Y72000D01*
X532000Y67500D01*
G01X537300Y65036D02*
Y70000D01*
X539800Y72500D01*
G01X533250Y63060D02*
X535740D01*
X537500Y61300D01*
G01X533250Y60500D02*
X536700D01*
X537500Y61300D01*
G01D02*
Y64836D01*
X537300Y65036D01*
G01X530000Y72300D02*
X533500D01*
G01X530000D02*
X529800D01*
X527000Y69500D01*
G01X528985Y89975D02*
Y90015D01*
X529520Y90550D01*
Y94200D01*
G01X533500Y75700D02*
X532000Y77200D01*
Y83000D01*
X532986Y83986D01*
Y85675D01*
G01X533455Y94200D02*
Y92044D01*
X534992Y90507D01*
Y88593D01*
X532986Y86587D01*
Y85675D01*
G01X535425Y94200D02*
Y91614D01*
X535942Y91097D01*
Y87912D01*
X535370Y87340D01*
Y81670D01*
X534800Y81100D01*
G01D02*
Y80200D01*
X536500Y78500D01*
Y75700D01*
G01X534750Y183600D02*
X534850Y183500D01*
Y183150D01*
X536975Y181025D01*
X538296D01*
X539360Y179961D01*
Y177800D01*
G01X547235Y94200D02*
Y92044D01*
X548074Y91205D01*
Y87210D01*
X544000Y83136D01*
Y81000D01*
G01X549205Y94200D02*
Y91595D01*
X550000Y90800D01*
Y85500D01*
G01X557080Y177800D02*
Y179956D01*
X556011Y181025D01*
X554329D01*
X551754Y183600D01*
G01X642375Y173100D02*
X639600Y170325D01*
X626483D01*
X625154Y171654D01*
X624384Y172425D01*
X601649D01*
X599899Y170675D01*
X554325D01*
X551175Y173825D01*
Y177800D01*
G01X541550Y183550D02*
X541600Y183500D01*
Y183439D01*
X543300Y181739D01*
Y177800D01*
G01X555500Y183500D02*
X556400D01*
X559045Y180855D01*
Y177800D01*
G01X556800Y190000D02*
X552500D01*
X547669Y194831D01*
Y195500D01*
G01X543200Y204600D02*
Y196300D01*
X544000Y195500D01*
X547669D01*
G01X551500Y187500D02*
X551754Y187246D01*
Y183600D01*
G01X546600Y204600D02*
Y208000D01*
X548300Y209700D01*
G01X555200Y205200D02*
X560964D01*
X567324Y211560D01*
X568500D01*
G01X555200Y202200D02*
X560500D01*
G01X565729Y203031D02*
X564478D01*
X561422Y199975D01*
X555975D01*
X555200Y199200D01*
G01X562300Y217600D02*
X562200Y217500D01*
X555300D01*
G01X566500Y77700D02*
X568200D01*
X570500Y80000D01*
Y85000D01*
G01X568890Y94200D02*
Y88343D01*
X570500Y86733D01*
Y85000D01*
G01X568890Y177800D02*
Y182795D01*
X569395Y183300D01*
G01X634748Y177708D02*
Y175648D01*
X632150Y173050D01*
X626517D01*
X625192Y174375D01*
X600840D01*
X599090Y172625D01*
X565375D01*
X562985Y175015D01*
Y177800D01*
G01X561900Y183600D02*
Y183085D01*
X562985Y182000D01*
Y177800D01*
G01X566897Y183405D02*
X566920Y183382D01*
Y177800D01*
G01D02*
X566940Y177780D01*
Y175624D01*
X567989Y174575D01*
X598281D01*
X600031Y176325D01*
X627575D01*
X628900Y175000D01*
G01X558500Y194500D02*
X558891D01*
X568173Y185218D01*
X569917D01*
X571120Y184015D01*
Y182585D01*
X570860Y182325D01*
Y177800D01*
G01X560200Y186800D02*
Y185300D01*
X561900Y183600D01*
G01X577000Y195735D02*
X572965D01*
X572100Y196600D01*
G01X570500Y190500D02*
X573200D01*
X573600Y190100D01*
G01X556800Y190000D02*
Y192800D01*
X558500Y194500D01*
G01X566000Y194000D02*
X567800Y192200D01*
Y191200D01*
X566000Y189400D01*
Y188735D01*
X568567Y186168D01*
X572108D01*
X574440Y188500D01*
X577384D01*
X578175Y187709D01*
Y186175D01*
X577500Y185500D01*
X575370D01*
X574570Y184700D01*
Y182685D01*
X574795Y182460D01*
Y177800D01*
G01X577000Y191795D02*
X575944D01*
X574924Y192815D01*
X571252D01*
X568825Y195242D01*
Y200000D01*
X568019Y200806D01*
X565011D01*
X561076Y196871D01*
Y195073D01*
X563549Y192600D01*
X564600D01*
X566000Y194000D01*
G01X570500Y202500D02*
X569775Y201775D01*
Y195636D01*
X571646Y193765D01*
X577000D01*
G01X580350Y207250D02*
Y205796D01*
X576454Y201900D01*
X574150D01*
X572100Y199850D01*
Y196600D01*
G01X568500Y211560D02*
X575150D01*
G01X560500Y202200D02*
X561400D01*
X568200Y209000D01*
X575150D01*
G01X565729Y203031D02*
X567031D01*
X570445Y206445D01*
X575150D01*
G01Y219240D02*
X579448D01*
X581550Y221342D01*
X583343D01*
X584685Y220000D01*
Y216600D01*
X583785Y215700D01*
X578975D01*
X578625Y215350D01*
Y213025D01*
X579075Y212575D01*
X582550D01*
X582900Y212225D01*
Y210675D01*
X582550Y210325D01*
X579075D01*
X578625Y209875D01*
Y205415D01*
X576110Y202900D01*
X570900D01*
X570500Y202500D01*
G01X562300Y217600D02*
X565696Y220996D01*
X570503D01*
X571500Y221993D01*
Y223355D01*
X572500Y224355D01*
X575150D01*
G01X568000Y217500D02*
X568899D01*
X573199Y221800D01*
X575150D01*
G01X580700Y94200D02*
Y79700D01*
X575000Y74000D01*
X574500D01*
G01X577000Y79800D02*
X573600D01*
X573300Y80100D01*
G01X572825Y94200D02*
Y80575D01*
X573300Y80100D01*
G01X574795Y94200D02*
Y89305D01*
X575000Y89100D01*
G01X576295Y183400D02*
Y183360D01*
X578730Y180925D01*
Y177800D01*
G01X586605D02*
Y183955D01*
X588050Y185400D01*
Y188350D01*
X589530Y189830D01*
X590400D01*
G01X572845Y183300D02*
X572825Y183280D01*
Y177800D01*
G01X582670D02*
Y179980D01*
X580529Y182121D01*
Y184006D01*
X579125Y185410D01*
Y196636D01*
X578056Y197705D01*
X577000D01*
G01X586655Y187050D02*
Y186355D01*
X584800Y184500D01*
Y183300D01*
G01X577000Y189830D02*
X573870D01*
X573600Y190100D01*
G01X596850Y219240D02*
X594736D01*
X589550Y214054D01*
Y211050D01*
X587075Y208575D01*
Y205075D01*
X587980Y204170D01*
Y192909D01*
X589094Y191795D01*
X590400D01*
G01X583800Y207200D02*
Y202479D01*
X581096Y199775D01*
X580099D01*
X579994Y199670D01*
X577000D01*
G01X575150Y221800D02*
X579250D01*
X579600Y222150D01*
Y223650D01*
X579950Y224000D01*
X585400D01*
X586635Y222765D01*
Y215475D01*
X584500Y213340D01*
Y209275D01*
X584150Y208925D01*
X583085D01*
X582075Y207915D01*
Y205827D01*
X580745Y204497D01*
Y202450D01*
G01X593475Y183275D02*
Y183225D01*
X592510Y182260D01*
Y177800D01*
G01X601750Y182500D02*
X602275Y183025D01*
Y191017D01*
X606925Y195667D01*
Y206014D01*
X607739Y206828D01*
Y218961D01*
X600850Y225850D01*
X593869D01*
X593375Y225356D01*
Y223125D01*
X594700Y221800D01*
X596850D01*
G01X601750Y182500D02*
Y180319D01*
X599706Y178275D01*
X599224D01*
X598749Y177800D01*
X596450D01*
G01X599150Y180300D02*
X600025Y181175D01*
Y183215D01*
X600325Y183515D01*
Y191825D01*
X604975Y196475D01*
Y206822D01*
X605789Y207636D01*
Y218153D01*
X600042Y223900D01*
X597305D01*
X596850Y224355D01*
G01X599150Y180300D02*
X598076D01*
X597351Y181025D01*
X595549D01*
X594480Y179956D01*
Y177800D01*
G01X590400Y193765D02*
X594635D01*
X595350Y193050D01*
G01D02*
Y188725D01*
X594350Y187725D01*
G01X597916Y186411D02*
Y193773D01*
X595954Y195735D01*
X590400D01*
G01X591850Y187725D02*
X593575Y186000D01*
X597505D01*
X597916Y186411D01*
G01X601000Y195800D02*
X601125Y195925D01*
Y201422D01*
X597947Y204600D01*
X592711D01*
X592249Y205061D01*
X589638Y207672D01*
Y209102D01*
X591500Y210964D01*
Y213246D01*
X594934Y216680D01*
X596850D01*
G01X601000Y195800D02*
X598475D01*
X597300Y196975D01*
X592700D01*
X591970Y197705D01*
X590400D01*
G01X601200Y207700D02*
X599900Y209000D01*
X596850D01*
G01X602800Y203225D02*
X603025Y203450D01*
Y208456D01*
X599921Y211560D01*
X596850D01*
G01X591363Y208387D02*
X593305Y206445D01*
X596850D01*
G01X595500Y198800D02*
X597200D01*
X598900Y200500D01*
G01X590400Y199670D02*
X592880D01*
X593750Y198800D01*
X595500D01*
G01X596850Y219240D02*
X601554D01*
X603047Y217747D01*
G01X603800Y105490D02*
X607266D01*
X617000Y95756D01*
Y87000D01*
G01X603800Y103520D02*
X607892D01*
X614028Y97384D01*
Y82472D01*
X617000Y79500D01*
G01X603800Y109425D02*
X606250D01*
X614175Y101500D01*
X620000D01*
G01X603800Y107455D02*
X606876D01*
X620000Y94331D01*
Y94000D01*
G01X613000Y115700D02*
X610900Y117800D01*
X609600D01*
G01X608360Y121800D02*
Y119040D01*
X609600Y117800D01*
G01X612120Y121750D02*
X613250D01*
X615500Y119500D01*
G01X616000Y115700D02*
Y119000D01*
X615500Y119500D01*
G01X603800Y133045D02*
X611255D01*
G01X617300Y128500D02*
X615800D01*
X611255Y133045D01*
G01X603800Y123205D02*
X606955D01*
X608360Y121800D01*
G01X603800Y125175D02*
X608695D01*
X612120Y121750D01*
G01X630000Y136600D02*
X619900D01*
X607705Y148795D01*
X603800D01*
G01X619200Y178500D02*
X616900Y180800D01*
X616225D01*
X615000Y182025D01*
Y182500D01*
G01D02*
Y183375D01*
X615791Y184166D01*
Y187000D01*
G01X615800Y178500D02*
X615450Y178850D01*
X615417D01*
X612775Y181492D01*
Y184159D01*
X613616Y185000D01*
Y188651D01*
X616000Y191035D01*
Y194211D01*
X614375Y195836D01*
Y198115D01*
X615935Y199675D01*
X624675D01*
X625125Y200125D01*
X634675D01*
X636500Y198300D01*
G01X605600Y186650D02*
Y191584D01*
X606516Y192500D01*
X608525D01*
X608875Y192850D01*
Y199875D01*
X609500Y200500D01*
G01X612500Y204800D02*
X613500Y203800D01*
Y200000D01*
X612500Y199000D01*
X611289D01*
X610825Y198536D01*
Y194398D01*
X611175Y194048D01*
X613405D01*
X614050Y193403D01*
Y191843D01*
X611224Y189017D01*
X610428D01*
X609345Y190100D01*
G01X612500Y216300D02*
X610125D01*
X609775Y215950D01*
Y200775D01*
X609500Y200500D01*
G01X612000Y212000D02*
Y208700D01*
X612500Y208200D01*
G01X626889Y218000D02*
X625500D01*
X619500Y212000D01*
X612000D01*
G01X612500Y219700D02*
X609800D01*
X607500Y222000D01*
Y223500D01*
X608000Y224000D01*
X617749D01*
X617949Y223800D01*
G01D02*
Y217500D01*
X618449Y217000D01*
X621000D01*
X621500Y217500D01*
Y222500D01*
X622000Y223000D01*
X626889D01*
G01X622500Y81700D02*
X623977Y83177D01*
X631500D01*
G01D02*
Y95375D01*
X628875Y98000D01*
Y101539D01*
X630200Y102864D01*
Y109397D01*
X637450Y116647D01*
Y132850D01*
X634000Y136300D01*
G01X623000Y115700D02*
Y121000D01*
G01X620700Y128500D02*
Y125300D01*
X621100Y124900D01*
G01X623000Y121000D02*
Y123000D01*
X621100Y124900D01*
G01X630000Y136600D02*
X633700D01*
X634000Y136300D01*
G01X628900Y175000D02*
X631050D01*
X631900Y175850D01*
G01X628650Y182440D02*
Y178650D01*
X628900Y178400D01*
G01X632700Y192000D02*
X629700Y195000D01*
Y198300D01*
G01X639800Y192900D02*
Y195000D01*
X638450Y196350D01*
X635050D01*
X633100Y198300D01*
G01X629300Y192000D02*
X626849Y194451D01*
X626186D01*
G01X624209Y190740D02*
Y192474D01*
X626186Y194451D01*
G01X628650Y187560D02*
Y189150D01*
X629600Y190100D01*
X633926D01*
X635626Y191800D01*
X636300D01*
G01X650500Y155000D02*
X651675Y153825D01*
Y140321D01*
X642600Y131246D01*
Y112000D01*
X638000Y107400D01*
G01X645000Y165300D02*
Y161000D01*
G01D02*
Y160000D01*
X646000Y159000D01*
X651886D01*
X653638Y160752D01*
G01X640461Y181410D02*
X642710D01*
X643500Y182200D01*
G01X634748Y177708D02*
X636556Y175900D01*
X643609D01*
X645225Y177516D01*
Y177525D01*
X646500Y178800D01*
G01X642375Y173100D02*
X647200D01*
X647300Y173000D01*
G01X635150Y187560D02*
X638040D01*
X641400Y184200D01*
X645000D01*
X646500Y182700D01*
Y182200D01*
G01X635150Y182440D02*
Y180600D01*
X637610Y178140D01*
X638524D01*
G01D02*
X638539Y178125D01*
X642825D01*
X643500Y178800D01*
G01X650100Y176700D02*
X648500Y178300D01*
Y187400D01*
X646500Y189400D01*
G01X643100Y192500D02*
Y189400D01*
G01X642600Y186400D02*
Y188900D01*
X643100Y189400D01*
G01X636300Y191800D02*
X637500D01*
X639800Y189500D01*
G01X646500Y192500D02*
Y197000D01*
X645200Y198300D01*
X636500D01*
G01X649111Y208000D02*
X652879D01*
X658479Y202400D01*
G01X649111Y213000D02*
X652900D01*
X657900Y208000D01*
G01X651750Y179940D02*
Y177450D01*
X651000Y176700D01*
X650100D01*
G01X662800Y179500D02*
X662700D01*
X662260Y179940D01*
X658250D01*
G01X662800Y179500D02*
X665500D01*
X666500Y180500D01*
G01X655500Y173100D02*
Y173050D01*
X655450Y173000D01*
X650700D01*
G01X655500Y173100D02*
X658025Y175625D01*
X661756D01*
X662825Y174556D01*
Y172325D01*
X662362Y171862D01*
Y167248D01*
G01X654851Y191978D02*
X655422D01*
X656700Y190700D01*
Y189000D01*
G01X651750Y185060D02*
Y186750D01*
X653300Y188300D01*
Y189000D01*
G01X652146Y194648D02*
Y192101D01*
X653300Y190947D01*
Y189000D01*
G01X657722Y193800D02*
X658922Y192600D01*
X660700D01*
X660800Y192500D01*
G01Y189500D02*
Y192500D01*
G01X658250Y185060D02*
X662215D01*
X663155Y186000D01*
G01X664200Y189500D02*
Y187045D01*
X663155Y186000D01*
G01X661500Y205000D02*
Y202900D01*
X661000Y202400D01*
X658479D01*
G01X661500Y208000D02*
X657900D01*
G01X673044Y190456D02*
Y183544D01*
X670000Y180500D01*
X669900D01*
G01X664900Y208000D02*
X667900D01*
X668000Y208100D01*
G01X668732Y204555D02*
Y207368D01*
X668000Y208100D01*
G01X664900Y205000D02*
Y203583D01*
X666446Y202037D01*
G01X684200Y183000D02*
X685300D01*
X689400Y178900D01*
G01X691900Y181400D02*
Y177853D01*
X689547Y175500D01*
G01X681500Y194250D02*
Y187300D01*
G01X680800Y183000D02*
X681500Y183700D01*
Y187300D01*
G01X691900Y184800D02*
Y187094D01*
X690400Y188594D01*
Y188600D01*
G01D02*
X690394D01*
X686500Y192494D01*
Y194250D01*
G01X695300Y188650D02*
Y188800D01*
X691500Y192600D01*
Y194250D01*
G01X694900Y184800D02*
X695400Y185300D01*
Y188550D01*
X695300Y188650D01*
G01X709879Y165479D02*
X702134Y157734D01*
Y117652D01*
X699241Y114759D01*
G01X714842Y173742D02*
X700183Y159083D01*
Y119362D01*
X698970Y118149D01*
G01X709900Y139900D02*
Y132600D01*
X713000Y129500D01*
X717300D01*
X718000Y130200D01*
G01X715000Y140300D02*
X711803Y143497D01*
Y143500D01*
X709500D01*
G01X727800Y176600D02*
X725275Y174075D01*
X718475D01*
X709879Y165479D01*
G01X718000Y130200D02*
X721300D01*
G01X718200Y147000D02*
X721300D01*
G01X714700D02*
X718200D01*
G01X724700D02*
Y146700D01*
X726625Y144775D01*
X728046D01*
X730976Y141845D01*
Y139639D01*
X731636Y138979D01*
G01X714700Y150000D02*
X717800D01*
X718200Y150400D01*
G01X721300Y150000D02*
X718600D01*
X718200Y150400D01*
G01X724700Y150000D02*
X725517D01*
X728792Y146725D01*
X729243D01*
X730784Y145184D01*
G01X724700Y153000D02*
X726116D01*
X728589Y150527D01*
G01X714700Y153000D02*
X715400D01*
X717853Y155453D01*
X718825D01*
G01X721300Y153000D02*
X718847Y155453D01*
X718825D01*
G01X726000Y179800D02*
X727800Y178000D01*
Y176600D01*
G01X714842Y173742D02*
X717125Y176025D01*
X724400D01*
G01X723000Y179800D02*
X724400Y178400D01*
Y176025D01*
G01X728740Y187440D02*
X728240D01*
X726000Y185200D01*
Y183200D01*
G01D02*
X729800Y179400D01*
X730400D01*
G01X719200Y184100D02*
Y186200D01*
X720440Y187440D01*
X721260D01*
G01X723000Y183200D02*
X720100D01*
X719200Y184100D01*
G01X714370Y246430D02*
Y268470D01*
X715900Y270000D01*
G01X735654Y137700D02*
X732915D01*
X731636Y138979D01*
G01X735654Y140850D02*
Y143462D01*
X728589Y150527D01*
G01X735654Y139275D02*
X734403D01*
X733529Y140149D01*
Y142439D01*
X730784Y145184D01*
G01X750984Y6630D02*
Y14490D01*
X754626Y18132D01*
X762978D01*
X766578Y21732D01*
X771268D01*
X774000Y19000D01*
X778300D01*
G01X746260Y6630D02*
Y11188D01*
X746675Y11603D01*
Y20188D01*
X752619Y26132D01*
X757632D01*
X757923Y26423D01*
X766437D01*
X766578Y26282D01*
X772282D01*
X774000Y28000D01*
X778300D01*
G01X752165Y38966D02*
Y34342D01*
X753050Y33457D01*
X760692D01*
X767392Y40157D01*
X780676D01*
X782500Y38333D01*
Y38207D01*
G01X779500D02*
X768200D01*
X761500Y31507D01*
X752500D01*
X749803Y34204D01*
Y38966D01*
G01X747441D02*
Y33007D01*
G01X778300Y22000D02*
Y19000D01*
G01Y25000D02*
Y28000D01*
G01X779500Y34807D02*
X776300D01*
X774500Y33007D01*
Y31307D01*
G01X778000D02*
X780300D01*
X782500Y33507D01*
Y34807D01*
G01Y41800D02*
X783531D01*
X794032Y52301D01*
Y57032D01*
G01X806200Y109000D02*
Y106590D01*
X811950Y100840D01*
Y46950D01*
X806500Y41500D01*
X801500D01*
X799500Y39500D01*
Y32500D01*
X794032Y27032D01*
G01Y47032D02*
Y49032D01*
X800000Y55000D01*
Y68268D01*
X804775Y73043D01*
Y89575D01*
X806200Y91000D01*
G01X794032Y57032D02*
X797757Y60757D01*
Y68985D01*
X802825Y74053D01*
Y93625D01*
X806200Y97000D01*
G01Y103000D02*
Y100500D01*
X800875Y95175D01*
Y74861D01*
X794032Y68018D01*
Y67032D01*
G01X807500Y86200D02*
X810000Y88700D01*
Y93200D01*
X806200Y97000D01*
G54D138*
G01X200900Y177000D02*
X202150Y175750D01*
X203940D01*
G01X219940Y162250D02*
Y159280D01*
X219200Y158540D01*
Y157000D01*
G54D54*
X121000Y254266D03*
Y267734D03*
G54D72*
X194603Y105871D03*
Y120871D03*
Y115871D03*
Y110871D03*
X220893Y105871D03*
Y120871D03*
Y115871D03*
Y110871D03*
G54D18*
X27900Y84500D03*
X31300D03*
X25000Y203800D03*
X28400D03*
X35500Y187000D03*
X38900D03*
X60700Y211800D03*
X64100D03*
X60700Y226800D03*
X64100D03*
X60700Y220800D03*
X64100D03*
X60700Y223800D03*
X64100D03*
X60700Y235800D03*
X64100D03*
X60700Y229800D03*
X64100D03*
X60700Y238800D03*
X64100D03*
X49200Y247400D03*
X52600D03*
X76800Y82000D03*
X76900Y207200D03*
X71067Y249509D03*
X74467D03*
X80200Y82000D03*
X80300Y207200D03*
X101300Y188500D03*
X104700D03*
X102300Y200000D03*
X105700D03*
X108800Y228400D03*
X103600Y239500D03*
X107000D03*
X123800Y137800D03*
X113400Y214600D03*
X116800D03*
X112200Y228400D03*
X113500Y217800D03*
X116900D03*
X127200Y137800D03*
X148800Y205000D03*
X152200D03*
X167600Y193600D03*
X171000D03*
X167600Y196600D03*
X171000D03*
X170300Y241000D03*
X172800Y72500D03*
X176200D03*
X186800D03*
X174300Y84500D03*
X177700D03*
X174300Y81500D03*
X177700D03*
X174800Y109600D03*
X178200D03*
X180300Y131000D03*
X183700D03*
X173700Y241000D03*
X190200Y72500D03*
X216300Y92500D03*
X215800Y157000D03*
X217300Y180500D03*
Y183500D03*
X232300Y102000D03*
Y99000D03*
X219700Y92500D03*
X218800Y136000D03*
X222200D03*
X218800Y148000D03*
X222200D03*
X218800Y142000D03*
X222200D03*
X218800Y145000D03*
X222200D03*
X218800Y139000D03*
X222200D03*
X219200Y157000D03*
X229800Y164500D03*
X233200D03*
X220700Y180500D03*
Y183500D03*
X236000Y54400D03*
X239400D03*
X245300Y88500D03*
X248700D03*
X235700Y102000D03*
Y99000D03*
X245300Y91500D03*
X248700D03*
X251300Y127000D03*
X254700D03*
X253300Y186500D03*
X256700D03*
X279300Y121000D03*
X272300D03*
X275700D03*
X271200Y166300D03*
X274600D03*
X276900Y178400D03*
X266300Y198000D03*
X269700D03*
X266300Y201000D03*
X269700D03*
X281300Y72000D03*
X284700D03*
X288300Y104000D03*
X291700D03*
X288300Y107000D03*
X291700D03*
X282700Y121000D03*
X289800Y126500D03*
X293200D03*
X289800Y129500D03*
X293200D03*
X293400Y151500D03*
X286800Y164000D03*
X290200D03*
X280300Y178400D03*
X289800Y185500D03*
X293200D03*
X305300Y50500D03*
X308700D03*
X305300Y47500D03*
X308700D03*
X296800Y151500D03*
X322800Y251000D03*
X326200D03*
X394400Y266100D03*
X397800D03*
X419800Y78500D03*
X423200D03*
X437300Y79500D03*
X440700D03*
X502800Y142000D03*
X506200D03*
X502800Y145000D03*
X506200D03*
X502800Y148000D03*
X506200D03*
X502800Y139000D03*
X506200D03*
X539800Y72500D03*
Y75500D03*
X543200Y72500D03*
Y75500D03*
X556800Y190000D03*
Y186800D03*
X551800Y199200D03*
X555200D03*
X551800Y202200D03*
X555200D03*
X551800Y205200D03*
X555200D03*
X554500Y223700D03*
Y220700D03*
Y226700D03*
X560200Y190000D03*
Y186800D03*
X557900Y223700D03*
Y220700D03*
Y226700D03*
X600800Y49000D03*
X604200D03*
X608300Y46000D03*
X611700D03*
X629300Y192000D03*
X632700D03*
X647300Y173000D03*
X643100Y192500D03*
X646500D03*
X650700Y173000D03*
X660800Y192500D03*
X664200D03*
X653300Y189000D03*
X656700D03*
X661500Y205000D03*
X664900D03*
X661500Y208000D03*
X664900D03*
X667300Y158000D03*
X670700D03*
X666500Y180500D03*
X669900D03*
X711300Y147000D03*
Y153000D03*
X717800Y137000D03*
X721200D03*
X721300Y150000D03*
X724700D03*
X714700Y147000D03*
Y153000D03*
X721300D03*
X724700D03*
X726800Y169000D03*
Y172000D03*
X730200Y169000D03*
Y172000D03*
X763300Y145900D03*
X766700D03*
X763300Y142900D03*
X766700D03*
X778300Y22000D03*
X781700D03*
X778300Y25000D03*
X781700D03*
G54D27*
X45857Y91657D03*
Y93626D03*
Y95594D03*
Y97563D03*
Y99531D03*
Y101500D03*
Y103469D03*
Y105437D03*
Y107406D03*
Y109374D03*
Y111343D03*
X34357Y133657D03*
Y135626D03*
Y137594D03*
Y139563D03*
Y141531D03*
Y143500D03*
Y145469D03*
Y147437D03*
Y149406D03*
Y151374D03*
Y153343D03*
X64143Y105437D03*
Y103469D03*
Y101500D03*
Y99531D03*
Y97563D03*
Y95594D03*
Y93626D03*
Y91657D03*
Y111343D03*
Y109374D03*
Y107406D03*
X52643Y135626D03*
Y133657D03*
Y151374D03*
Y149406D03*
Y147437D03*
Y145469D03*
Y143500D03*
Y141531D03*
Y139563D03*
Y137594D03*
Y153343D03*
X218795Y197079D03*
Y199047D03*
Y201016D03*
Y202984D03*
Y204953D03*
Y206921D03*
X229205Y197079D03*
Y206921D03*
Y204953D03*
Y202984D03*
Y201016D03*
Y199047D03*
G54D45*
X87729Y270300D03*
X96391D03*
G54D63*
X171320Y160560D03*
Y155440D03*
Y158000D03*
Y164940D03*
Y167500D03*
Y170060D03*
X173120Y151060D03*
X180480D03*
Y145940D03*
X173120D03*
Y148500D03*
X178680Y160560D03*
Y155440D03*
Y164940D03*
Y170060D03*
X427820Y251940D03*
Y257060D03*
X435180Y251940D03*
Y257060D03*
Y254500D03*
X721380Y197525D03*
Y202645D03*
X733320Y192560D03*
X740680D03*
Y187440D03*
X733320D03*
Y190000D03*
X728740Y197525D03*
Y202645D03*
Y200085D03*
G54D81*
X273791Y210500D03*
X288291Y53000D03*
X282209Y214240D03*
Y206760D03*
X296709Y56740D03*
Y49260D03*
X615791Y187000D03*
X624209Y183260D03*
Y190740D03*
G54D36*
X52500Y116000D03*
X51000Y217500D03*
X77200Y194000D03*
X74100Y252600D03*
X82400Y139200D03*
X105500Y197000D03*
Y194000D03*
X182100Y127700D03*
X183100Y176000D03*
X192500Y193500D03*
X265000Y49500D03*
X285500Y219000D03*
X426000Y260500D03*
X474200Y245500D03*
X506500Y155000D03*
X514500Y176000D03*
Y179000D03*
X523500Y215500D03*
X568000Y227000D03*
X604000Y46000D03*
X620500Y208000D03*
X670500Y161000D03*
Y171500D03*
G54D129*
X792515Y146060D03*
G54D90*
X387205Y26342D03*
G54D148*
G01X31700Y229500D02*
X30625Y228425D01*
X28485D01*
X17259Y239651D01*
X8810D01*
X7600Y240861D01*
G01X31700Y226000D02*
X30625Y227075D01*
X27925D01*
X16699Y238301D01*
X8810D01*
X7600Y237091D01*
G01X31700Y219000D02*
X30625Y220075D01*
X29025D01*
X16761Y232339D01*
X14300D01*
X13090Y231129D01*
G01X31700Y222500D02*
X30625Y221425D01*
X29585D01*
X17321Y233689D01*
X14300D01*
X13090Y234899D01*
G01X31700Y233000D02*
X30525Y234175D01*
X27752D01*
X17777Y244150D01*
X14800D01*
X13590Y242940D01*
G01X31700Y240000D02*
X30625Y241075D01*
X27201D01*
X18164Y250112D01*
X8810D01*
X7600Y248902D01*
G01X31700Y243500D02*
X30625Y242425D01*
X27761D01*
X18724Y251462D01*
X8810D01*
X7600Y252672D01*
G01X31700Y236500D02*
X30725Y235525D01*
X28312D01*
X18337Y245500D01*
X14800D01*
X13590Y246710D01*
G01X31700Y250500D02*
X30725Y249525D01*
X26561D01*
X18775Y257311D01*
X14800D01*
X13590Y258521D01*
G01X31700Y247000D02*
X30525Y248175D01*
X26001D01*
X18215Y255961D01*
X14800D01*
X13590Y254751D01*
G01X31700Y257500D02*
X30625Y256425D01*
X25475D01*
X18627Y263273D01*
X8810D01*
X7600Y264483D01*
G01X31700Y254000D02*
X30625Y255075D01*
X24915D01*
X18067Y261923D01*
X8810D01*
X7600Y260713D01*
G01X43200Y198800D02*
Y199400D01*
X42025Y200575D01*
X33275D01*
X32000Y199300D01*
G01X43200Y203700D02*
Y202900D01*
X42225Y201925D01*
X33275D01*
X32000Y203200D01*
G01X46800Y198800D02*
Y200075D01*
X47400Y200675D01*
X48325D01*
X49506Y199494D01*
Y196406D01*
X47950Y194850D01*
Y190240D01*
X49340Y188850D01*
X50650D01*
X51860Y187640D01*
G01X40200Y198800D02*
X37600D01*
G01X40200Y203700D02*
X37600D01*
G01X43000Y207800D02*
X40400D01*
G01X43000Y212700D02*
X40400D01*
G01X46000Y207800D02*
Y208400D01*
X44825Y209575D01*
X36075D01*
X34800Y208300D01*
G01X46000Y212700D02*
Y211900D01*
X45025Y210925D01*
X36075D01*
X34800Y212200D01*
G01X46800Y203700D02*
Y202600D01*
X47375Y202025D01*
X48885D01*
X50856Y200054D01*
Y195846D01*
X49300Y194290D01*
Y190800D01*
X49900Y190200D01*
X50650D01*
X51860Y191410D01*
G01X35300Y219000D02*
X37900D01*
G01X35300Y222500D02*
X37900D01*
G01Y226000D02*
X35300D01*
G01X38000Y236500D02*
X35300D01*
G01X37900Y233000D02*
X35300D01*
G01X37900Y229500D02*
X35300D01*
G01X37900Y240000D02*
X35300D01*
G01X37900Y243500D02*
X35300D01*
G01X38000Y250500D02*
X35300D01*
G01X37900Y247000D02*
X35300D01*
G01X37900Y254000D02*
X35300D01*
G01X37900Y257500D02*
X35300D01*
G01X49600Y207800D02*
Y209200D01*
X50400Y210000D01*
X52000D01*
X54650Y207350D01*
Y205700D01*
X53860Y204910D01*
Y203260D01*
X54650Y202470D01*
Y200820D01*
X53860Y200030D01*
Y198380D01*
X54650Y197590D01*
Y194902D01*
X57050Y192502D01*
Y185710D01*
X55720Y184380D01*
G01X49600Y212700D02*
Y212065D01*
X50315Y211350D01*
X52560D01*
X56000Y207910D01*
Y195462D01*
X58400Y193062D01*
Y185359D01*
X59379Y184380D01*
G01X76181Y24392D02*
Y31407D01*
X77474Y32700D01*
Y39294D01*
X76411Y40357D01*
G01X80118Y24392D02*
Y31382D01*
X78824Y32676D01*
Y39150D01*
X80031Y40357D01*
G01X91929Y24392D02*
Y31606D01*
X93223Y32900D01*
Y39293D01*
X92159Y40357D01*
G01X107677Y24392D02*
Y31507D01*
X108970Y32800D01*
Y39294D01*
X107907Y40357D01*
G01X95866Y24392D02*
Y31534D01*
X94573Y32827D01*
Y39151D01*
X95779Y40357D01*
G01X123425Y24392D02*
Y31406D01*
X124719Y32700D01*
Y39293D01*
X123655Y40357D01*
G01X111614Y24392D02*
Y31406D01*
X110320Y32700D01*
Y39150D01*
X111527Y40357D01*
G01X143220Y118325D02*
X138189D01*
X132025Y112161D01*
Y101208D01*
X120125Y89308D01*
Y83391D01*
X115917Y79183D01*
X112101D01*
X111162Y78244D01*
Y75064D01*
X111200Y75026D01*
Y67200D01*
G01X139173Y24392D02*
Y33256D01*
X140467Y34550D01*
Y39293D01*
X139403Y40357D01*
G01X127362Y24392D02*
Y31507D01*
X126069Y32800D01*
Y39151D01*
X127275Y40357D01*
G01X143110Y24392D02*
Y33257D01*
X141817Y34550D01*
Y39151D01*
X143023Y40357D01*
G01X154921Y24392D02*
Y33257D01*
X156214Y34550D01*
Y39294D01*
X155151Y40357D01*
G01X150670Y115500D02*
X149570Y116600D01*
X147550D01*
X147310Y116360D01*
X143220D01*
G01Y118325D02*
X147025D01*
X147400Y117950D01*
X149720D01*
X150670Y118900D01*
G01X170669Y24392D02*
Y33256D01*
X171963Y34550D01*
Y39293D01*
X170899Y40357D01*
G01X158858Y24392D02*
Y33256D01*
X157564Y34550D01*
Y39150D01*
X158771Y40357D01*
G01X186417Y24392D02*
Y33256D01*
X187711Y34550D01*
Y39293D01*
X186647Y40357D01*
G01X174606Y24392D02*
Y33257D01*
X173313Y34550D01*
Y39151D01*
X174519Y40357D01*
G01X202165Y24392D02*
Y33257D01*
X203458Y34550D01*
Y40868D01*
X206425Y43835D01*
Y47875D01*
X205600Y48700D01*
G01X190354Y24392D02*
Y33257D01*
X189061Y34550D01*
Y39151D01*
X190267Y40357D01*
G01X194700Y48200D02*
X195525Y47375D01*
Y41475D01*
X194445Y40395D01*
G01X197700Y48200D02*
X196875Y47375D01*
Y41593D01*
X198073Y40395D01*
G01X194700Y51800D02*
Y54400D01*
G01X197700Y51800D02*
Y54400D01*
G01X206102Y24392D02*
Y33256D01*
X204808Y34550D01*
Y40308D01*
X207775Y43275D01*
Y47875D01*
X208600Y48700D01*
G01Y52300D02*
Y54800D01*
X208700Y54900D01*
G01X205600Y52300D02*
Y54600D01*
X205300Y54900D01*
G01X233661Y24392D02*
Y33256D01*
X234955Y34550D01*
Y38235D01*
X233655Y39535D01*
Y41993D01*
X232591Y43057D01*
G01X237598Y24392D02*
Y33257D01*
X236305Y34550D01*
Y38795D01*
X235005Y40095D01*
Y41851D01*
X236211Y43057D01*
G01X253346Y24392D02*
Y33256D01*
X252052Y34550D01*
Y44152D01*
X252675Y44775D01*
Y50875D01*
X253500Y51700D01*
G01X249409Y24392D02*
Y33257D01*
X250702Y34550D01*
Y44712D01*
X251325Y45335D01*
Y50875D01*
X250500Y51700D01*
G01X253500Y55300D02*
Y57900D01*
G01X250500Y55300D02*
Y57900D01*
G01X269094Y24392D02*
Y33256D01*
X267700Y34650D01*
Y39280D01*
X268910Y40490D01*
G01X265157Y24392D02*
Y33257D01*
X266350Y34450D01*
Y39280D01*
X265140Y40490D01*
G01X313392Y130531D02*
X312431D01*
X309255Y127355D01*
X307665D01*
X306498Y126188D01*
Y125071D01*
X305332Y123904D01*
X304214D01*
X303048Y122738D01*
Y121620D01*
X301881Y120454D01*
X300764D01*
X299597Y119287D01*
Y118170D01*
X298431Y117003D01*
X297313D01*
X295905Y115595D01*
Y113105D01*
X293955Y111155D01*
X292305D01*
X291515Y110365D01*
X289865D01*
X289075Y111155D01*
X287425D01*
X286635Y110365D01*
X284985D01*
X284195Y111155D01*
X281855D01*
X281000Y110300D01*
Y108650D01*
X281790Y107860D01*
Y106210D01*
X281000Y105420D01*
Y103540D01*
X279610Y102150D01*
X276290D01*
X274900Y103540D01*
Y108900D01*
X274300Y109500D01*
X273348D01*
X272200Y108352D01*
G01X317332Y131541D02*
X314292D01*
X313952Y131881D01*
X311871D01*
X308695Y128705D01*
X307105D01*
X294555Y116155D01*
Y113665D01*
X293395Y112505D01*
X281295D01*
X279650Y110860D01*
Y104100D01*
X279050Y103500D01*
X276850D01*
X276250Y104100D01*
Y109460D01*
X274860Y110850D01*
X273166D01*
X272185Y111831D01*
G01X280905Y24392D02*
Y33257D01*
X282198Y34550D01*
Y39280D01*
X280988Y40490D01*
G01X284842Y24392D02*
Y33256D01*
X283548Y34550D01*
Y39280D01*
X284758Y40490D01*
G01X296653Y24392D02*
Y33257D01*
X297946Y34550D01*
Y39280D01*
X296736Y40490D01*
G01X300590Y24392D02*
Y33256D01*
X299296Y34550D01*
Y39280D01*
X300506Y40490D01*
G01X307500Y122700D02*
Y122831D01*
X314058Y129389D01*
X314110D01*
X315222Y130501D01*
X316499D01*
X317869Y129131D01*
X318702D01*
G01X315782Y129151D02*
X314670Y128039D01*
X314618D01*
X313290Y126710D01*
X309700Y123120D01*
Y122796D01*
G01X312401Y24392D02*
Y33257D01*
X313694Y34550D01*
Y39480D01*
X312484Y40690D01*
G01X316338Y24392D02*
Y33256D01*
X315044Y34550D01*
Y39480D01*
X316254Y40690D01*
G01X317352Y123221D02*
X316731Y122600D01*
X316070D01*
X315451Y123219D01*
G01X321922Y123261D02*
X319454D01*
X319418Y123225D01*
G01X320332Y199551D02*
X320001D01*
X316860Y196410D01*
Y196026D01*
X316844Y196010D01*
G01X321442Y196901D02*
X319801Y195260D01*
Y194890D01*
G01X325782Y197891D02*
X324587Y196696D01*
X323331D01*
G01X323772Y199771D02*
Y199372D01*
X323018Y198618D01*
X322256D01*
G01X326442Y200601D02*
Y201525D01*
X325642Y202325D01*
G01X376196Y226576D02*
X381850Y232230D01*
Y246677D01*
X372650Y255877D01*
X339133D01*
X325906Y242650D01*
X318740D01*
X316850Y240760D01*
Y238550D01*
X316000Y237700D01*
G01X375241Y227531D02*
X380500Y232790D01*
Y246117D01*
X372090Y254527D01*
X339693D01*
X326466Y241300D01*
X319300D01*
X318200Y240200D01*
Y238600D01*
X319100Y237700D01*
G01X328149Y24392D02*
Y33257D01*
X329442Y34550D01*
Y39856D01*
X328303Y40995D01*
G01X332086Y24392D02*
Y33256D01*
X330792Y34550D01*
Y39856D01*
X331931Y40995D01*
G01X330100Y98000D02*
X330600Y98500D01*
X338010D01*
X338560Y99050D01*
X342938D01*
X345302Y101414D01*
Y103911D01*
G01X330100Y100200D02*
X330450Y99850D01*
X337450D01*
X338000Y100400D01*
X342378D01*
X343952Y101974D01*
Y104471D01*
X344992Y105511D01*
Y108061D01*
G01X336750Y95704D02*
X337154Y95300D01*
X338490D01*
X340140Y96950D01*
X346940D01*
X349352Y99362D01*
Y104561D01*
G01X336750Y93500D02*
X337100Y93850D01*
X338950D01*
X340700Y95600D01*
X347500D01*
X350702Y98802D01*
Y105121D01*
X349382Y106441D01*
Y107481D01*
G01X331622Y104561D02*
X332445D01*
X333313Y103693D01*
G01X327822Y121201D02*
X329100Y119923D01*
X329415D01*
G01X337352Y118101D02*
X333595D01*
X333534Y118040D01*
G01X337352Y121101D02*
X334202D01*
X333601Y120500D01*
G01X331652Y107481D02*
X332621D01*
X333434Y106668D01*
G01X330822Y121201D02*
X329637Y122386D01*
X329308D01*
G01X326550Y191600D02*
X327011Y192061D01*
X328592D01*
G01X326850Y193900D02*
X327431D01*
X328592Y195061D01*
G01X331352D02*
X331252D01*
X329972Y196341D01*
Y196400D01*
G01X331352Y192061D02*
X329972Y193441D01*
Y193559D01*
G01X336412Y190561D02*
X334910Y192063D01*
X333996D01*
G01X336412Y187561D02*
Y187678D01*
X334707Y189383D01*
G01X339172Y193561D02*
Y193554D01*
X337818Y192200D01*
X337800D01*
G01X339172Y190561D02*
Y190554D01*
X337818Y189200D01*
X337800D01*
G01X336722Y197691D02*
X335400Y196369D01*
Y196300D01*
G01X327216Y203902D02*
Y203404D01*
X328089Y202531D01*
X328532D01*
G01X336842Y202551D02*
Y200420D01*
X335739Y199317D01*
G01X364300Y229390D02*
Y241183D01*
X358756Y246727D01*
X342927D01*
X336150Y239950D01*
Y226650D01*
X328510Y219010D01*
Y218320D01*
G01X365650Y229390D02*
Y241743D01*
X359316Y248077D01*
X342367D01*
X334800Y240510D01*
Y227210D01*
X332190Y224600D01*
X331400D01*
X330233Y223433D01*
Y222643D01*
X327614Y220024D01*
X327024D01*
G01X328945Y235846D02*
X330036D01*
X330700Y236510D01*
Y241927D01*
X340750Y251977D01*
X371033D01*
X377875Y245135D01*
Y234075D01*
G01X331142Y233658D02*
Y235042D01*
X332050Y235950D01*
Y241367D01*
X341310Y250627D01*
X370473D01*
X376525Y244575D01*
Y234075D01*
G01X347932Y116601D02*
Y116499D01*
X346596Y115163D01*
G01X347932Y119601D02*
Y119499D01*
X346596Y118163D01*
G01X354812Y181561D02*
X354734D01*
X353302Y182993D01*
G01X344232Y180061D02*
Y181151D01*
X342363Y183020D01*
Y183186D01*
X342188Y183361D01*
G01X346992Y186061D02*
X346990D01*
X345631Y187420D01*
G01X346992Y183061D02*
X346939D01*
X345500Y184500D01*
G01X354812Y184561D02*
Y184654D01*
X353342Y186124D01*
G01X344232Y183061D02*
X343713Y183580D01*
Y184159D01*
X342233Y185639D01*
G01X344232Y189061D02*
X343269Y190024D01*
X342342D01*
G01X344232Y192061D02*
X342513D01*
X342350Y192224D01*
Y192225D01*
X342339D01*
G01X346992Y192061D02*
Y191996D01*
X345500Y190504D01*
Y190500D01*
G01X346992Y195061D02*
X345596Y193665D01*
Y193567D01*
X345503Y193474D01*
G01X352052Y187561D02*
X349913Y189700D01*
X349100D01*
G01Y191900D02*
X349183Y191817D01*
X350796D01*
X352052Y190561D01*
G01X354812Y193561D02*
X353625Y194748D01*
Y195045D01*
G01X354812Y190561D02*
X353625Y191748D01*
Y192045D01*
G01X371392Y118101D02*
X372700Y119409D01*
Y119663D01*
G01X371392Y121101D02*
X370100Y119809D01*
Y119563D01*
G01X362632Y189061D02*
Y189325D01*
X361257Y190700D01*
G01Y193524D02*
X362632Y192149D01*
Y192061D01*
G01X367692Y190561D02*
X365275D01*
X364895Y190941D01*
G01X364947Y193141D02*
X365407Y193601D01*
X367652D01*
X367692Y193561D01*
G01X370452Y187561D02*
X369200Y188812D01*
Y189100D01*
G01X370452Y190561D02*
X369110Y191903D01*
X369106D01*
G01X359872Y195061D02*
X357239D01*
X356600Y195700D01*
G01X359872Y192061D02*
X358633Y193300D01*
X356700D01*
G01X375512Y189061D02*
X374223Y190350D01*
X374000D01*
G01X375512Y192061D02*
X374470Y193103D01*
X373922D01*
G01X408350Y232850D02*
X401100D01*
X394229Y239721D01*
Y241128D01*
G01X408350Y231500D02*
X400540D01*
X399645Y232395D01*
X398528D01*
X397361Y233562D01*
Y234679D01*
X393280Y238760D01*
X391788D01*
G01X415552Y118101D02*
Y118239D01*
X416904Y119591D01*
G01X415552Y121101D02*
X416851Y122400D01*
Y122600D01*
G54D139*
G01X240565Y113365D02*
X239630Y114300D01*
X236100D01*
G54D37*
X54000Y127000D03*
X60600Y208500D03*
X73000Y132000D03*
X70200Y265800D03*
X86400Y206600D03*
X98900Y203700D03*
X118500Y131500D03*
X153200Y216000D03*
X150200D03*
X167400Y155600D03*
X182500Y91000D03*
X187600Y149200D03*
X184500D03*
X183500Y188500D03*
X178800Y203600D03*
X181800D03*
X197700Y51500D03*
X194700D03*
X188400Y206250D03*
X216000Y167500D03*
X217700Y191500D03*
X253500Y55000D03*
X250500D03*
X277000Y228300D03*
X274000D03*
X293300Y157500D03*
X314500Y244000D03*
X448000Y254500D03*
X537500Y61000D03*
X538500Y84500D03*
X534500Y210000D03*
X555300Y211100D03*
X585500Y83000D03*
X591500D03*
X594500D03*
X597500Y235000D03*
X616000Y109000D03*
X613000D03*
X609400Y235000D03*
X612500D03*
X619500D03*
X724700Y126400D03*
X721000Y143500D03*
X717000Y193500D03*
X718500Y209900D03*
X733500Y172000D03*
X744500Y192500D03*
Y239000D03*
G54D73*
X214300Y56191D03*
X210560Y64609D03*
X218040D03*
G54D91*
X482874Y67286D03*
X476969Y218110D03*
X776968Y67286D03*
X771063Y218110D03*
G54D64*
X170760Y189000D03*
X174500Y181000D03*
X178240Y189000D03*
G54D46*
X99331Y70650D03*
X115669D03*
X531331Y195500D03*
X547669D03*
G54D55*
X143220Y78955D03*
Y80925D03*
Y82895D03*
Y84860D03*
Y86830D03*
Y88800D03*
Y90770D03*
Y92735D03*
Y94705D03*
Y96675D03*
Y98640D03*
Y100610D03*
Y102580D03*
Y104545D03*
Y106515D03*
Y108485D03*
Y110455D03*
Y112420D03*
Y114390D03*
Y116360D03*
Y118325D03*
Y120295D03*
Y122265D03*
Y124230D03*
Y126200D03*
Y128170D03*
Y130140D03*
Y132105D03*
Y134075D03*
Y136045D03*
X165755Y78955D03*
Y80925D03*
Y82895D03*
Y84860D03*
Y86830D03*
Y88800D03*
Y90770D03*
Y92735D03*
Y94705D03*
Y96675D03*
Y98640D03*
Y100610D03*
Y102580D03*
Y104545D03*
Y106515D03*
Y108485D03*
Y110455D03*
Y112420D03*
Y114390D03*
Y116360D03*
Y118325D03*
Y120295D03*
Y122265D03*
Y124230D03*
Y126200D03*
Y128170D03*
Y130140D03*
Y132105D03*
Y134075D03*
Y136045D03*
G54D19*
X26100Y97900D03*
Y103100D03*
X39300Y111500D03*
Y116700D03*
X68800Y133400D03*
Y138600D03*
X71800Y170400D03*
Y175600D03*
X92000Y167900D03*
Y173100D03*
X94420Y252800D03*
Y258000D03*
X109000Y124900D03*
Y130100D03*
X103500Y124900D03*
Y130100D03*
X101000Y243500D03*
Y248700D03*
X99420Y252800D03*
Y258000D03*
X114500Y124900D03*
Y130100D03*
X121000Y214900D03*
Y220100D03*
X135500Y150100D03*
Y155300D03*
X160500Y195900D03*
Y201100D03*
X187200Y137500D03*
Y142700D03*
X214000Y171000D03*
Y176200D03*
X209800Y199400D03*
Y204600D03*
X513500Y188400D03*
Y193600D03*
X512500Y219400D03*
Y224600D03*
X517500Y219400D03*
Y224600D03*
X674200Y47407D03*
Y52607D03*
X720500Y55900D03*
X715500D03*
X720500Y61100D03*
X715500D03*
X742500Y60900D03*
Y66100D03*
X732300Y102100D03*
Y107300D03*
X747500Y60900D03*
Y66100D03*
X764500Y149900D03*
Y155100D03*
G54D82*
X280950Y243180D03*
Y240620D03*
Y238060D03*
Y235500D03*
Y232945D03*
Y250855D03*
Y248300D03*
Y245740D03*
X302650Y232945D03*
Y235500D03*
Y238060D03*
Y240620D03*
Y243180D03*
Y245740D03*
Y248300D03*
Y250855D03*
X575150Y211560D03*
Y209000D03*
Y206445D03*
Y224355D03*
Y221800D03*
Y219240D03*
Y216680D03*
Y214120D03*
X596850Y206445D03*
Y209000D03*
Y211560D03*
Y214120D03*
Y216680D03*
Y219240D03*
Y221800D03*
Y224355D03*
G54D28*
X46750Y126000D03*
X211250Y210500D03*
G54D149*
G01X608071Y246430D02*
Y251013D01*
X606750Y252334D01*
Y255550D01*
X606700Y255600D01*
G01X605709Y246430D02*
Y251324D01*
X605300Y251733D01*
Y253168D01*
X604074Y254394D01*
G01X606890Y278766D02*
Y275300D01*
X607190Y275000D01*
Y272012D01*
X608996Y270206D01*
G01X609252Y278766D02*
Y275698D01*
X608640Y275086D01*
Y273465D01*
X609216Y272889D01*
X609896D01*
G01X647047Y6630D02*
Y9830D01*
X646135Y10742D01*
Y14672D01*
X645300Y15507D01*
G01X644685Y6630D02*
Y12415D01*
X644193Y12907D01*
G01X645866Y38966D02*
Y36157D01*
X646778Y35245D01*
Y29829D01*
X647000Y29607D01*
G01X648228Y38966D02*
Y32254D01*
X649550Y30932D01*
Y30807D01*
G54D38*
X54000Y124000D03*
X60600Y205500D03*
X73000Y129000D03*
X70200Y262800D03*
X86400Y203600D03*
X98900Y200700D03*
X118500Y128500D03*
X153200Y213000D03*
X150200D03*
X167400Y152600D03*
X182500Y88000D03*
X187600Y146200D03*
X184500D03*
X183500Y185500D03*
X178800Y200600D03*
X181800D03*
X197700Y48500D03*
X194700D03*
X188400Y203250D03*
X216000Y164500D03*
X217700Y188500D03*
X253500Y52000D03*
X250500D03*
X277000Y225300D03*
X274000D03*
X293300Y154500D03*
X314500Y241000D03*
X448000Y251500D03*
X537500Y58000D03*
X538500Y81500D03*
X534500Y207000D03*
X555300Y208100D03*
X585500Y80000D03*
X591500D03*
X594500D03*
X597500Y232000D03*
X616000Y106000D03*
X613000D03*
X609400Y232000D03*
X612500D03*
X619500D03*
X724700Y123400D03*
X721000Y140500D03*
X717000Y190500D03*
X718500Y206900D03*
X733500Y169000D03*
X744500Y189500D03*
Y236000D03*
G54D29*
X44250Y126000D03*
X208750Y210500D03*
G54D74*
X232791Y82260D03*
Y89740D03*
X241209Y86000D03*
X248591Y102060D03*
Y109540D03*
X257009Y105800D03*
X273791Y193260D03*
Y200740D03*
X282209Y197000D03*
G54D47*
X111500Y89850D03*
Y113150D03*
G54D56*
X136800Y260189D03*
G54D92*
X500787Y70042D03*
X494882Y215354D03*
X759055Y70042D03*
X753150Y215354D03*
G54D65*
X172811Y226000D03*
Y221000D03*
Y231000D03*
G54D83*
X276811Y263386D03*
X296811D03*
X457913Y45276D03*
X477913D03*
G54D66*
X164500Y228500D03*
G54D57*
X136800Y255861D03*
G54D48*
X108550Y153000D03*
X109200Y165500D03*
X119150Y153000D03*
X119800Y165500D03*
G54D75*
X224984Y196795D03*
X223016D03*
Y207205D03*
X224984D03*
G54D84*
X305900Y121151D03*
X303610Y110800D03*
X309000Y114700D03*
X306700D03*
X311200Y114800D03*
X311410Y118110D03*
X309194Y117700D03*
X306994Y117725D03*
X304149Y128349D03*
X307854Y130539D03*
X309700Y122796D03*
X309500Y132925D03*
X307298Y132697D03*
X307500Y122700D03*
X305050Y151150D03*
X309000Y137600D03*
X311000Y141731D03*
X306961Y153717D03*
X306696Y158610D03*
X309000Y158806D03*
X311242Y158732D03*
X309220Y153698D03*
X305800Y195400D03*
X305290Y187836D03*
X301320Y191060D03*
X303500Y195400D03*
X310500Y195600D03*
X308200D03*
X303480Y189100D03*
X301300Y188700D03*
X309700Y187997D03*
X307500Y188000D03*
X309100Y206800D03*
X317641Y90956D03*
X325081Y100631D03*
X322075Y100650D03*
X323120Y92400D03*
X319520Y92419D03*
X318900Y98000D03*
X317600Y93625D03*
X326162Y91438D03*
X315950Y98650D03*
X315613Y100850D03*
X315400Y110800D03*
X312000Y122600D03*
X320992Y112180D03*
X325300Y112300D03*
X311600Y110800D03*
X322010Y118573D03*
X325350Y114500D03*
X319096Y113300D03*
X319418Y123225D03*
X315451Y123219D03*
X323900Y129900D03*
X322691Y136023D03*
X326313Y122380D03*
X323007Y127672D03*
X320321Y130528D03*
X325418Y127349D03*
X325746Y133702D03*
X312917Y133440D03*
X323300Y147046D03*
X323550Y142104D03*
X319252Y140949D03*
X326322Y138434D03*
X325763Y141958D03*
X319401Y149354D03*
X317698Y152311D03*
X325200Y149319D03*
X319704Y162804D03*
X323000Y153900D03*
X315384Y166733D03*
X324953Y161722D03*
X324200Y157800D03*
X324029Y166384D03*
X326234Y153969D03*
X311417Y153821D03*
X323165Y171937D03*
X324436Y175705D03*
X326399Y169401D03*
X323500Y180063D03*
X311460Y172078D03*
X319942Y180524D03*
X323121Y182913D03*
X326408Y182292D03*
X312829Y181940D03*
X316844Y196010D03*
X319801Y194890D03*
X326550Y191600D03*
X323800Y192150D03*
X323789Y188117D03*
X320029Y184300D03*
X326500Y187900D03*
X311900Y188070D03*
X322256Y198618D03*
X323331Y196696D03*
X319500Y212100D03*
X325642Y202325D03*
X321600Y208700D03*
Y211000D03*
X317200Y213100D03*
X315585Y207787D03*
X324100Y208000D03*
X318700Y207800D03*
X311600Y207600D03*
X325200Y221700D03*
X319400Y216200D03*
X317200Y215300D03*
X313600Y237700D03*
X321400D03*
X316000D03*
X319100D03*
X329300Y87300D03*
X331200Y88600D03*
X330100Y100200D03*
Y98000D03*
X328000Y97100D03*
X334850Y96900D03*
X336750Y93500D03*
X335500Y91600D03*
X336750Y95704D03*
X328000Y92700D03*
X330900Y93400D03*
X333313Y103693D03*
X339500Y102000D03*
X332600Y101400D03*
X329415Y119923D03*
X333601Y120500D03*
X333534Y118040D03*
X333551Y115090D03*
X333434Y106668D03*
X333416Y108899D03*
X330470Y112515D03*
X330910Y115010D03*
X341200Y112569D03*
X338768Y116755D03*
Y119755D03*
X329308Y122386D03*
X338329Y135665D03*
X329031Y125428D03*
X335303Y135178D03*
X339280Y127380D03*
X341309Y135651D03*
X329693Y134428D03*
X331290Y125810D03*
X330870Y130540D03*
X336900Y127600D03*
X333977Y127678D03*
X327854Y130434D03*
X338470Y138177D03*
X335450Y150900D03*
X327963Y142008D03*
X335514Y138220D03*
X338320Y141300D03*
X327390Y149106D03*
X336920Y146130D03*
X329421Y138228D03*
X327696Y146108D03*
X336190Y141970D03*
X330796Y146221D03*
X330163Y142008D03*
X332478Y138255D03*
X341342Y138224D03*
X333750Y145950D03*
X339491Y143163D03*
X329800Y150800D03*
X332000D03*
X330300Y158546D03*
X339784Y161847D03*
X335499Y153846D03*
X327800Y161500D03*
X336900Y161600D03*
X336800Y164434D03*
X341390Y153991D03*
X329161Y153830D03*
X335964Y158512D03*
X333742Y161624D03*
X332185Y153806D03*
X338421Y153802D03*
X334470Y164760D03*
X341400Y156700D03*
X331000Y164500D03*
X330900Y161700D03*
X333000Y158300D03*
X339747Y164478D03*
X341300Y169600D03*
X335400D03*
X339300Y174100D03*
X330821Y177402D03*
X333842Y177224D03*
X332300Y173900D03*
X339875Y177303D03*
X329442Y169463D03*
X327708Y177241D03*
X332353Y169522D03*
X337000Y174102D03*
X327600Y174174D03*
X330027Y174119D03*
X334700Y174100D03*
X336915Y177423D03*
X337863Y180545D03*
X334715Y180900D03*
X330280D03*
X332500D03*
X332100Y185600D03*
X338000Y185700D03*
X335000Y185500D03*
X335400Y196300D03*
X337800Y189200D03*
X326850Y193900D03*
X329972Y196400D03*
Y193559D03*
X333996Y192063D03*
X334707Y189383D03*
X337800Y192200D03*
X338048Y196250D03*
X342029Y196427D03*
X332800Y187700D03*
X326831Y196119D03*
X329313Y188000D03*
X337670Y213520D03*
X335739Y199317D03*
X336500Y204600D03*
X332974Y210874D03*
X338926Y211674D03*
X338967Y209455D03*
X331658Y212660D03*
X329028Y199931D03*
X339800Y207400D03*
X327216Y203902D03*
X330200Y216800D03*
X336000Y219750D03*
X328510Y218320D03*
X327024Y220024D03*
X337307Y217961D03*
X331616Y214860D03*
X337341Y215731D03*
X333036Y231910D03*
X327100Y237100D03*
X328945Y235846D03*
X331142Y233658D03*
X344523Y98477D03*
X344500Y94000D03*
X347230Y100190D03*
X351342Y114158D03*
X346596Y118163D03*
Y115163D03*
X351000Y111700D03*
X355175Y108212D03*
X348076Y108910D03*
X343570Y112561D03*
X346600Y121100D03*
X346495Y130000D03*
X349149Y124141D03*
X351500Y136000D03*
X354333Y125665D03*
X343000Y126200D03*
X343146Y128473D03*
X343000Y124000D03*
X347641Y133479D03*
X342533Y133822D03*
X349600Y126700D03*
X357300Y128600D03*
X355400Y137100D03*
X354300Y128600D03*
X346300Y143000D03*
X342880Y146180D03*
X355447Y146528D03*
X344500Y141700D03*
X348675Y143326D03*
X350800Y138300D03*
X355342Y143424D03*
X348743Y146072D03*
X346000Y146043D03*
X346450Y149120D03*
X348743Y149100D03*
X355460Y149510D03*
X348432Y164844D03*
X346944Y156775D03*
X350550Y153280D03*
X342716Y161593D03*
X344300Y153800D03*
X344090Y156690D03*
X352000Y162000D03*
X348700Y161700D03*
X351600Y164300D03*
X355400Y152900D03*
X355413Y156050D03*
X351700Y167300D03*
X350700Y155600D03*
X345900Y161700D03*
X342188Y183361D03*
X355300Y174600D03*
X347200Y174300D03*
X344165Y169466D03*
X352200Y171800D03*
X350000Y177700D03*
X345562Y178700D03*
X347500Y169500D03*
X351600Y169600D03*
X353302Y182993D03*
X353321Y180128D03*
X342233Y185639D03*
X356900Y186100D03*
X349600Y194800D03*
X342760Y187810D03*
X342339Y192225D03*
X342342Y190024D03*
X349100Y191900D03*
X353625Y195045D03*
Y192045D03*
X356600Y195700D03*
X356700Y193300D03*
X345503Y193474D03*
X345500Y190500D03*
X349100Y189700D03*
X353342Y186124D03*
X349751Y187241D03*
X356800Y191000D03*
X345500Y184500D03*
X345631Y187420D03*
X351950Y214800D03*
X346500Y208350D03*
X345500Y213000D03*
X353594Y210707D03*
X347593Y210277D03*
X353385Y212898D03*
X345837Y199887D03*
X350409Y199755D03*
X353792Y208466D03*
X354700Y199900D03*
X343242Y213690D03*
X347664Y212476D03*
X355860Y216690D03*
X345300Y216700D03*
X343198Y215910D03*
X371900Y85400D03*
X364800Y91200D03*
X368600Y90700D03*
X361200Y90200D03*
X371900Y89000D03*
X371950Y92500D03*
X364874Y98250D03*
X362803Y106035D03*
X357900Y99200D03*
X368600Y97500D03*
X357721Y91779D03*
X361200Y97500D03*
X368600Y94100D03*
X365000Y94700D03*
X357721Y95100D03*
X360900Y94200D03*
X361141Y104099D03*
X365316Y108130D03*
X372700Y119663D03*
X370100Y119563D03*
X370000Y116563D03*
X369997Y113706D03*
X368721Y108528D03*
X359942Y110924D03*
X365721Y115528D03*
X358000Y115500D03*
X366400Y112200D03*
X364600Y137063D03*
X367221Y125428D03*
X370000Y122563D03*
X362111Y127142D03*
X362120Y124153D03*
X359421Y127128D03*
Y124008D03*
X372821Y125628D03*
X370121Y125528D03*
X367321Y122528D03*
X368026Y137118D03*
X364700Y134000D03*
X367992Y133982D03*
X367121Y128628D03*
X362111Y130128D03*
X358500Y137000D03*
X371176Y136890D03*
X359300Y130000D03*
X367900Y152550D03*
X368000Y146500D03*
X361700Y143300D03*
X364886Y140268D03*
X368026D03*
Y143418D03*
X364621Y143328D03*
X361726Y140268D03*
X361700Y146549D03*
X361500Y149500D03*
X364700Y152713D03*
X368026Y149718D03*
X368100Y165300D03*
X364600D03*
X367950Y159200D03*
X371157Y162320D03*
X371176Y158940D03*
X358477Y159300D03*
X361600Y159250D03*
X368100Y162200D03*
X358342Y165324D03*
X358576Y162090D03*
X358500Y155700D03*
X371100Y168700D03*
X364600Y174800D03*
X361500Y175000D03*
Y168500D03*
X368000D03*
X367906Y171458D03*
X364600Y171600D03*
X364607Y177103D03*
X370900Y171700D03*
X361200Y178500D03*
X361292Y181409D03*
X372400Y179100D03*
X369021Y180128D03*
X372600Y181400D03*
X361400Y187600D03*
X368455Y196455D03*
X371299Y196008D03*
X364792Y188743D03*
X364600Y186138D03*
X364895Y190941D03*
X369106Y191903D03*
X369200Y189100D03*
X361257Y193524D03*
Y190700D03*
X364947Y193141D03*
X361300Y184500D03*
X359222Y197700D03*
X369009Y186191D03*
X372700Y213700D03*
X369450Y212040D03*
X359750Y208390D03*
X359910Y214100D03*
X358498Y210220D03*
X358382Y212427D03*
X371100Y199500D03*
X365250Y208600D03*
X372800Y221600D03*
X369580Y218800D03*
Y215400D03*
X357966Y217516D03*
X359827Y216341D03*
X383350Y83350D03*
X383450Y90500D03*
X387200D03*
X387100Y83500D03*
X375800D03*
Y90500D03*
X379500Y83302D03*
Y90600D03*
X375800Y87000D03*
X383450Y86900D03*
X387200D03*
X379500D03*
X379526Y106396D03*
X381950Y100950D03*
X381600Y119900D03*
X381900Y113000D03*
X382596Y108600D03*
X385600Y116500D03*
X385200Y113137D03*
X385721Y119528D03*
X381550Y117400D03*
X377800Y112063D03*
X377818Y115008D03*
X386561Y108812D03*
X377713Y121061D03*
X385479Y125569D03*
X381500Y123200D03*
X381600Y126427D03*
X385523Y122532D03*
X385750Y128517D03*
X386708Y137118D03*
X383567Y137096D03*
X377800Y124163D03*
X380475Y137016D03*
X380400Y133928D03*
X380443Y130102D03*
X374200Y136994D03*
X387000Y143280D03*
X380398Y146568D03*
X383548D03*
X380398Y143418D03*
X383395Y143306D03*
X374200Y140144D03*
Y143294D03*
X380400Y152700D03*
X383575Y149603D03*
X380522Y149564D03*
X386853Y149640D03*
X377476Y149688D03*
X374200Y149494D03*
X374100Y159150D03*
X386800Y165300D03*
X380398Y165240D03*
X383781Y165235D03*
X386777Y162155D03*
X387000Y155850D03*
X386777Y159005D03*
X380500Y162025D03*
X383700Y162199D03*
X383500Y159000D03*
X374300Y155800D03*
X377500Y165240D03*
Y156000D03*
X384740Y180080D03*
X381720Y180220D03*
X381800Y183300D03*
X380540Y177370D03*
X380500Y168500D03*
X383693Y171424D03*
X383548Y168390D03*
X386600Y174900D03*
X380477Y171605D03*
X376830Y175640D03*
X376800Y178600D03*
X384650Y183170D03*
X376742Y181524D03*
X381460Y195610D03*
X384390Y196470D03*
X381140Y187960D03*
X381280Y191550D03*
X384708Y188910D03*
X384600Y186100D03*
X376800Y193500D03*
X376900Y196600D03*
X380510Y185500D03*
X384684Y191950D03*
X373922Y193103D03*
X374000Y190350D03*
X379750Y213500D03*
X376300Y211000D03*
Y213700D03*
X384810Y208530D03*
X384644Y205994D03*
X382471Y199843D03*
X382600Y222600D03*
X382750Y229000D03*
X379700Y219200D03*
X385947Y226500D03*
X385900Y218400D03*
X376300Y216200D03*
X385900Y222600D03*
X382700Y226000D03*
X379700Y216500D03*
X372950Y217400D03*
X390700Y89300D03*
X403726Y83826D03*
X403700Y90200D03*
X397300Y89168D03*
X400400Y92200D03*
Y98500D03*
X390750Y96500D03*
X394100Y91400D03*
Y99000D03*
X397100Y96600D03*
X397300Y93100D03*
X392382Y102149D03*
X390650Y93000D03*
X394100Y94900D03*
X400400Y95000D03*
X393331Y118043D03*
X393351Y115107D03*
X397650Y115500D03*
X401749Y112418D03*
X401159Y119636D03*
X401353Y116562D03*
X396276Y120948D03*
X396251Y117999D03*
X396600Y112463D03*
X390683Y108042D03*
X400700Y108800D03*
X393653Y121122D03*
X389700Y112363D03*
X398500Y125604D03*
X398512Y122815D03*
X401500Y125600D03*
X393482Y123982D03*
X396700Y128000D03*
X389914Y124536D03*
X393561Y127130D03*
X401500Y122600D03*
X401256Y128755D03*
X397800Y130000D03*
X399452Y133964D03*
X389380Y130100D03*
X390100Y127600D03*
X390205Y133858D03*
X392998Y133968D03*
X396148D03*
X396321Y136987D03*
X402561Y137000D03*
X399298Y137118D03*
X392998D03*
X389848D03*
X402400Y140163D03*
X393000Y152663D03*
X402900Y149663D03*
X389721Y143320D03*
X393000Y140268D03*
X403132Y144374D03*
X396148Y140268D03*
X399298D03*
X389848Y146568D03*
X393204Y146436D03*
X403080Y146931D03*
X399198Y146468D03*
X396192Y146444D03*
X392998Y149718D03*
X399198Y149618D03*
X396182Y149674D03*
X396200Y152763D03*
X396300Y162100D03*
X399300Y152863D03*
Y155963D03*
X392998Y165240D03*
X396148Y155790D03*
X393208D03*
X399298Y165240D03*
X393028Y162059D03*
X393198Y158940D03*
X403078Y152922D03*
X402373Y155952D03*
X399298Y162090D03*
X402505Y159133D03*
X396148Y158940D03*
X399298D03*
X392599Y181686D03*
X400252Y182966D03*
X403600Y182400D03*
Y180200D03*
X402540Y171760D03*
X399300Y168400D03*
X402600Y174611D03*
X395573Y175400D03*
X396000Y179000D03*
X393077Y168455D03*
X399385Y171686D03*
X396225D03*
X390025Y174672D03*
X393085Y171686D03*
Y174836D03*
X400352Y180171D03*
X397100Y181000D03*
X400301Y186099D03*
X397805Y192061D03*
X392600Y190600D03*
X396200Y194700D03*
X392624Y184537D03*
X389500Y193600D03*
X397307Y186607D03*
X395600Y184100D03*
Y190300D03*
X392700Y193563D03*
X403022Y192094D03*
X402967Y195005D03*
X389484Y190442D03*
X389300Y187700D03*
X402962Y189014D03*
X392596Y187541D03*
X397728Y189053D03*
X395641Y188045D03*
X392100Y213700D03*
X395700Y213600D03*
X400400Y209400D03*
X398500Y208000D03*
X389100Y224000D03*
X399700Y225000D03*
Y216400D03*
X395600Y224400D03*
X395700Y217000D03*
X391950Y220800D03*
X389200Y227400D03*
X392000Y217200D03*
X395700Y220600D03*
X399800D03*
X389150Y230300D03*
X407500Y84000D03*
X407400Y91000D03*
X411300Y85600D03*
X414722Y90250D03*
X414300Y85600D03*
X403800Y87000D03*
X407400Y87400D03*
X411000Y88900D03*
X418300Y91300D03*
X418400Y98150D03*
X411000Y92100D03*
X414622Y98000D03*
X414672Y94500D03*
X417800Y100400D03*
X412650Y100197D03*
X418300Y94800D03*
X407550Y100196D03*
X404529Y118507D03*
X405900Y121700D03*
X409110Y114910D03*
X405200Y115343D03*
X412462Y115713D03*
X409196Y118195D03*
X416904Y119591D03*
X416922Y116613D03*
X413100Y121800D03*
X409110Y120910D03*
X404900Y124600D03*
X416000Y135983D03*
X415000Y131400D03*
X408956Y130064D03*
X418500Y128200D03*
X415100Y127900D03*
X406200Y127400D03*
X412100Y135600D03*
X416851Y122600D03*
X412600Y124100D03*
X412462Y126300D03*
X417753Y131322D03*
X404400Y128900D03*
X405500Y131063D03*
X414900Y147000D03*
X417900Y146900D03*
X408800Y147000D03*
X411900Y146800D03*
X413300Y139100D03*
X413400Y142700D03*
X418000Y142500D03*
X406000Y150200D03*
X407500Y152100D03*
X410400Y152000D03*
X415700Y143100D03*
X410302Y141864D03*
X405990Y144251D03*
X409096Y143963D03*
X406042Y147025D03*
X415100Y149800D03*
X407399Y142561D03*
X408837Y149809D03*
X418439Y167118D03*
X414800Y162600D03*
X411800Y162700D03*
X414572Y165913D03*
X411356Y165732D03*
X407500Y157600D03*
X412900Y157800D03*
X407400Y154863D03*
X406100Y159500D03*
X417785Y162622D03*
X413314Y154908D03*
X410100Y157700D03*
X415100Y158100D03*
X410272Y154794D03*
X416400Y155000D03*
X408600Y159600D03*
X411600D03*
X409300Y167163D03*
X408900Y162463D03*
X406000Y162663D03*
X404558Y154835D03*
X407100Y167429D03*
X418600Y182800D03*
X414960Y178130D03*
X414950Y181460D03*
X411260Y178090D03*
X411553Y181222D03*
X416400Y170300D03*
X413265Y170423D03*
X410408Y170261D03*
X410620Y173300D03*
X405100Y178500D03*
X408158Y178666D03*
X407552Y170424D03*
X416315Y183219D03*
X417900Y178363D03*
X415992Y189254D03*
Y186205D03*
X419097Y189563D03*
X416500Y195563D03*
X408242Y184624D03*
X405231Y184976D03*
X408200Y190500D03*
X408100Y193600D03*
X412500Y197300D03*
X405000Y190700D03*
X412000Y187500D03*
X412500Y194900D03*
X412100Y190400D03*
X418800Y196700D03*
X416139Y192007D03*
X411342Y185024D03*
X405800Y196700D03*
X405102Y187874D03*
X412200Y192600D03*
X416900Y200100D03*
X416353Y207249D03*
X408200Y226900D03*
X408100Y220500D03*
X404400Y228600D03*
Y222300D03*
X415600Y222700D03*
X415800Y215900D03*
X412050Y225100D03*
X412100Y218400D03*
X408200Y223800D03*
X412000Y222000D03*
X415700Y219200D03*
X404400Y225300D03*
X422078Y97678D03*
X422000Y91300D03*
X427560Y104770D03*
X429105Y106337D03*
X426800Y97850D03*
X429500Y93800D03*
X434021Y100128D03*
X422050Y94800D03*
X428100Y120000D03*
X424900Y121213D03*
X420600Y118300D03*
X420672Y120600D03*
X422042Y115224D03*
X424700Y115000D03*
X427900Y114300D03*
X428100Y116500D03*
X427500Y112091D03*
X430302Y112098D03*
X419596Y113463D03*
X425200Y118823D03*
X431188Y116105D03*
X430342Y119724D03*
X428255Y126236D03*
X425000Y135350D03*
X419500Y136400D03*
X430100Y131500D03*
X431700Y128300D03*
X423500Y128200D03*
X427000Y128050D03*
X423900Y131500D03*
X420942Y131324D03*
X422300Y126300D03*
X431504Y126061D03*
X424982Y126500D03*
X434700Y131800D03*
X432542Y136898D03*
X426982Y131334D03*
X427600Y143841D03*
X421500Y142400D03*
X426900Y147100D03*
X431100Y145500D03*
X424856Y142270D03*
X422400Y139000D03*
X420861Y149687D03*
Y146923D03*
X430694Y142275D03*
X428390Y139059D03*
X419499Y139064D03*
X423496Y144000D03*
X428363Y141756D03*
X423945Y165221D03*
X421710Y167230D03*
X431130Y166660D03*
X428238Y167709D03*
X420804Y162659D03*
X420900Y160037D03*
X425500Y154737D03*
X428400D03*
X426000Y167370D03*
X426900Y160040D03*
X430542Y160753D03*
X430600Y164513D03*
X431620Y154620D03*
X422363Y154700D03*
X434500Y160037D03*
X430360Y181350D03*
X430340Y177620D03*
X423642Y181374D03*
X426970Y178310D03*
X425400Y170240D03*
X428500Y173120D03*
X422337Y170575D03*
X425427Y173113D03*
X419453Y173187D03*
X420922Y178117D03*
X423842Y178274D03*
X428431Y170264D03*
X419340Y170500D03*
X421697Y174049D03*
X423910Y175700D03*
X432712Y172469D03*
X434482Y177021D03*
X432100Y190400D03*
X429100Y189696D03*
X426173Y190784D03*
X428830Y195379D03*
X422152Y189600D03*
X420800Y193100D03*
X421171Y196496D03*
X431270Y193425D03*
X425500Y186045D03*
X423966Y190846D03*
X423800Y196500D03*
X433842Y197021D03*
X421848Y186550D03*
X428400Y185900D03*
X429933Y197283D03*
X420975Y211300D03*
X427900Y202800D03*
X424832Y200174D03*
X421811Y202603D03*
X426311Y204399D03*
X421253Y199822D03*
X425642Y209524D03*
X419550Y222700D03*
X419600Y216200D03*
Y219200D03*
X444578Y106201D03*
X442378Y106198D03*
X440178Y106200D03*
X437400Y121600D03*
X442842Y120824D03*
X438700Y112900D03*
X438500Y116400D03*
X439400Y120100D03*
X434960Y114529D03*
X444242Y124324D03*
X435442Y124024D03*
X437800Y128100D03*
X439275Y124197D03*
X434700Y128200D03*
X443443Y144757D03*
X437398Y146257D03*
X435004Y142110D03*
X443400Y148900D03*
X437472Y152501D03*
X434834Y163817D03*
X439600Y153800D03*
X439276Y159645D03*
X435453Y167560D03*
X435105Y181207D03*
X438742Y197224D03*
X435642Y194824D03*
X437921Y192956D03*
X445000Y194500D03*
X443100Y195900D03*
X443000Y192700D03*
X435453Y185397D03*
X436957Y209867D03*
X459800Y118800D03*
X453000Y118700D03*
X456200Y118900D03*
X459700Y129900D03*
X452200Y129800D03*
X463100Y133700D03*
X456000Y133500D03*
X460100Y123100D03*
X453000Y123300D03*
X463200Y126200D03*
X456500Y126100D03*
X456200Y129600D03*
X459700Y133600D03*
X459800Y126200D03*
X456500Y123000D03*
X461200Y167400D03*
X454200D03*
X457700D03*
X464300Y181800D03*
X458000Y171100D03*
X451000D03*
X460000Y174900D03*
X453000D03*
X456500D03*
X454500Y171100D03*
X457400Y197000D03*
X450400D03*
X462500Y189000D03*
X460400Y193300D03*
X453400D03*
X456900D03*
X453900Y197000D03*
X459500Y200700D03*
X452500D03*
X456000D03*
X473900Y178200D03*
X466900D03*
X471300Y181800D03*
X470400Y178200D03*
X467800Y181800D03*
X473100Y185500D03*
X466000D03*
X469500Y189000D03*
X469600Y185500D03*
X466000Y189000D03*
X504000Y12507D03*
X506800Y12907D03*
X508700Y14607D03*
Y17207D03*
X511589Y30295D03*
X507839Y30362D03*
X506500Y32807D03*
X507817Y252248D03*
X511200Y258900D03*
X509244Y272796D03*
X506496Y272500D03*
X523453Y12360D03*
X511800Y12507D03*
X514360Y12417D03*
X526000Y12507D03*
X519426Y12318D03*
X520700Y14807D03*
X518769Y22907D03*
X515484D03*
X522311Y16720D03*
X514300Y20507D03*
X519623Y20457D03*
X525753Y30893D03*
X522733Y32832D03*
X522700Y30007D03*
X513005Y32412D03*
X519400Y33340D03*
X526700Y33207D03*
X511640Y255956D03*
X514137Y256089D03*
X522908Y255117D03*
X526715Y254700D03*
X516600Y252200D03*
X521800Y252875D03*
X513776Y258563D03*
X511736Y273001D03*
X514900Y271350D03*
X522992Y270700D03*
X525845Y272863D03*
X517846Y262489D03*
X521131D03*
X516727Y273122D03*
X521790Y273140D03*
X517100Y265100D03*
X521987D03*
X528525Y12549D03*
X537964Y12317D03*
X532500Y13407D03*
X541114Y12307D03*
X542100Y15107D03*
X530700Y15407D03*
X536485Y22907D03*
X533200D03*
X528219Y15096D03*
X532472Y20515D03*
X537410Y20584D03*
X542407Y30882D03*
X532350Y30807D03*
X529120Y32575D03*
X529000Y30007D03*
X541950Y33340D03*
X532542Y33307D03*
X537200Y33207D03*
X530015Y255000D03*
X531775Y252231D03*
X541005Y254800D03*
X532900Y255300D03*
X535098Y252600D03*
X540900Y252300D03*
X527400Y252100D03*
X530900Y273000D03*
X534100Y270700D03*
X541500Y270900D03*
X535562Y262489D03*
X538847D03*
X529300Y271000D03*
X528330Y273140D03*
X539937Y272989D03*
X539505Y265100D03*
X534905Y273097D03*
X534700Y265100D03*
X550000Y12507D03*
X544860Y12407D03*
X547500Y12507D03*
X553720Y12297D03*
X552800Y14807D03*
X557745Y22907D03*
X554460D03*
X550234Y14997D03*
X553797Y20496D03*
X549500Y29107D03*
X553079Y30712D03*
X549500Y31607D03*
X545928Y31047D03*
X553250Y33207D03*
X547306Y33134D03*
X544800Y255100D03*
X550200Y255500D03*
X551000Y252056D03*
X552800Y255300D03*
X545500Y252600D03*
X553485Y252332D03*
X544292Y273128D03*
X548800Y271000D03*
X551937Y272789D03*
X555641Y262489D03*
X546200Y271000D03*
X554500Y264900D03*
X546900Y273100D03*
X554434Y272914D03*
X568555Y12407D03*
X561200Y12507D03*
X558448Y12407D03*
X566040Y12317D03*
X571600Y14207D03*
X564400Y14307D03*
X566000Y16507D03*
X572200Y28707D03*
X558500Y20507D03*
X573200Y19907D03*
X570852Y33204D03*
X569800Y29807D03*
X565091Y30815D03*
X561456Y30902D03*
X565470Y33287D03*
X573242Y32462D03*
X560635Y33264D03*
X561419Y254850D03*
X565054Y254773D03*
X568327Y253348D03*
X571867Y254685D03*
X560555Y252503D03*
X563376Y256627D03*
X566151Y252115D03*
X572150Y252200D03*
X560600Y270300D03*
X564100Y271100D03*
X567800Y270500D03*
X570200Y273100D03*
X558926Y262489D03*
X570200Y269700D03*
X559600Y272900D03*
X572155Y264900D03*
X565700Y273050D03*
X559700Y264900D03*
X572700Y273100D03*
X587940Y12417D03*
X582655Y12407D03*
X573470Y12347D03*
X578620Y12357D03*
X585280Y12267D03*
X579800Y14807D03*
X577824Y22907D03*
X574539D03*
X583700Y28207D03*
X578600Y20307D03*
X585179Y30867D03*
X581450Y30707D03*
X579100Y33207D03*
X585550Y33340D03*
X587700Y255300D03*
X579205Y254850D03*
X582200Y252206D03*
X587642D03*
X582300Y254900D03*
X578800Y252200D03*
X580200Y273000D03*
X582600Y270300D03*
X588036Y273089D03*
X588400Y270300D03*
X573357Y262489D03*
X576642D03*
X577450Y264900D03*
X580107Y270501D03*
X577636Y272947D03*
X594600Y6707D03*
X590000Y14007D03*
X594500Y4007D03*
X600896Y12407D03*
X601704Y22907D03*
X601000Y20507D03*
X594400Y36207D03*
X589300Y33007D03*
X590500Y30507D03*
X594200Y33607D03*
X600360Y33287D03*
X594600Y260000D03*
X591300Y255010D03*
X590837Y259889D03*
X598398Y260199D03*
X591342Y252206D03*
X603187Y252056D03*
X589500Y257100D03*
X594500Y265200D03*
X591500Y270100D03*
X591536Y273000D03*
X590700Y264833D03*
X598300Y265400D03*
X589900Y268133D03*
X602450Y272900D03*
X598418Y262699D03*
X590322Y262361D03*
X594559Y262559D03*
X595386Y272932D03*
X610952Y12307D03*
X616600D03*
X605700Y12407D03*
X614700Y14107D03*
X615852Y19807D03*
X615907Y24856D03*
X607300Y14507D03*
X616707Y15616D03*
X604989Y22907D03*
X610800Y14807D03*
X605728Y20518D03*
X615951Y22356D03*
X612000Y17407D03*
X610944Y33333D03*
X607800Y30407D03*
X618900Y33290D03*
X615103Y30690D03*
X610500Y30507D03*
X615044Y33190D03*
X607544Y33340D03*
X618877Y30790D03*
X619382Y260089D03*
X615532Y259700D03*
X611706Y259387D03*
X606700Y255600D03*
X604074Y254394D03*
X609500Y254900D03*
X609937Y252106D03*
X608700Y257300D03*
X611845Y253723D03*
X615537Y264789D03*
X619100Y265300D03*
X611536Y264385D03*
X609896Y272889D03*
X608996Y270206D03*
X605100Y270100D03*
X605065Y272967D03*
X611593Y261885D03*
X606200Y267800D03*
X615430Y262213D03*
X612393Y273026D03*
X619180Y262689D03*
X633500Y12406D03*
X624000D03*
X623532Y20007D03*
X623555Y25107D03*
X619607Y19807D03*
X627255Y25107D03*
X627231Y19907D03*
X630955Y25207D03*
X631000Y20107D03*
X634555Y25307D03*
X634757Y20207D03*
X619730Y24864D03*
X634757Y22707D03*
X623480Y22564D03*
X631007Y22707D03*
X619700Y22307D03*
X627257Y22407D03*
X624100Y33190D03*
X633449D03*
X630432Y260100D03*
X626682Y260300D03*
X622933Y260189D03*
X634207Y260300D03*
X630455Y265400D03*
X634280Y265332D03*
X626651Y265489D03*
X622899Y265189D03*
X629937Y272990D03*
X630457Y262832D03*
X626680Y262989D03*
X634280Y262832D03*
X620437Y272990D03*
X622930Y262689D03*
X644193Y12907D03*
X648800Y12707D03*
X641745Y12367D03*
X638400Y20607D03*
X638290Y25674D03*
X642246Y25807D03*
X642451Y20707D03*
X645300Y15507D03*
X648400Y15490D03*
X645200Y27707D03*
X646800Y17607D03*
X642257Y23307D03*
X638507Y23183D03*
X647000Y29607D03*
X649550Y30807D03*
X643700Y33290D03*
X644100Y30307D03*
X650200Y33307D03*
X641900Y31507D03*
X638032Y260342D03*
X642802Y252186D03*
X645920Y254130D03*
X635043Y252106D03*
X638900Y254809D03*
X643020Y254710D03*
X647800Y252300D03*
X635197Y254602D03*
X638893Y252206D03*
X638090Y265340D03*
X642937Y273089D03*
X646360Y271530D03*
X637288Y270100D03*
X637337Y272944D03*
X648948Y262489D03*
X644090Y270420D03*
X648200Y265300D03*
X637987Y262842D03*
X644550Y267170D03*
X639500Y268800D03*
X648291Y273140D03*
X662359Y12379D03*
X657897Y12504D03*
X651316Y12360D03*
X659400Y25907D03*
Y20474D03*
X662192Y14874D03*
X663202Y25973D03*
X655602Y25223D03*
X663200Y20956D03*
X655700Y20225D03*
X664212Y16356D03*
X663300Y23454D03*
X662916Y28457D03*
X655592Y22723D03*
X659400Y23207D03*
X662503Y33207D03*
X657900Y30690D03*
X664678Y30307D03*
X661708Y30699D03*
X657900Y33190D03*
X659437Y246389D03*
X665500Y252189D03*
X665300Y254700D03*
X661200Y248500D03*
X653600Y252130D03*
X659500Y274000D03*
X665100Y272700D03*
X652233Y262489D03*
X664500Y270000D03*
X653000Y264900D03*
X661600Y272300D03*
X653041Y272989D03*
X671290Y12457D03*
X665901Y12307D03*
X675990Y12357D03*
X674320Y14219D03*
X666175Y14807D03*
X680580Y22807D03*
X677295D03*
X669600Y17907D03*
X676600Y20307D03*
X671500Y15007D03*
X674400Y31307D03*
X671295Y33190D03*
X671900Y30707D03*
X675970Y33267D03*
X670200Y254700D03*
X673770Y254752D03*
X669930Y252150D03*
X674636Y252406D03*
X669700Y270900D03*
X672800Y272700D03*
X676113Y262489D03*
X679398D03*
X680600Y265000D03*
X675400D03*
X668000Y272890D03*
X680400Y273100D03*
X675400D03*
X690102Y12502D03*
X684760Y12256D03*
X687602Y12439D03*
X694200Y13507D03*
X681280Y12457D03*
X692200Y15357D03*
X682013Y14848D03*
X695029Y22853D03*
X684500Y15507D03*
X689595Y27883D03*
X685400Y28307D03*
X681700Y20507D03*
X694205Y20302D03*
X693300Y30607D03*
X689624Y30383D03*
X685700Y30807D03*
X681900Y30907D03*
X693700Y33107D03*
X681280Y33340D03*
X687900Y33327D03*
X682800Y254900D03*
X685382Y252200D03*
X688800Y254600D03*
X692250Y255700D03*
X690000Y256800D03*
X685390Y254900D03*
X688720Y252090D03*
X693860Y252210D03*
X681900Y252500D03*
X682481Y270700D03*
X685100Y273100D03*
X689700Y270800D03*
X692537Y272989D03*
X696192Y262489D03*
X691900Y269300D03*
X683100Y268000D03*
X695500Y265000D03*
Y273100D03*
X687682Y272889D03*
X709000Y12407D03*
X702000Y12607D03*
X699503Y12482D03*
X706360Y12397D03*
X705031Y14515D03*
X698277Y22855D03*
X705604Y16949D03*
X710813Y28796D03*
X699104Y20495D03*
X708900Y30407D03*
X704430Y33313D03*
X701800Y30807D03*
X707157Y33333D03*
X700940Y33340D03*
X701649Y255049D03*
X704178Y252189D03*
X707800Y255000D03*
X711400Y255072D03*
X704137Y254796D03*
X699800Y252230D03*
X701704Y257549D03*
X707490Y252310D03*
X701300Y270777D03*
X704277Y272989D03*
X709400Y272600D03*
X699477Y262489D03*
X706000Y270500D03*
X700200Y264900D03*
X700300Y273100D03*
X706900Y273000D03*
X723586Y14080D03*
X712182Y14124D03*
X714000Y12407D03*
X719110Y12347D03*
X725530Y12507D03*
X720100Y14707D03*
X718375Y22907D03*
X715090D03*
X714100Y20607D03*
X719220Y20553D03*
X727000Y30407D03*
X723500Y29907D03*
X721747Y32954D03*
X712400Y30807D03*
X721074Y30514D03*
X718350Y33107D03*
X712450Y33340D03*
X725653Y32654D03*
X721500Y255000D03*
X724374Y254515D03*
X712350Y252640D03*
X725950Y252573D03*
X721395Y252175D03*
X721600Y257500D03*
X716737Y252189D03*
X712200Y270500D03*
X722400Y270800D03*
X725300Y272800D03*
X717452Y262489D03*
X720737D03*
X716795Y265000D03*
X721400D03*
X721395Y273100D03*
X713100Y273000D03*
X716737Y272989D03*
X715900Y270000D03*
X742200Y12407D03*
X728010Y12857D03*
X737300Y12307D03*
X732110Y12267D03*
X739000Y14407D03*
X731169Y14584D03*
X736091Y23607D03*
X732806D03*
X728500Y15507D03*
X742100Y28107D03*
X732000Y20307D03*
X736748D03*
X728500Y27907D03*
X742100Y33007D03*
X740200Y29907D03*
X730500D03*
X733474Y33340D03*
X738487Y33094D03*
X730400Y255400D03*
X732200Y252200D03*
X741560Y255000D03*
X730300Y257900D03*
X734937Y253100D03*
X739750Y252800D03*
X730400Y272850D03*
X732740Y270200D03*
X741200Y270500D03*
X735168Y262489D03*
X738453D03*
X729860Y269810D03*
X734200Y265100D03*
X739111Y264962D03*
X739838Y272813D03*
X727800Y272800D03*
X734510Y273110D03*
X745100Y12256D03*
X744900Y20500D03*
X745000Y23000D03*
X744800Y33007D03*
X747441D03*
X744437Y252189D03*
X744100Y254800D03*
X749000Y252200D03*
X744200Y272600D03*
X753000Y272100D03*
X746737Y272889D03*
G54D39*
X62246Y154500D03*
X84754D03*
G36*
G01X507677Y3080D02*
X507552Y3090D01*
X507427Y3130D01*
X507317Y3190D01*
X507217Y3270D01*
X507137Y3370D01*
X507077Y3480D01*
X507037Y3605D01*
X507027Y3730D01*
Y6160D01*
X506997Y6190D01*
X506897Y6330D01*
X506877Y6370D01*
X506862Y6405D01*
X506842Y6445D01*
X506827Y6485D01*
X506817Y6525D01*
X506802Y6570D01*
X506797Y6610D01*
X506787Y6650D01*
X506782Y6695D01*
Y6735D01*
X506777Y6780D01*
X506782Y6825D01*
Y6865D01*
X506787Y6910D01*
X506797Y6950D01*
X506802Y6990D01*
X506817Y7035D01*
X506827Y7075D01*
X506842Y7115D01*
X506862Y7155D01*
X506877Y7190D01*
X506897Y7230D01*
X506997Y7370D01*
X507027Y7400D01*
Y9530D01*
X507037Y9655D01*
X507077Y9780D01*
X507137Y9890D01*
X507217Y9990D01*
X507317Y10070D01*
X507427Y10130D01*
X507552Y10170D01*
X507677Y10180D01*
X507802Y10170D01*
X507927Y10130D01*
X508037Y10070D01*
X508137Y9990D01*
X508217Y9890D01*
X508277Y9780D01*
X508317Y9655D01*
X508327Y9530D01*
Y7405D01*
X508357Y7375D01*
X508382Y7340D01*
X508412Y7305D01*
X508432Y7270D01*
X508457Y7235D01*
X508497Y7155D01*
X508542Y7035D01*
X508552Y6995D01*
X508562Y6950D01*
X508567Y6910D01*
X508577Y6865D01*
Y6695D01*
X508567Y6650D01*
X508562Y6610D01*
X508552Y6565D01*
X508542Y6525D01*
X508497Y6405D01*
X508457Y6325D01*
X508432Y6290D01*
X508412Y6255D01*
X508382Y6220D01*
X508357Y6185D01*
X508327Y6155D01*
Y3730D01*
X508317Y3605D01*
X508277Y3480D01*
X508217Y3370D01*
X508137Y3270D01*
X508037Y3190D01*
X507927Y3130D01*
X507802Y3090D01*
X507677Y3080D01*
G37*
G36*
G01X521850D02*
X521725Y3090D01*
X521600Y3130D01*
X521490Y3190D01*
X521390Y3270D01*
X521310Y3370D01*
X521250Y3480D01*
X521210Y3605D01*
X521200Y3730D01*
Y6160D01*
X521170Y6190D01*
X521070Y6330D01*
X521050Y6370D01*
X521035Y6405D01*
X521015Y6445D01*
X521000Y6485D01*
X520990Y6525D01*
X520975Y6570D01*
X520970Y6610D01*
X520960Y6650D01*
X520955Y6695D01*
Y6735D01*
X520950Y6780D01*
X520955Y6825D01*
Y6865D01*
X520960Y6910D01*
X520970Y6950D01*
X520975Y6990D01*
X520990Y7035D01*
X521000Y7075D01*
X521015Y7115D01*
X521035Y7155D01*
X521050Y7190D01*
X521070Y7230D01*
X521170Y7370D01*
X521200Y7400D01*
Y9530D01*
X521210Y9655D01*
X521250Y9780D01*
X521310Y9890D01*
X521390Y9990D01*
X521490Y10070D01*
X521600Y10130D01*
X521725Y10170D01*
X521850Y10180D01*
X521975Y10170D01*
X522100Y10130D01*
X522210Y10070D01*
X522310Y9990D01*
X522390Y9890D01*
X522450Y9780D01*
X522490Y9655D01*
X522500Y9530D01*
Y7405D01*
X522530Y7375D01*
X522555Y7340D01*
X522585Y7305D01*
X522605Y7270D01*
X522630Y7235D01*
X522670Y7155D01*
X522715Y7035D01*
X522725Y6995D01*
X522735Y6950D01*
X522740Y6910D01*
X522750Y6865D01*
Y6695D01*
X522740Y6650D01*
X522735Y6610D01*
X522725Y6565D01*
X522715Y6525D01*
X522670Y6405D01*
X522630Y6325D01*
X522605Y6290D01*
X522585Y6255D01*
X522555Y6220D01*
X522530Y6185D01*
X522500Y6155D01*
Y3730D01*
X522490Y3605D01*
X522450Y3480D01*
X522390Y3370D01*
X522310Y3270D01*
X522210Y3190D01*
X522100Y3130D01*
X521975Y3090D01*
X521850Y3080D01*
G37*
G36*
G01X517126D02*
X517001Y3090D01*
X516876Y3130D01*
X516766Y3190D01*
X516666Y3270D01*
X516586Y3370D01*
X516526Y3480D01*
X516486Y3605D01*
X516476Y3730D01*
Y6160D01*
X516446Y6190D01*
X516346Y6330D01*
X516326Y6370D01*
X516311Y6405D01*
X516291Y6445D01*
X516276Y6485D01*
X516266Y6525D01*
X516251Y6570D01*
X516246Y6610D01*
X516236Y6650D01*
X516231Y6695D01*
Y6735D01*
X516226Y6780D01*
X516231Y6825D01*
Y6865D01*
X516236Y6910D01*
X516246Y6950D01*
X516251Y6990D01*
X516266Y7035D01*
X516276Y7075D01*
X516291Y7115D01*
X516311Y7155D01*
X516326Y7190D01*
X516346Y7230D01*
X516446Y7370D01*
X516476Y7400D01*
Y9530D01*
X516486Y9655D01*
X516526Y9780D01*
X516586Y9890D01*
X516666Y9990D01*
X516766Y10070D01*
X516876Y10130D01*
X517001Y10170D01*
X517126Y10180D01*
X517251Y10170D01*
X517376Y10130D01*
X517486Y10070D01*
X517586Y9990D01*
X517666Y9890D01*
X517726Y9780D01*
X517766Y9655D01*
X517776Y9530D01*
Y7405D01*
X517806Y7375D01*
X517831Y7340D01*
X517861Y7305D01*
X517881Y7270D01*
X517906Y7235D01*
X517946Y7155D01*
X517991Y7035D01*
X518001Y6995D01*
X518011Y6950D01*
X518016Y6910D01*
X518026Y6865D01*
Y6695D01*
X518016Y6650D01*
X518011Y6610D01*
X518001Y6565D01*
X517991Y6525D01*
X517946Y6405D01*
X517906Y6325D01*
X517881Y6290D01*
X517861Y6255D01*
X517831Y6220D01*
X517806Y6185D01*
X517776Y6155D01*
Y3730D01*
X517766Y3605D01*
X517726Y3480D01*
X517666Y3370D01*
X517586Y3270D01*
X517486Y3190D01*
X517376Y3130D01*
X517251Y3090D01*
X517126Y3080D01*
G37*
G36*
G01X512401D02*
X512276Y3090D01*
X512151Y3130D01*
X512041Y3190D01*
X511941Y3270D01*
X511861Y3370D01*
X511801Y3480D01*
X511761Y3605D01*
X511751Y3730D01*
Y6160D01*
X511721Y6190D01*
X511621Y6330D01*
X511601Y6370D01*
X511586Y6405D01*
X511566Y6445D01*
X511551Y6485D01*
X511541Y6525D01*
X511526Y6570D01*
X511521Y6610D01*
X511511Y6650D01*
X511506Y6695D01*
Y6735D01*
X511501Y6780D01*
X511506Y6825D01*
Y6865D01*
X511511Y6910D01*
X511521Y6950D01*
X511526Y6990D01*
X511541Y7035D01*
X511551Y7075D01*
X511566Y7115D01*
X511586Y7155D01*
X511601Y7190D01*
X511621Y7230D01*
X511721Y7370D01*
X511751Y7400D01*
Y9530D01*
X511761Y9655D01*
X511801Y9780D01*
X511861Y9890D01*
X511941Y9990D01*
X512041Y10070D01*
X512151Y10130D01*
X512276Y10170D01*
X512401Y10180D01*
X512526Y10170D01*
X512651Y10130D01*
X512761Y10070D01*
X512861Y9990D01*
X512941Y9890D01*
X513001Y9780D01*
X513041Y9655D01*
X513051Y9530D01*
Y7405D01*
X513081Y7375D01*
X513106Y7340D01*
X513136Y7305D01*
X513156Y7270D01*
X513181Y7235D01*
X513221Y7155D01*
X513266Y7035D01*
X513276Y6995D01*
X513286Y6950D01*
X513291Y6910D01*
X513301Y6865D01*
Y6695D01*
X513291Y6650D01*
X513286Y6610D01*
X513276Y6565D01*
X513266Y6525D01*
X513221Y6405D01*
X513181Y6325D01*
X513156Y6290D01*
X513136Y6255D01*
X513106Y6220D01*
X513081Y6185D01*
X513051Y6155D01*
Y3730D01*
X513041Y3605D01*
X513001Y3480D01*
X512941Y3370D01*
X512861Y3270D01*
X512761Y3190D01*
X512651Y3130D01*
X512526Y3090D01*
X512401Y3080D01*
G37*
G36*
G01X540748D02*
X540623Y3090D01*
X540498Y3130D01*
X540388Y3190D01*
X540288Y3270D01*
X540208Y3370D01*
X540148Y3480D01*
X540108Y3605D01*
X540098Y3730D01*
Y6160D01*
X540068Y6190D01*
X539968Y6330D01*
X539948Y6370D01*
X539933Y6405D01*
X539913Y6445D01*
X539898Y6485D01*
X539888Y6525D01*
X539873Y6570D01*
X539868Y6610D01*
X539858Y6650D01*
X539853Y6695D01*
Y6735D01*
X539848Y6780D01*
X539853Y6825D01*
Y6865D01*
X539858Y6910D01*
X539868Y6950D01*
X539873Y6990D01*
X539888Y7035D01*
X539898Y7075D01*
X539913Y7115D01*
X539933Y7155D01*
X539948Y7190D01*
X539968Y7230D01*
X540068Y7370D01*
X540098Y7400D01*
Y9530D01*
X540108Y9655D01*
X540148Y9780D01*
X540208Y9890D01*
X540288Y9990D01*
X540388Y10070D01*
X540498Y10130D01*
X540623Y10170D01*
X540748Y10180D01*
X540873Y10170D01*
X540998Y10130D01*
X541108Y10070D01*
X541208Y9990D01*
X541288Y9890D01*
X541348Y9780D01*
X541388Y9655D01*
X541398Y9530D01*
Y7405D01*
X541428Y7375D01*
X541453Y7340D01*
X541483Y7305D01*
X541503Y7270D01*
X541528Y7235D01*
X541568Y7155D01*
X541613Y7035D01*
X541623Y6995D01*
X541633Y6950D01*
X541638Y6910D01*
X541648Y6865D01*
Y6695D01*
X541638Y6650D01*
X541633Y6610D01*
X541623Y6565D01*
X541613Y6525D01*
X541568Y6405D01*
X541528Y6325D01*
X541503Y6290D01*
X541483Y6255D01*
X541453Y6220D01*
X541428Y6185D01*
X541398Y6155D01*
Y3730D01*
X541388Y3605D01*
X541348Y3480D01*
X541288Y3370D01*
X541208Y3270D01*
X541108Y3190D01*
X540998Y3130D01*
X540873Y3090D01*
X540748Y3080D01*
G37*
G36*
G01X536023D02*
X535898Y3090D01*
X535773Y3130D01*
X535663Y3190D01*
X535563Y3270D01*
X535483Y3370D01*
X535423Y3480D01*
X535383Y3605D01*
X535373Y3730D01*
Y6160D01*
X535343Y6190D01*
X535243Y6330D01*
X535223Y6370D01*
X535208Y6405D01*
X535188Y6445D01*
X535173Y6485D01*
X535163Y6525D01*
X535148Y6570D01*
X535143Y6610D01*
X535133Y6650D01*
X535128Y6695D01*
Y6735D01*
X535123Y6780D01*
X535128Y6825D01*
Y6865D01*
X535133Y6910D01*
X535143Y6950D01*
X535148Y6990D01*
X535163Y7035D01*
X535173Y7075D01*
X535188Y7115D01*
X535208Y7155D01*
X535223Y7190D01*
X535243Y7230D01*
X535343Y7370D01*
X535373Y7400D01*
Y9530D01*
X535383Y9655D01*
X535423Y9780D01*
X535483Y9890D01*
X535563Y9990D01*
X535663Y10070D01*
X535773Y10130D01*
X535898Y10170D01*
X536023Y10180D01*
X536148Y10170D01*
X536273Y10130D01*
X536383Y10070D01*
X536483Y9990D01*
X536563Y9890D01*
X536623Y9780D01*
X536663Y9655D01*
X536673Y9530D01*
Y7405D01*
X536703Y7375D01*
X536728Y7340D01*
X536758Y7305D01*
X536778Y7270D01*
X536803Y7235D01*
X536843Y7155D01*
X536888Y7035D01*
X536898Y6995D01*
X536908Y6950D01*
X536913Y6910D01*
X536923Y6865D01*
Y6695D01*
X536913Y6650D01*
X536908Y6610D01*
X536898Y6565D01*
X536888Y6525D01*
X536843Y6405D01*
X536803Y6325D01*
X536778Y6290D01*
X536758Y6255D01*
X536728Y6220D01*
X536703Y6185D01*
X536673Y6155D01*
Y3730D01*
X536663Y3605D01*
X536623Y3480D01*
X536563Y3370D01*
X536483Y3270D01*
X536383Y3190D01*
X536273Y3130D01*
X536148Y3090D01*
X536023Y3080D01*
G37*
G36*
G01X531299D02*
X531174Y3090D01*
X531049Y3130D01*
X530939Y3190D01*
X530839Y3270D01*
X530759Y3370D01*
X530699Y3480D01*
X530659Y3605D01*
X530649Y3730D01*
Y6160D01*
X530619Y6190D01*
X530519Y6330D01*
X530499Y6370D01*
X530484Y6405D01*
X530464Y6445D01*
X530449Y6485D01*
X530439Y6525D01*
X530424Y6570D01*
X530419Y6610D01*
X530409Y6650D01*
X530404Y6695D01*
Y6735D01*
X530399Y6780D01*
X530404Y6825D01*
Y6865D01*
X530409Y6910D01*
X530419Y6950D01*
X530424Y6990D01*
X530439Y7035D01*
X530449Y7075D01*
X530464Y7115D01*
X530484Y7155D01*
X530499Y7190D01*
X530519Y7230D01*
X530619Y7370D01*
X530649Y7400D01*
Y9530D01*
X530659Y9655D01*
X530699Y9780D01*
X530759Y9890D01*
X530839Y9990D01*
X530939Y10070D01*
X531049Y10130D01*
X531174Y10170D01*
X531299Y10180D01*
X531424Y10170D01*
X531549Y10130D01*
X531659Y10070D01*
X531759Y9990D01*
X531839Y9890D01*
X531899Y9780D01*
X531939Y9655D01*
X531949Y9530D01*
Y7405D01*
X531979Y7375D01*
X532004Y7340D01*
X532034Y7305D01*
X532054Y7270D01*
X532079Y7235D01*
X532119Y7155D01*
X532164Y7035D01*
X532174Y6995D01*
X532184Y6950D01*
X532189Y6910D01*
X532199Y6865D01*
Y6695D01*
X532189Y6650D01*
X532184Y6610D01*
X532174Y6565D01*
X532164Y6525D01*
X532119Y6405D01*
X532079Y6325D01*
X532054Y6290D01*
X532034Y6255D01*
X532004Y6220D01*
X531979Y6185D01*
X531949Y6155D01*
Y3730D01*
X531939Y3605D01*
X531899Y3480D01*
X531839Y3370D01*
X531759Y3270D01*
X531659Y3190D01*
X531549Y3130D01*
X531424Y3090D01*
X531299Y3080D01*
G37*
G36*
G01X526575D02*
X526450Y3090D01*
X526325Y3130D01*
X526215Y3190D01*
X526115Y3270D01*
X526035Y3370D01*
X525975Y3480D01*
X525935Y3605D01*
X525925Y3730D01*
Y6160D01*
X525895Y6190D01*
X525795Y6330D01*
X525775Y6370D01*
X525760Y6405D01*
X525740Y6445D01*
X525725Y6485D01*
X525715Y6525D01*
X525700Y6570D01*
X525695Y6610D01*
X525685Y6650D01*
X525680Y6695D01*
Y6735D01*
X525675Y6780D01*
X525680Y6825D01*
Y6865D01*
X525685Y6910D01*
X525695Y6950D01*
X525700Y6990D01*
X525715Y7035D01*
X525725Y7075D01*
X525740Y7115D01*
X525760Y7155D01*
X525775Y7190D01*
X525795Y7230D01*
X525895Y7370D01*
X525925Y7400D01*
Y9530D01*
X525935Y9655D01*
X525975Y9780D01*
X526035Y9890D01*
X526115Y9990D01*
X526215Y10070D01*
X526325Y10130D01*
X526450Y10170D01*
X526575Y10180D01*
X526700Y10170D01*
X526825Y10130D01*
X526935Y10070D01*
X527035Y9990D01*
X527115Y9890D01*
X527175Y9780D01*
X527215Y9655D01*
X527225Y9530D01*
Y7405D01*
X527255Y7375D01*
X527280Y7340D01*
X527310Y7305D01*
X527330Y7270D01*
X527355Y7235D01*
X527395Y7155D01*
X527440Y7035D01*
X527450Y6995D01*
X527460Y6950D01*
X527465Y6910D01*
X527475Y6865D01*
Y6695D01*
X527465Y6650D01*
X527460Y6610D01*
X527450Y6565D01*
X527440Y6525D01*
X527395Y6405D01*
X527355Y6325D01*
X527330Y6290D01*
X527310Y6255D01*
X527280Y6220D01*
X527255Y6185D01*
X527225Y6155D01*
Y3730D01*
X527215Y3605D01*
X527175Y3480D01*
X527115Y3370D01*
X527035Y3270D01*
X526935Y3190D01*
X526825Y3130D01*
X526700Y3090D01*
X526575Y3080D01*
G37*
G36*
G01X554921D02*
X554796Y3090D01*
X554671Y3130D01*
X554561Y3190D01*
X554461Y3270D01*
X554381Y3370D01*
X554321Y3480D01*
X554281Y3605D01*
X554271Y3730D01*
Y6160D01*
X554241Y6190D01*
X554141Y6330D01*
X554121Y6370D01*
X554106Y6405D01*
X554086Y6445D01*
X554071Y6485D01*
X554061Y6525D01*
X554046Y6570D01*
X554041Y6610D01*
X554031Y6650D01*
X554026Y6695D01*
Y6735D01*
X554021Y6780D01*
X554026Y6825D01*
Y6865D01*
X554031Y6910D01*
X554041Y6950D01*
X554046Y6990D01*
X554061Y7035D01*
X554071Y7075D01*
X554086Y7115D01*
X554106Y7155D01*
X554121Y7190D01*
X554141Y7230D01*
X554241Y7370D01*
X554271Y7400D01*
Y9530D01*
X554281Y9655D01*
X554321Y9780D01*
X554381Y9890D01*
X554461Y9990D01*
X554561Y10070D01*
X554671Y10130D01*
X554796Y10170D01*
X554921Y10180D01*
X555046Y10170D01*
X555171Y10130D01*
X555281Y10070D01*
X555381Y9990D01*
X555461Y9890D01*
X555521Y9780D01*
X555561Y9655D01*
X555571Y9530D01*
Y7405D01*
X555601Y7375D01*
X555626Y7340D01*
X555656Y7305D01*
X555676Y7270D01*
X555701Y7235D01*
X555741Y7155D01*
X555786Y7035D01*
X555796Y6995D01*
X555806Y6950D01*
X555811Y6910D01*
X555821Y6865D01*
Y6695D01*
X555811Y6650D01*
X555806Y6610D01*
X555796Y6565D01*
X555786Y6525D01*
X555741Y6405D01*
X555701Y6325D01*
X555676Y6290D01*
X555656Y6255D01*
X555626Y6220D01*
X555601Y6185D01*
X555571Y6155D01*
Y3730D01*
X555561Y3605D01*
X555521Y3480D01*
X555461Y3370D01*
X555381Y3270D01*
X555281Y3190D01*
X555171Y3130D01*
X555046Y3090D01*
X554921Y3080D01*
G37*
G36*
G01X550197D02*
X550072Y3090D01*
X549947Y3130D01*
X549837Y3190D01*
X549737Y3270D01*
X549657Y3370D01*
X549597Y3480D01*
X549557Y3605D01*
X549547Y3730D01*
Y6160D01*
X549517Y6190D01*
X549417Y6330D01*
X549397Y6370D01*
X549382Y6405D01*
X549362Y6445D01*
X549347Y6485D01*
X549337Y6525D01*
X549322Y6570D01*
X549317Y6610D01*
X549307Y6650D01*
X549302Y6695D01*
Y6735D01*
X549297Y6780D01*
X549302Y6825D01*
Y6865D01*
X549307Y6910D01*
X549317Y6950D01*
X549322Y6990D01*
X549337Y7035D01*
X549347Y7075D01*
X549362Y7115D01*
X549382Y7155D01*
X549397Y7190D01*
X549417Y7230D01*
X549517Y7370D01*
X549547Y7400D01*
Y9530D01*
X549557Y9655D01*
X549597Y9780D01*
X549657Y9890D01*
X549737Y9990D01*
X549837Y10070D01*
X549947Y10130D01*
X550072Y10170D01*
X550197Y10180D01*
X550322Y10170D01*
X550447Y10130D01*
X550557Y10070D01*
X550657Y9990D01*
X550737Y9890D01*
X550797Y9780D01*
X550837Y9655D01*
X550847Y9530D01*
Y7405D01*
X550877Y7375D01*
X550902Y7340D01*
X550932Y7305D01*
X550952Y7270D01*
X550977Y7235D01*
X551017Y7155D01*
X551062Y7035D01*
X551072Y6995D01*
X551082Y6950D01*
X551087Y6910D01*
X551097Y6865D01*
Y6695D01*
X551087Y6650D01*
X551082Y6610D01*
X551072Y6565D01*
X551062Y6525D01*
X551017Y6405D01*
X550977Y6325D01*
X550952Y6290D01*
X550932Y6255D01*
X550902Y6220D01*
X550877Y6185D01*
X550847Y6155D01*
Y3730D01*
X550837Y3605D01*
X550797Y3480D01*
X550737Y3370D01*
X550657Y3270D01*
X550557Y3190D01*
X550447Y3130D01*
X550322Y3090D01*
X550197Y3080D01*
G37*
G36*
G01X545472D02*
X545347Y3090D01*
X545222Y3130D01*
X545112Y3190D01*
X545012Y3270D01*
X544932Y3370D01*
X544872Y3480D01*
X544832Y3605D01*
X544822Y3730D01*
Y6160D01*
X544792Y6190D01*
X544692Y6330D01*
X544672Y6370D01*
X544657Y6405D01*
X544637Y6445D01*
X544622Y6485D01*
X544612Y6525D01*
X544597Y6570D01*
X544592Y6610D01*
X544582Y6650D01*
X544577Y6695D01*
Y6735D01*
X544572Y6780D01*
X544577Y6825D01*
Y6865D01*
X544582Y6910D01*
X544592Y6950D01*
X544597Y6990D01*
X544612Y7035D01*
X544622Y7075D01*
X544637Y7115D01*
X544657Y7155D01*
X544672Y7190D01*
X544692Y7230D01*
X544792Y7370D01*
X544822Y7400D01*
Y9530D01*
X544832Y9655D01*
X544872Y9780D01*
X544932Y9890D01*
X545012Y9990D01*
X545112Y10070D01*
X545222Y10130D01*
X545347Y10170D01*
X545472Y10180D01*
X545597Y10170D01*
X545722Y10130D01*
X545832Y10070D01*
X545932Y9990D01*
X546012Y9890D01*
X546072Y9780D01*
X546112Y9655D01*
X546122Y9530D01*
Y7405D01*
X546152Y7375D01*
X546177Y7340D01*
X546207Y7305D01*
X546227Y7270D01*
X546252Y7235D01*
X546292Y7155D01*
X546337Y7035D01*
X546347Y6995D01*
X546357Y6950D01*
X546362Y6910D01*
X546372Y6865D01*
Y6695D01*
X546362Y6650D01*
X546357Y6610D01*
X546347Y6565D01*
X546337Y6525D01*
X546292Y6405D01*
X546252Y6325D01*
X546227Y6290D01*
X546207Y6255D01*
X546177Y6220D01*
X546152Y6185D01*
X546122Y6155D01*
Y3730D01*
X546112Y3605D01*
X546072Y3480D01*
X546012Y3370D01*
X545932Y3270D01*
X545832Y3190D01*
X545722Y3130D01*
X545597Y3090D01*
X545472Y3080D01*
G37*
G36*
G01X569094D02*
X568969Y3090D01*
X568844Y3130D01*
X568734Y3190D01*
X568634Y3270D01*
X568554Y3370D01*
X568494Y3480D01*
X568454Y3605D01*
X568444Y3730D01*
Y6160D01*
X568414Y6190D01*
X568314Y6330D01*
X568294Y6370D01*
X568279Y6405D01*
X568259Y6445D01*
X568244Y6485D01*
X568234Y6525D01*
X568219Y6570D01*
X568214Y6610D01*
X568204Y6650D01*
X568199Y6695D01*
Y6735D01*
X568194Y6780D01*
X568199Y6825D01*
Y6865D01*
X568204Y6910D01*
X568214Y6950D01*
X568219Y6990D01*
X568234Y7035D01*
X568244Y7075D01*
X568259Y7115D01*
X568279Y7155D01*
X568294Y7190D01*
X568314Y7230D01*
X568414Y7370D01*
X568444Y7400D01*
Y9530D01*
X568454Y9655D01*
X568494Y9780D01*
X568554Y9890D01*
X568634Y9990D01*
X568734Y10070D01*
X568844Y10130D01*
X568969Y10170D01*
X569094Y10180D01*
X569219Y10170D01*
X569344Y10130D01*
X569454Y10070D01*
X569554Y9990D01*
X569634Y9890D01*
X569694Y9780D01*
X569734Y9655D01*
X569744Y9530D01*
Y7405D01*
X569774Y7375D01*
X569799Y7340D01*
X569829Y7305D01*
X569849Y7270D01*
X569874Y7235D01*
X569914Y7155D01*
X569959Y7035D01*
X569969Y6995D01*
X569979Y6950D01*
X569984Y6910D01*
X569994Y6865D01*
Y6695D01*
X569984Y6650D01*
X569979Y6610D01*
X569969Y6565D01*
X569959Y6525D01*
X569914Y6405D01*
X569874Y6325D01*
X569849Y6290D01*
X569829Y6255D01*
X569799Y6220D01*
X569774Y6185D01*
X569744Y6155D01*
Y3730D01*
X569734Y3605D01*
X569694Y3480D01*
X569634Y3370D01*
X569554Y3270D01*
X569454Y3190D01*
X569344Y3130D01*
X569219Y3090D01*
X569094Y3080D01*
G37*
G36*
G01X564370D02*
X564245Y3090D01*
X564120Y3130D01*
X564010Y3190D01*
X563910Y3270D01*
X563830Y3370D01*
X563770Y3480D01*
X563730Y3605D01*
X563720Y3730D01*
Y6160D01*
X563690Y6190D01*
X563590Y6330D01*
X563570Y6370D01*
X563555Y6405D01*
X563535Y6445D01*
X563520Y6485D01*
X563510Y6525D01*
X563495Y6570D01*
X563490Y6610D01*
X563480Y6650D01*
X563475Y6695D01*
Y6735D01*
X563470Y6780D01*
X563475Y6825D01*
Y6865D01*
X563480Y6910D01*
X563490Y6950D01*
X563495Y6990D01*
X563510Y7035D01*
X563520Y7075D01*
X563535Y7115D01*
X563555Y7155D01*
X563570Y7190D01*
X563590Y7230D01*
X563690Y7370D01*
X563720Y7400D01*
Y9530D01*
X563730Y9655D01*
X563770Y9780D01*
X563830Y9890D01*
X563910Y9990D01*
X564010Y10070D01*
X564120Y10130D01*
X564245Y10170D01*
X564370Y10180D01*
X564495Y10170D01*
X564620Y10130D01*
X564730Y10070D01*
X564830Y9990D01*
X564910Y9890D01*
X564970Y9780D01*
X565010Y9655D01*
X565020Y9530D01*
Y7405D01*
X565050Y7375D01*
X565075Y7340D01*
X565105Y7305D01*
X565125Y7270D01*
X565150Y7235D01*
X565190Y7155D01*
X565235Y7035D01*
X565245Y6995D01*
X565255Y6950D01*
X565260Y6910D01*
X565270Y6865D01*
Y6695D01*
X565260Y6650D01*
X565255Y6610D01*
X565245Y6565D01*
X565235Y6525D01*
X565190Y6405D01*
X565150Y6325D01*
X565125Y6290D01*
X565105Y6255D01*
X565075Y6220D01*
X565050Y6185D01*
X565020Y6155D01*
Y3730D01*
X565010Y3605D01*
X564970Y3480D01*
X564910Y3370D01*
X564830Y3270D01*
X564730Y3190D01*
X564620Y3130D01*
X564495Y3090D01*
X564370Y3080D01*
G37*
G36*
G01X559645D02*
X559520Y3090D01*
X559395Y3130D01*
X559285Y3190D01*
X559185Y3270D01*
X559105Y3370D01*
X559045Y3480D01*
X559005Y3605D01*
X558995Y3730D01*
Y6160D01*
X558965Y6190D01*
X558865Y6330D01*
X558845Y6370D01*
X558830Y6405D01*
X558810Y6445D01*
X558795Y6485D01*
X558785Y6525D01*
X558770Y6570D01*
X558765Y6610D01*
X558755Y6650D01*
X558750Y6695D01*
Y6735D01*
X558745Y6780D01*
X558750Y6825D01*
Y6865D01*
X558755Y6910D01*
X558765Y6950D01*
X558770Y6990D01*
X558785Y7035D01*
X558795Y7075D01*
X558810Y7115D01*
X558830Y7155D01*
X558845Y7190D01*
X558865Y7230D01*
X558965Y7370D01*
X558995Y7400D01*
Y9530D01*
X559005Y9655D01*
X559045Y9780D01*
X559105Y9890D01*
X559185Y9990D01*
X559285Y10070D01*
X559395Y10130D01*
X559520Y10170D01*
X559645Y10180D01*
X559770Y10170D01*
X559895Y10130D01*
X560005Y10070D01*
X560105Y9990D01*
X560185Y9890D01*
X560245Y9780D01*
X560285Y9655D01*
X560295Y9530D01*
Y7405D01*
X560325Y7375D01*
X560350Y7340D01*
X560380Y7305D01*
X560400Y7270D01*
X560425Y7235D01*
X560465Y7155D01*
X560510Y7035D01*
X560520Y6995D01*
X560530Y6950D01*
X560535Y6910D01*
X560545Y6865D01*
Y6695D01*
X560535Y6650D01*
X560530Y6610D01*
X560520Y6565D01*
X560510Y6525D01*
X560465Y6405D01*
X560425Y6325D01*
X560400Y6290D01*
X560380Y6255D01*
X560350Y6220D01*
X560325Y6185D01*
X560295Y6155D01*
Y3730D01*
X560285Y3605D01*
X560245Y3480D01*
X560185Y3370D01*
X560105Y3270D01*
X560005Y3190D01*
X559895Y3130D01*
X559770Y3090D01*
X559645Y3080D01*
G37*
G36*
G01X587992D02*
X587867Y3090D01*
X587742Y3130D01*
X587632Y3190D01*
X587532Y3270D01*
X587452Y3370D01*
X587392Y3480D01*
X587352Y3605D01*
X587342Y3730D01*
Y6160D01*
X587312Y6190D01*
X587212Y6330D01*
X587192Y6370D01*
X587177Y6405D01*
X587157Y6445D01*
X587142Y6485D01*
X587132Y6525D01*
X587117Y6570D01*
X587112Y6610D01*
X587102Y6650D01*
X587097Y6695D01*
Y6735D01*
X587092Y6780D01*
X587097Y6825D01*
Y6865D01*
X587102Y6910D01*
X587112Y6950D01*
X587117Y6990D01*
X587132Y7035D01*
X587142Y7075D01*
X587157Y7115D01*
X587177Y7155D01*
X587192Y7190D01*
X587212Y7230D01*
X587312Y7370D01*
X587342Y7400D01*
Y9530D01*
X587352Y9655D01*
X587392Y9780D01*
X587452Y9890D01*
X587532Y9990D01*
X587632Y10070D01*
X587742Y10130D01*
X587867Y10170D01*
X587992Y10180D01*
X588117Y10170D01*
X588242Y10130D01*
X588352Y10070D01*
X588452Y9990D01*
X588532Y9890D01*
X588592Y9780D01*
X588632Y9655D01*
X588642Y9530D01*
Y7405D01*
X588672Y7375D01*
X588697Y7340D01*
X588727Y7305D01*
X588747Y7270D01*
X588772Y7235D01*
X588812Y7155D01*
X588857Y7035D01*
X588867Y6995D01*
X588877Y6950D01*
X588882Y6910D01*
X588892Y6865D01*
Y6695D01*
X588882Y6650D01*
X588877Y6610D01*
X588867Y6565D01*
X588857Y6525D01*
X588812Y6405D01*
X588772Y6325D01*
X588747Y6290D01*
X588727Y6255D01*
X588697Y6220D01*
X588672Y6185D01*
X588642Y6155D01*
Y3730D01*
X588632Y3605D01*
X588592Y3480D01*
X588532Y3370D01*
X588452Y3270D01*
X588352Y3190D01*
X588242Y3130D01*
X588117Y3090D01*
X587992Y3080D01*
G37*
G36*
G01X583267D02*
X583142Y3090D01*
X583017Y3130D01*
X582907Y3190D01*
X582807Y3270D01*
X582727Y3370D01*
X582667Y3480D01*
X582627Y3605D01*
X582617Y3730D01*
Y6160D01*
X582587Y6190D01*
X582487Y6330D01*
X582467Y6370D01*
X582452Y6405D01*
X582432Y6445D01*
X582417Y6485D01*
X582407Y6525D01*
X582392Y6570D01*
X582387Y6610D01*
X582377Y6650D01*
X582372Y6695D01*
Y6735D01*
X582367Y6780D01*
X582372Y6825D01*
Y6865D01*
X582377Y6910D01*
X582387Y6950D01*
X582392Y6990D01*
X582407Y7035D01*
X582417Y7075D01*
X582432Y7115D01*
X582452Y7155D01*
X582467Y7190D01*
X582487Y7230D01*
X582587Y7370D01*
X582617Y7400D01*
Y9530D01*
X582627Y9655D01*
X582667Y9780D01*
X582727Y9890D01*
X582807Y9990D01*
X582907Y10070D01*
X583017Y10130D01*
X583142Y10170D01*
X583267Y10180D01*
X583392Y10170D01*
X583517Y10130D01*
X583627Y10070D01*
X583727Y9990D01*
X583807Y9890D01*
X583867Y9780D01*
X583907Y9655D01*
X583917Y9530D01*
Y7405D01*
X583947Y7375D01*
X583972Y7340D01*
X584002Y7305D01*
X584022Y7270D01*
X584047Y7235D01*
X584087Y7155D01*
X584132Y7035D01*
X584142Y6995D01*
X584152Y6950D01*
X584157Y6910D01*
X584167Y6865D01*
Y6695D01*
X584157Y6650D01*
X584152Y6610D01*
X584142Y6565D01*
X584132Y6525D01*
X584087Y6405D01*
X584047Y6325D01*
X584022Y6290D01*
X584002Y6255D01*
X583972Y6220D01*
X583947Y6185D01*
X583917Y6155D01*
Y3730D01*
X583907Y3605D01*
X583867Y3480D01*
X583807Y3370D01*
X583727Y3270D01*
X583627Y3190D01*
X583517Y3130D01*
X583392Y3090D01*
X583267Y3080D01*
G37*
G36*
G01X578543D02*
X578418Y3090D01*
X578293Y3130D01*
X578183Y3190D01*
X578083Y3270D01*
X578003Y3370D01*
X577943Y3480D01*
X577903Y3605D01*
X577893Y3730D01*
Y6160D01*
X577863Y6190D01*
X577763Y6330D01*
X577743Y6370D01*
X577728Y6405D01*
X577708Y6445D01*
X577693Y6485D01*
X577683Y6525D01*
X577668Y6570D01*
X577663Y6610D01*
X577653Y6650D01*
X577648Y6695D01*
Y6735D01*
X577643Y6780D01*
X577648Y6825D01*
Y6865D01*
X577653Y6910D01*
X577663Y6950D01*
X577668Y6990D01*
X577683Y7035D01*
X577693Y7075D01*
X577708Y7115D01*
X577728Y7155D01*
X577743Y7190D01*
X577763Y7230D01*
X577863Y7370D01*
X577893Y7400D01*
Y9530D01*
X577903Y9655D01*
X577943Y9780D01*
X578003Y9890D01*
X578083Y9990D01*
X578183Y10070D01*
X578293Y10130D01*
X578418Y10170D01*
X578543Y10180D01*
X578668Y10170D01*
X578793Y10130D01*
X578903Y10070D01*
X579003Y9990D01*
X579083Y9890D01*
X579143Y9780D01*
X579183Y9655D01*
X579193Y9530D01*
Y7405D01*
X579223Y7375D01*
X579248Y7340D01*
X579278Y7305D01*
X579298Y7270D01*
X579323Y7235D01*
X579363Y7155D01*
X579408Y7035D01*
X579418Y6995D01*
X579428Y6950D01*
X579433Y6910D01*
X579443Y6865D01*
Y6695D01*
X579433Y6650D01*
X579428Y6610D01*
X579418Y6565D01*
X579408Y6525D01*
X579363Y6405D01*
X579323Y6325D01*
X579298Y6290D01*
X579278Y6255D01*
X579248Y6220D01*
X579223Y6185D01*
X579193Y6155D01*
Y3730D01*
X579183Y3605D01*
X579143Y3480D01*
X579083Y3370D01*
X579003Y3270D01*
X578903Y3190D01*
X578793Y3130D01*
X578668Y3090D01*
X578543Y3080D01*
G37*
G36*
G01X573819D02*
X573694Y3090D01*
X573569Y3130D01*
X573459Y3190D01*
X573359Y3270D01*
X573279Y3370D01*
X573219Y3480D01*
X573179Y3605D01*
X573169Y3730D01*
Y6160D01*
X573139Y6190D01*
X573039Y6330D01*
X573019Y6370D01*
X573004Y6405D01*
X572984Y6445D01*
X572969Y6485D01*
X572959Y6525D01*
X572944Y6570D01*
X572939Y6610D01*
X572929Y6650D01*
X572924Y6695D01*
Y6735D01*
X572919Y6780D01*
X572924Y6825D01*
Y6865D01*
X572929Y6910D01*
X572939Y6950D01*
X572944Y6990D01*
X572959Y7035D01*
X572969Y7075D01*
X572984Y7115D01*
X573004Y7155D01*
X573019Y7190D01*
X573039Y7230D01*
X573139Y7370D01*
X573169Y7400D01*
Y9530D01*
X573179Y9655D01*
X573219Y9780D01*
X573279Y9890D01*
X573359Y9990D01*
X573459Y10070D01*
X573569Y10130D01*
X573694Y10170D01*
X573819Y10180D01*
X573944Y10170D01*
X574069Y10130D01*
X574179Y10070D01*
X574279Y9990D01*
X574359Y9890D01*
X574419Y9780D01*
X574459Y9655D01*
X574469Y9530D01*
Y7405D01*
X574499Y7375D01*
X574524Y7340D01*
X574554Y7305D01*
X574574Y7270D01*
X574599Y7235D01*
X574639Y7155D01*
X574684Y7035D01*
X574694Y6995D01*
X574704Y6950D01*
X574709Y6910D01*
X574719Y6865D01*
Y6695D01*
X574709Y6650D01*
X574704Y6610D01*
X574694Y6565D01*
X574684Y6525D01*
X574639Y6405D01*
X574599Y6325D01*
X574574Y6290D01*
X574554Y6255D01*
X574524Y6220D01*
X574499Y6185D01*
X574469Y6155D01*
Y3730D01*
X574459Y3605D01*
X574419Y3480D01*
X574359Y3370D01*
X574279Y3270D01*
X574179Y3190D01*
X574069Y3130D01*
X573944Y3090D01*
X573819Y3080D01*
G37*
G36*
G01X602165D02*
X602040Y3090D01*
X601915Y3130D01*
X601805Y3190D01*
X601705Y3270D01*
X601625Y3370D01*
X601565Y3480D01*
X601525Y3605D01*
X601515Y3730D01*
Y6160D01*
X601485Y6190D01*
X601385Y6330D01*
X601365Y6370D01*
X601350Y6405D01*
X601330Y6445D01*
X601315Y6485D01*
X601305Y6525D01*
X601290Y6570D01*
X601285Y6610D01*
X601275Y6650D01*
X601270Y6695D01*
Y6735D01*
X601265Y6780D01*
X601270Y6825D01*
Y6865D01*
X601275Y6910D01*
X601285Y6950D01*
X601290Y6990D01*
X601305Y7035D01*
X601315Y7075D01*
X601330Y7115D01*
X601350Y7155D01*
X601365Y7190D01*
X601385Y7230D01*
X601485Y7370D01*
X601515Y7400D01*
Y9530D01*
X601525Y9655D01*
X601565Y9780D01*
X601625Y9890D01*
X601705Y9990D01*
X601805Y10070D01*
X601915Y10130D01*
X602040Y10170D01*
X602165Y10180D01*
X602290Y10170D01*
X602415Y10130D01*
X602525Y10070D01*
X602625Y9990D01*
X602705Y9890D01*
X602765Y9780D01*
X602805Y9655D01*
X602815Y9530D01*
Y7405D01*
X602845Y7375D01*
X602870Y7340D01*
X602900Y7305D01*
X602920Y7270D01*
X602945Y7235D01*
X602985Y7155D01*
X603030Y7035D01*
X603040Y6995D01*
X603050Y6950D01*
X603055Y6910D01*
X603065Y6865D01*
Y6695D01*
X603055Y6650D01*
X603050Y6610D01*
X603040Y6565D01*
X603030Y6525D01*
X602985Y6405D01*
X602945Y6325D01*
X602920Y6290D01*
X602900Y6255D01*
X602870Y6220D01*
X602845Y6185D01*
X602815Y6155D01*
Y3730D01*
X602805Y3605D01*
X602765Y3480D01*
X602705Y3370D01*
X602625Y3270D01*
X602525Y3190D01*
X602415Y3130D01*
X602290Y3090D01*
X602165Y3080D01*
G37*
G36*
G01X616338D02*
X616213Y3090D01*
X616088Y3130D01*
X615978Y3190D01*
X615878Y3270D01*
X615798Y3370D01*
X615738Y3480D01*
X615698Y3605D01*
X615688Y3730D01*
Y6160D01*
X615658Y6190D01*
X615558Y6330D01*
X615538Y6370D01*
X615523Y6405D01*
X615503Y6445D01*
X615488Y6485D01*
X615478Y6525D01*
X615463Y6570D01*
X615458Y6610D01*
X615448Y6650D01*
X615443Y6695D01*
Y6735D01*
X615438Y6780D01*
X615443Y6825D01*
Y6865D01*
X615448Y6910D01*
X615458Y6950D01*
X615463Y6990D01*
X615478Y7035D01*
X615488Y7075D01*
X615503Y7115D01*
X615523Y7155D01*
X615538Y7190D01*
X615558Y7230D01*
X615658Y7370D01*
X615688Y7400D01*
Y9530D01*
X615698Y9655D01*
X615738Y9780D01*
X615798Y9890D01*
X615878Y9990D01*
X615978Y10070D01*
X616088Y10130D01*
X616213Y10170D01*
X616338Y10180D01*
X616463Y10170D01*
X616588Y10130D01*
X616698Y10070D01*
X616798Y9990D01*
X616878Y9890D01*
X616938Y9780D01*
X616978Y9655D01*
X616988Y9530D01*
Y7405D01*
X617018Y7375D01*
X617043Y7340D01*
X617073Y7305D01*
X617093Y7270D01*
X617118Y7235D01*
X617158Y7155D01*
X617203Y7035D01*
X617213Y6995D01*
X617223Y6950D01*
X617228Y6910D01*
X617238Y6865D01*
Y6695D01*
X617228Y6650D01*
X617223Y6610D01*
X617213Y6565D01*
X617203Y6525D01*
X617158Y6405D01*
X617118Y6325D01*
X617093Y6290D01*
X617073Y6255D01*
X617043Y6220D01*
X617018Y6185D01*
X616988Y6155D01*
Y3730D01*
X616978Y3605D01*
X616938Y3480D01*
X616878Y3370D01*
X616798Y3270D01*
X616698Y3190D01*
X616588Y3130D01*
X616463Y3090D01*
X616338Y3080D01*
G37*
G36*
G01X611614D02*
X611489Y3090D01*
X611364Y3130D01*
X611254Y3190D01*
X611154Y3270D01*
X611074Y3370D01*
X611014Y3480D01*
X610974Y3605D01*
X610964Y3730D01*
Y6160D01*
X610934Y6190D01*
X610834Y6330D01*
X610814Y6370D01*
X610799Y6405D01*
X610779Y6445D01*
X610764Y6485D01*
X610754Y6525D01*
X610739Y6570D01*
X610734Y6610D01*
X610724Y6650D01*
X610719Y6695D01*
Y6735D01*
X610714Y6780D01*
X610719Y6825D01*
Y6865D01*
X610724Y6910D01*
X610734Y6950D01*
X610739Y6990D01*
X610754Y7035D01*
X610764Y7075D01*
X610779Y7115D01*
X610799Y7155D01*
X610814Y7190D01*
X610834Y7230D01*
X610934Y7370D01*
X610964Y7400D01*
Y9530D01*
X610974Y9655D01*
X611014Y9780D01*
X611074Y9890D01*
X611154Y9990D01*
X611254Y10070D01*
X611364Y10130D01*
X611489Y10170D01*
X611614Y10180D01*
X611739Y10170D01*
X611864Y10130D01*
X611974Y10070D01*
X612074Y9990D01*
X612154Y9890D01*
X612214Y9780D01*
X612254Y9655D01*
X612264Y9530D01*
Y7405D01*
X612294Y7375D01*
X612319Y7340D01*
X612349Y7305D01*
X612369Y7270D01*
X612394Y7235D01*
X612434Y7155D01*
X612479Y7035D01*
X612489Y6995D01*
X612499Y6950D01*
X612504Y6910D01*
X612514Y6865D01*
Y6695D01*
X612504Y6650D01*
X612499Y6610D01*
X612489Y6565D01*
X612479Y6525D01*
X612434Y6405D01*
X612394Y6325D01*
X612369Y6290D01*
X612349Y6255D01*
X612319Y6220D01*
X612294Y6185D01*
X612264Y6155D01*
Y3730D01*
X612254Y3605D01*
X612214Y3480D01*
X612154Y3370D01*
X612074Y3270D01*
X611974Y3190D01*
X611864Y3130D01*
X611739Y3090D01*
X611614Y3080D01*
G37*
G36*
G01X606890D02*
X606765Y3090D01*
X606640Y3130D01*
X606530Y3190D01*
X606430Y3270D01*
X606350Y3370D01*
X606290Y3480D01*
X606250Y3605D01*
X606240Y3730D01*
Y6160D01*
X606210Y6190D01*
X606110Y6330D01*
X606090Y6370D01*
X606075Y6405D01*
X606055Y6445D01*
X606040Y6485D01*
X606030Y6525D01*
X606015Y6570D01*
X606010Y6610D01*
X606000Y6650D01*
X605995Y6695D01*
Y6735D01*
X605990Y6780D01*
X605995Y6825D01*
Y6865D01*
X606000Y6910D01*
X606010Y6950D01*
X606015Y6990D01*
X606030Y7035D01*
X606040Y7075D01*
X606055Y7115D01*
X606075Y7155D01*
X606090Y7190D01*
X606110Y7230D01*
X606210Y7370D01*
X606240Y7400D01*
Y9530D01*
X606250Y9655D01*
X606290Y9780D01*
X606350Y9890D01*
X606430Y9990D01*
X606530Y10070D01*
X606640Y10130D01*
X606765Y10170D01*
X606890Y10180D01*
X607015Y10170D01*
X607140Y10130D01*
X607250Y10070D01*
X607350Y9990D01*
X607430Y9890D01*
X607490Y9780D01*
X607530Y9655D01*
X607540Y9530D01*
Y7405D01*
X607570Y7375D01*
X607595Y7340D01*
X607625Y7305D01*
X607645Y7270D01*
X607670Y7235D01*
X607710Y7155D01*
X607755Y7035D01*
X607765Y6995D01*
X607775Y6950D01*
X607780Y6910D01*
X607790Y6865D01*
Y6695D01*
X607780Y6650D01*
X607775Y6610D01*
X607765Y6565D01*
X607755Y6525D01*
X607710Y6405D01*
X607670Y6325D01*
X607645Y6290D01*
X607625Y6255D01*
X607595Y6220D01*
X607570Y6185D01*
X607540Y6155D01*
Y3730D01*
X607530Y3605D01*
X607490Y3480D01*
X607430Y3370D01*
X607350Y3270D01*
X607250Y3190D01*
X607140Y3130D01*
X607015Y3090D01*
X606890Y3080D01*
G37*
G36*
G01X630512D02*
X630387Y3090D01*
X630262Y3130D01*
X630152Y3190D01*
X630052Y3270D01*
X629972Y3370D01*
X629912Y3480D01*
X629872Y3605D01*
X629862Y3730D01*
Y6160D01*
X629832Y6190D01*
X629732Y6330D01*
X629712Y6370D01*
X629697Y6405D01*
X629677Y6445D01*
X629662Y6485D01*
X629652Y6525D01*
X629637Y6570D01*
X629632Y6610D01*
X629622Y6650D01*
X629617Y6695D01*
Y6735D01*
X629612Y6780D01*
X629617Y6825D01*
Y6865D01*
X629622Y6910D01*
X629632Y6950D01*
X629637Y6990D01*
X629652Y7035D01*
X629662Y7075D01*
X629677Y7115D01*
X629697Y7155D01*
X629712Y7190D01*
X629732Y7230D01*
X629832Y7370D01*
X629862Y7400D01*
Y9530D01*
X629872Y9655D01*
X629912Y9780D01*
X629972Y9890D01*
X630052Y9990D01*
X630152Y10070D01*
X630262Y10130D01*
X630387Y10170D01*
X630512Y10180D01*
X630637Y10170D01*
X630762Y10130D01*
X630872Y10070D01*
X630972Y9990D01*
X631052Y9890D01*
X631112Y9780D01*
X631152Y9655D01*
X631162Y9530D01*
Y7405D01*
X631192Y7375D01*
X631217Y7340D01*
X631247Y7305D01*
X631267Y7270D01*
X631292Y7235D01*
X631332Y7155D01*
X631377Y7035D01*
X631387Y6995D01*
X631397Y6950D01*
X631402Y6910D01*
X631412Y6865D01*
Y6695D01*
X631402Y6650D01*
X631397Y6610D01*
X631387Y6565D01*
X631377Y6525D01*
X631332Y6405D01*
X631292Y6325D01*
X631267Y6290D01*
X631247Y6255D01*
X631217Y6220D01*
X631192Y6185D01*
X631162Y6155D01*
Y3730D01*
X631152Y3605D01*
X631112Y3480D01*
X631052Y3370D01*
X630972Y3270D01*
X630872Y3190D01*
X630762Y3130D01*
X630637Y3090D01*
X630512Y3080D01*
G37*
G36*
G01X625787D02*
X625662Y3090D01*
X625537Y3130D01*
X625427Y3190D01*
X625327Y3270D01*
X625247Y3370D01*
X625187Y3480D01*
X625147Y3605D01*
X625137Y3730D01*
Y6160D01*
X625107Y6190D01*
X625007Y6330D01*
X624987Y6370D01*
X624972Y6405D01*
X624952Y6445D01*
X624937Y6485D01*
X624927Y6525D01*
X624912Y6570D01*
X624907Y6610D01*
X624897Y6650D01*
X624892Y6695D01*
Y6735D01*
X624887Y6780D01*
X624892Y6825D01*
Y6865D01*
X624897Y6910D01*
X624907Y6950D01*
X624912Y6990D01*
X624927Y7035D01*
X624937Y7075D01*
X624952Y7115D01*
X624972Y7155D01*
X624987Y7190D01*
X625007Y7230D01*
X625107Y7370D01*
X625137Y7400D01*
Y9530D01*
X625147Y9655D01*
X625187Y9780D01*
X625247Y9890D01*
X625327Y9990D01*
X625427Y10070D01*
X625537Y10130D01*
X625662Y10170D01*
X625787Y10180D01*
X625912Y10170D01*
X626037Y10130D01*
X626147Y10070D01*
X626247Y9990D01*
X626327Y9890D01*
X626387Y9780D01*
X626427Y9655D01*
X626437Y9530D01*
Y7405D01*
X626467Y7375D01*
X626492Y7340D01*
X626522Y7305D01*
X626542Y7270D01*
X626567Y7235D01*
X626607Y7155D01*
X626652Y7035D01*
X626662Y6995D01*
X626672Y6950D01*
X626677Y6910D01*
X626687Y6865D01*
Y6695D01*
X626677Y6650D01*
X626672Y6610D01*
X626662Y6565D01*
X626652Y6525D01*
X626607Y6405D01*
X626567Y6325D01*
X626542Y6290D01*
X626522Y6255D01*
X626492Y6220D01*
X626467Y6185D01*
X626437Y6155D01*
Y3730D01*
X626427Y3605D01*
X626387Y3480D01*
X626327Y3370D01*
X626247Y3270D01*
X626147Y3190D01*
X626037Y3130D01*
X625912Y3090D01*
X625787Y3080D01*
G37*
G36*
G01X621063D02*
X620938Y3090D01*
X620813Y3130D01*
X620703Y3190D01*
X620603Y3270D01*
X620523Y3370D01*
X620463Y3480D01*
X620423Y3605D01*
X620413Y3730D01*
Y6160D01*
X620383Y6190D01*
X620283Y6330D01*
X620263Y6370D01*
X620248Y6405D01*
X620228Y6445D01*
X620213Y6485D01*
X620203Y6525D01*
X620188Y6570D01*
X620183Y6610D01*
X620173Y6650D01*
X620168Y6695D01*
Y6735D01*
X620163Y6780D01*
X620168Y6825D01*
Y6865D01*
X620173Y6910D01*
X620183Y6950D01*
X620188Y6990D01*
X620203Y7035D01*
X620213Y7075D01*
X620228Y7115D01*
X620248Y7155D01*
X620263Y7190D01*
X620283Y7230D01*
X620383Y7370D01*
X620413Y7400D01*
Y9530D01*
X620423Y9655D01*
X620463Y9780D01*
X620523Y9890D01*
X620603Y9990D01*
X620703Y10070D01*
X620813Y10130D01*
X620938Y10170D01*
X621063Y10180D01*
X621188Y10170D01*
X621313Y10130D01*
X621423Y10070D01*
X621523Y9990D01*
X621603Y9890D01*
X621663Y9780D01*
X621703Y9655D01*
X621713Y9530D01*
Y7405D01*
X621743Y7375D01*
X621768Y7340D01*
X621798Y7305D01*
X621818Y7270D01*
X621843Y7235D01*
X621883Y7155D01*
X621928Y7035D01*
X621938Y6995D01*
X621948Y6950D01*
X621953Y6910D01*
X621963Y6865D01*
Y6695D01*
X621953Y6650D01*
X621948Y6610D01*
X621938Y6565D01*
X621928Y6525D01*
X621883Y6405D01*
X621843Y6325D01*
X621818Y6290D01*
X621798Y6255D01*
X621768Y6220D01*
X621743Y6185D01*
X621713Y6155D01*
Y3730D01*
X621703Y3605D01*
X621663Y3480D01*
X621603Y3370D01*
X621523Y3270D01*
X621423Y3190D01*
X621313Y3130D01*
X621188Y3090D01*
X621063Y3080D01*
G37*
G36*
G01X649409D02*
X649284Y3090D01*
X649159Y3130D01*
X649049Y3190D01*
X648949Y3270D01*
X648869Y3370D01*
X648809Y3480D01*
X648769Y3605D01*
X648759Y3730D01*
Y6160D01*
X648729Y6190D01*
X648629Y6330D01*
X648609Y6370D01*
X648594Y6405D01*
X648574Y6445D01*
X648559Y6485D01*
X648549Y6525D01*
X648534Y6570D01*
X648529Y6610D01*
X648519Y6650D01*
X648514Y6695D01*
Y6735D01*
X648509Y6780D01*
X648514Y6825D01*
Y6865D01*
X648519Y6910D01*
X648529Y6950D01*
X648534Y6990D01*
X648549Y7035D01*
X648559Y7075D01*
X648574Y7115D01*
X648594Y7155D01*
X648609Y7190D01*
X648629Y7230D01*
X648729Y7370D01*
X648759Y7400D01*
Y9530D01*
X648769Y9655D01*
X648809Y9780D01*
X648869Y9890D01*
X648949Y9990D01*
X649049Y10070D01*
X649159Y10130D01*
X649284Y10170D01*
X649409Y10180D01*
X649534Y10170D01*
X649659Y10130D01*
X649769Y10070D01*
X649869Y9990D01*
X649949Y9890D01*
X650009Y9780D01*
X650049Y9655D01*
X650059Y9530D01*
Y7405D01*
X650089Y7375D01*
X650114Y7340D01*
X650144Y7305D01*
X650164Y7270D01*
X650189Y7235D01*
X650229Y7155D01*
X650274Y7035D01*
X650284Y6995D01*
X650294Y6950D01*
X650299Y6910D01*
X650309Y6865D01*
Y6695D01*
X650299Y6650D01*
X650294Y6610D01*
X650284Y6565D01*
X650274Y6525D01*
X650229Y6405D01*
X650189Y6325D01*
X650164Y6290D01*
X650144Y6255D01*
X650114Y6220D01*
X650089Y6185D01*
X650059Y6155D01*
Y3730D01*
X650049Y3605D01*
X650009Y3480D01*
X649949Y3370D01*
X649869Y3270D01*
X649769Y3190D01*
X649659Y3130D01*
X649534Y3090D01*
X649409Y3080D01*
G37*
G36*
G01X644685D02*
X644560Y3090D01*
X644435Y3130D01*
X644325Y3190D01*
X644225Y3270D01*
X644145Y3370D01*
X644085Y3480D01*
X644045Y3605D01*
X644035Y3730D01*
Y6160D01*
X644005Y6190D01*
X643905Y6330D01*
X643885Y6370D01*
X643870Y6405D01*
X643850Y6445D01*
X643835Y6485D01*
X643825Y6525D01*
X643810Y6570D01*
X643805Y6610D01*
X643795Y6650D01*
X643790Y6695D01*
Y6735D01*
X643785Y6780D01*
X643790Y6825D01*
Y6865D01*
X643795Y6910D01*
X643805Y6950D01*
X643810Y6990D01*
X643825Y7035D01*
X643835Y7075D01*
X643850Y7115D01*
X643870Y7155D01*
X643885Y7190D01*
X643905Y7230D01*
X644005Y7370D01*
X644035Y7400D01*
Y9530D01*
X644045Y9655D01*
X644085Y9780D01*
X644145Y9890D01*
X644225Y9990D01*
X644325Y10070D01*
X644435Y10130D01*
X644560Y10170D01*
X644685Y10180D01*
X644810Y10170D01*
X644935Y10130D01*
X645045Y10070D01*
X645145Y9990D01*
X645225Y9890D01*
X645285Y9780D01*
X645325Y9655D01*
X645335Y9530D01*
Y7405D01*
X645365Y7375D01*
X645390Y7340D01*
X645420Y7305D01*
X645440Y7270D01*
X645465Y7235D01*
X645505Y7155D01*
X645550Y7035D01*
X645560Y6995D01*
X645570Y6950D01*
X645575Y6910D01*
X645585Y6865D01*
Y6695D01*
X645575Y6650D01*
X645570Y6610D01*
X645560Y6565D01*
X645550Y6525D01*
X645505Y6405D01*
X645465Y6325D01*
X645440Y6290D01*
X645420Y6255D01*
X645390Y6220D01*
X645365Y6185D01*
X645335Y6155D01*
Y3730D01*
X645325Y3605D01*
X645285Y3480D01*
X645225Y3370D01*
X645145Y3270D01*
X645045Y3190D01*
X644935Y3130D01*
X644810Y3090D01*
X644685Y3080D01*
G37*
G36*
G01X639960D02*
X639835Y3090D01*
X639710Y3130D01*
X639600Y3190D01*
X639500Y3270D01*
X639420Y3370D01*
X639360Y3480D01*
X639320Y3605D01*
X639310Y3730D01*
Y6160D01*
X639280Y6190D01*
X639180Y6330D01*
X639160Y6370D01*
X639145Y6405D01*
X639125Y6445D01*
X639110Y6485D01*
X639100Y6525D01*
X639085Y6570D01*
X639080Y6610D01*
X639070Y6650D01*
X639065Y6695D01*
Y6735D01*
X639060Y6780D01*
X639065Y6825D01*
Y6865D01*
X639070Y6910D01*
X639080Y6950D01*
X639085Y6990D01*
X639100Y7035D01*
X639110Y7075D01*
X639125Y7115D01*
X639145Y7155D01*
X639160Y7190D01*
X639180Y7230D01*
X639280Y7370D01*
X639310Y7400D01*
Y9530D01*
X639320Y9655D01*
X639360Y9780D01*
X639420Y9890D01*
X639500Y9990D01*
X639600Y10070D01*
X639710Y10130D01*
X639835Y10170D01*
X639960Y10180D01*
X640085Y10170D01*
X640210Y10130D01*
X640320Y10070D01*
X640420Y9990D01*
X640500Y9890D01*
X640560Y9780D01*
X640600Y9655D01*
X640610Y9530D01*
Y7405D01*
X640640Y7375D01*
X640665Y7340D01*
X640695Y7305D01*
X640715Y7270D01*
X640740Y7235D01*
X640780Y7155D01*
X640825Y7035D01*
X640835Y6995D01*
X640845Y6950D01*
X640850Y6910D01*
X640860Y6865D01*
Y6695D01*
X640850Y6650D01*
X640845Y6610D01*
X640835Y6565D01*
X640825Y6525D01*
X640780Y6405D01*
X640740Y6325D01*
X640715Y6290D01*
X640695Y6255D01*
X640665Y6220D01*
X640640Y6185D01*
X640610Y6155D01*
Y3730D01*
X640600Y3605D01*
X640560Y3480D01*
X640500Y3370D01*
X640420Y3270D01*
X640320Y3190D01*
X640210Y3130D01*
X640085Y3090D01*
X639960Y3080D01*
G37*
G36*
G01X635236D02*
X635111Y3090D01*
X634986Y3130D01*
X634876Y3190D01*
X634776Y3270D01*
X634696Y3370D01*
X634636Y3480D01*
X634596Y3605D01*
X634586Y3730D01*
Y6160D01*
X634556Y6190D01*
X634456Y6330D01*
X634436Y6370D01*
X634421Y6405D01*
X634401Y6445D01*
X634386Y6485D01*
X634376Y6525D01*
X634361Y6570D01*
X634356Y6610D01*
X634346Y6650D01*
X634341Y6695D01*
Y6735D01*
X634336Y6780D01*
X634341Y6825D01*
Y6865D01*
X634346Y6910D01*
X634356Y6950D01*
X634361Y6990D01*
X634376Y7035D01*
X634386Y7075D01*
X634401Y7115D01*
X634421Y7155D01*
X634436Y7190D01*
X634456Y7230D01*
X634556Y7370D01*
X634586Y7400D01*
Y9530D01*
X634596Y9655D01*
X634636Y9780D01*
X634696Y9890D01*
X634776Y9990D01*
X634876Y10070D01*
X634986Y10130D01*
X635111Y10170D01*
X635236Y10180D01*
X635361Y10170D01*
X635486Y10130D01*
X635596Y10070D01*
X635696Y9990D01*
X635776Y9890D01*
X635836Y9780D01*
X635876Y9655D01*
X635886Y9530D01*
Y7405D01*
X635916Y7375D01*
X635941Y7340D01*
X635971Y7305D01*
X635991Y7270D01*
X636016Y7235D01*
X636056Y7155D01*
X636101Y7035D01*
X636111Y6995D01*
X636121Y6950D01*
X636126Y6910D01*
X636136Y6865D01*
Y6695D01*
X636126Y6650D01*
X636121Y6610D01*
X636111Y6565D01*
X636101Y6525D01*
X636056Y6405D01*
X636016Y6325D01*
X635991Y6290D01*
X635971Y6255D01*
X635941Y6220D01*
X635916Y6185D01*
X635886Y6155D01*
Y3730D01*
X635876Y3605D01*
X635836Y3480D01*
X635776Y3370D01*
X635696Y3270D01*
X635596Y3190D01*
X635486Y3130D01*
X635361Y3090D01*
X635236Y3080D01*
G37*
G36*
G01X663582D02*
X663457Y3090D01*
X663332Y3130D01*
X663222Y3190D01*
X663122Y3270D01*
X663042Y3370D01*
X662982Y3480D01*
X662942Y3605D01*
X662932Y3730D01*
Y6160D01*
X662902Y6190D01*
X662802Y6330D01*
X662782Y6370D01*
X662767Y6405D01*
X662747Y6445D01*
X662732Y6485D01*
X662722Y6525D01*
X662707Y6570D01*
X662702Y6610D01*
X662692Y6650D01*
X662687Y6695D01*
Y6735D01*
X662682Y6780D01*
X662687Y6825D01*
Y6865D01*
X662692Y6910D01*
X662702Y6950D01*
X662707Y6990D01*
X662722Y7035D01*
X662732Y7075D01*
X662747Y7115D01*
X662767Y7155D01*
X662782Y7190D01*
X662802Y7230D01*
X662902Y7370D01*
X662932Y7400D01*
Y9530D01*
X662942Y9655D01*
X662982Y9780D01*
X663042Y9890D01*
X663122Y9990D01*
X663222Y10070D01*
X663332Y10130D01*
X663457Y10170D01*
X663582Y10180D01*
X663707Y10170D01*
X663832Y10130D01*
X663942Y10070D01*
X664042Y9990D01*
X664122Y9890D01*
X664182Y9780D01*
X664222Y9655D01*
X664232Y9530D01*
Y7405D01*
X664262Y7375D01*
X664287Y7340D01*
X664317Y7305D01*
X664337Y7270D01*
X664362Y7235D01*
X664402Y7155D01*
X664447Y7035D01*
X664457Y6995D01*
X664467Y6950D01*
X664472Y6910D01*
X664482Y6865D01*
Y6695D01*
X664472Y6650D01*
X664467Y6610D01*
X664457Y6565D01*
X664447Y6525D01*
X664402Y6405D01*
X664362Y6325D01*
X664337Y6290D01*
X664317Y6255D01*
X664287Y6220D01*
X664262Y6185D01*
X664232Y6155D01*
Y3730D01*
X664222Y3605D01*
X664182Y3480D01*
X664122Y3370D01*
X664042Y3270D01*
X663942Y3190D01*
X663832Y3130D01*
X663707Y3090D01*
X663582Y3080D01*
G37*
G36*
G01X658858D02*
X658733Y3090D01*
X658608Y3130D01*
X658498Y3190D01*
X658398Y3270D01*
X658318Y3370D01*
X658258Y3480D01*
X658218Y3605D01*
X658208Y3730D01*
Y6160D01*
X658178Y6190D01*
X658078Y6330D01*
X658058Y6370D01*
X658043Y6405D01*
X658023Y6445D01*
X658008Y6485D01*
X657998Y6525D01*
X657983Y6570D01*
X657978Y6610D01*
X657968Y6650D01*
X657963Y6695D01*
Y6735D01*
X657958Y6780D01*
X657963Y6825D01*
Y6865D01*
X657968Y6910D01*
X657978Y6950D01*
X657983Y6990D01*
X657998Y7035D01*
X658008Y7075D01*
X658023Y7115D01*
X658043Y7155D01*
X658058Y7190D01*
X658078Y7230D01*
X658178Y7370D01*
X658208Y7400D01*
Y9530D01*
X658218Y9655D01*
X658258Y9780D01*
X658318Y9890D01*
X658398Y9990D01*
X658498Y10070D01*
X658608Y10130D01*
X658733Y10170D01*
X658858Y10180D01*
X658983Y10170D01*
X659108Y10130D01*
X659218Y10070D01*
X659318Y9990D01*
X659398Y9890D01*
X659458Y9780D01*
X659498Y9655D01*
X659508Y9530D01*
Y7405D01*
X659538Y7375D01*
X659563Y7340D01*
X659593Y7305D01*
X659613Y7270D01*
X659638Y7235D01*
X659678Y7155D01*
X659723Y7035D01*
X659733Y6995D01*
X659743Y6950D01*
X659748Y6910D01*
X659758Y6865D01*
Y6695D01*
X659748Y6650D01*
X659743Y6610D01*
X659733Y6565D01*
X659723Y6525D01*
X659678Y6405D01*
X659638Y6325D01*
X659613Y6290D01*
X659593Y6255D01*
X659563Y6220D01*
X659538Y6185D01*
X659508Y6155D01*
Y3730D01*
X659498Y3605D01*
X659458Y3480D01*
X659398Y3370D01*
X659318Y3270D01*
X659218Y3190D01*
X659108Y3130D01*
X658983Y3090D01*
X658858Y3080D01*
G37*
G36*
G01X654134D02*
X654009Y3090D01*
X653884Y3130D01*
X653774Y3190D01*
X653674Y3270D01*
X653594Y3370D01*
X653534Y3480D01*
X653494Y3605D01*
X653484Y3730D01*
Y6160D01*
X653454Y6190D01*
X653354Y6330D01*
X653334Y6370D01*
X653319Y6405D01*
X653299Y6445D01*
X653284Y6485D01*
X653274Y6525D01*
X653259Y6570D01*
X653254Y6610D01*
X653244Y6650D01*
X653239Y6695D01*
Y6735D01*
X653234Y6780D01*
X653239Y6825D01*
Y6865D01*
X653244Y6910D01*
X653254Y6950D01*
X653259Y6990D01*
X653274Y7035D01*
X653284Y7075D01*
X653299Y7115D01*
X653319Y7155D01*
X653334Y7190D01*
X653354Y7230D01*
X653454Y7370D01*
X653484Y7400D01*
Y9530D01*
X653494Y9655D01*
X653534Y9780D01*
X653594Y9890D01*
X653674Y9990D01*
X653774Y10070D01*
X653884Y10130D01*
X654009Y10170D01*
X654134Y10180D01*
X654259Y10170D01*
X654384Y10130D01*
X654494Y10070D01*
X654594Y9990D01*
X654674Y9890D01*
X654734Y9780D01*
X654774Y9655D01*
X654784Y9530D01*
Y7405D01*
X654814Y7375D01*
X654839Y7340D01*
X654869Y7305D01*
X654889Y7270D01*
X654914Y7235D01*
X654954Y7155D01*
X654999Y7035D01*
X655009Y6995D01*
X655019Y6950D01*
X655024Y6910D01*
X655034Y6865D01*
Y6695D01*
X655024Y6650D01*
X655019Y6610D01*
X655009Y6565D01*
X654999Y6525D01*
X654954Y6405D01*
X654914Y6325D01*
X654889Y6290D01*
X654869Y6255D01*
X654839Y6220D01*
X654814Y6185D01*
X654784Y6155D01*
Y3730D01*
X654774Y3605D01*
X654734Y3480D01*
X654674Y3370D01*
X654594Y3270D01*
X654494Y3190D01*
X654384Y3130D01*
X654259Y3090D01*
X654134Y3080D01*
G37*
G36*
G01X677756D02*
X677631Y3090D01*
X677506Y3130D01*
X677396Y3190D01*
X677296Y3270D01*
X677216Y3370D01*
X677156Y3480D01*
X677116Y3605D01*
X677106Y3730D01*
Y6160D01*
X677076Y6190D01*
X676976Y6330D01*
X676956Y6370D01*
X676941Y6405D01*
X676921Y6445D01*
X676906Y6485D01*
X676896Y6525D01*
X676881Y6570D01*
X676876Y6610D01*
X676866Y6650D01*
X676861Y6695D01*
Y6735D01*
X676856Y6780D01*
X676861Y6825D01*
Y6865D01*
X676866Y6910D01*
X676876Y6950D01*
X676881Y6990D01*
X676896Y7035D01*
X676906Y7075D01*
X676921Y7115D01*
X676941Y7155D01*
X676956Y7190D01*
X676976Y7230D01*
X677076Y7370D01*
X677106Y7400D01*
Y9530D01*
X677116Y9655D01*
X677156Y9780D01*
X677216Y9890D01*
X677296Y9990D01*
X677396Y10070D01*
X677506Y10130D01*
X677631Y10170D01*
X677756Y10180D01*
X677881Y10170D01*
X678006Y10130D01*
X678116Y10070D01*
X678216Y9990D01*
X678296Y9890D01*
X678356Y9780D01*
X678396Y9655D01*
X678406Y9530D01*
Y7405D01*
X678436Y7375D01*
X678461Y7340D01*
X678491Y7305D01*
X678511Y7270D01*
X678536Y7235D01*
X678576Y7155D01*
X678621Y7035D01*
X678631Y6995D01*
X678641Y6950D01*
X678646Y6910D01*
X678656Y6865D01*
Y6695D01*
X678646Y6650D01*
X678641Y6610D01*
X678631Y6565D01*
X678621Y6525D01*
X678576Y6405D01*
X678536Y6325D01*
X678511Y6290D01*
X678491Y6255D01*
X678461Y6220D01*
X678436Y6185D01*
X678406Y6155D01*
Y3730D01*
X678396Y3605D01*
X678356Y3480D01*
X678296Y3370D01*
X678216Y3270D01*
X678116Y3190D01*
X678006Y3130D01*
X677881Y3090D01*
X677756Y3080D01*
G37*
G36*
G01X673031D02*
X672906Y3090D01*
X672781Y3130D01*
X672671Y3190D01*
X672571Y3270D01*
X672491Y3370D01*
X672431Y3480D01*
X672391Y3605D01*
X672381Y3730D01*
Y6160D01*
X672351Y6190D01*
X672251Y6330D01*
X672231Y6370D01*
X672216Y6405D01*
X672196Y6445D01*
X672181Y6485D01*
X672171Y6525D01*
X672156Y6570D01*
X672151Y6610D01*
X672141Y6650D01*
X672136Y6695D01*
Y6735D01*
X672131Y6780D01*
X672136Y6825D01*
Y6865D01*
X672141Y6910D01*
X672151Y6950D01*
X672156Y6990D01*
X672171Y7035D01*
X672181Y7075D01*
X672196Y7115D01*
X672216Y7155D01*
X672231Y7190D01*
X672251Y7230D01*
X672351Y7370D01*
X672381Y7400D01*
Y9530D01*
X672391Y9655D01*
X672431Y9780D01*
X672491Y9890D01*
X672571Y9990D01*
X672671Y10070D01*
X672781Y10130D01*
X672906Y10170D01*
X673031Y10180D01*
X673156Y10170D01*
X673281Y10130D01*
X673391Y10070D01*
X673491Y9990D01*
X673571Y9890D01*
X673631Y9780D01*
X673671Y9655D01*
X673681Y9530D01*
Y7405D01*
X673711Y7375D01*
X673736Y7340D01*
X673766Y7305D01*
X673786Y7270D01*
X673811Y7235D01*
X673851Y7155D01*
X673896Y7035D01*
X673906Y6995D01*
X673916Y6950D01*
X673921Y6910D01*
X673931Y6865D01*
Y6695D01*
X673921Y6650D01*
X673916Y6610D01*
X673906Y6565D01*
X673896Y6525D01*
X673851Y6405D01*
X673811Y6325D01*
X673786Y6290D01*
X673766Y6255D01*
X673736Y6220D01*
X673711Y6185D01*
X673681Y6155D01*
Y3730D01*
X673671Y3605D01*
X673631Y3480D01*
X673571Y3370D01*
X673491Y3270D01*
X673391Y3190D01*
X673281Y3130D01*
X673156Y3090D01*
X673031Y3080D01*
G37*
G36*
G01X668307D02*
X668182Y3090D01*
X668057Y3130D01*
X667947Y3190D01*
X667847Y3270D01*
X667767Y3370D01*
X667707Y3480D01*
X667667Y3605D01*
X667657Y3730D01*
Y6160D01*
X667627Y6190D01*
X667527Y6330D01*
X667507Y6370D01*
X667492Y6405D01*
X667472Y6445D01*
X667457Y6485D01*
X667447Y6525D01*
X667432Y6570D01*
X667427Y6610D01*
X667417Y6650D01*
X667412Y6695D01*
Y6735D01*
X667407Y6780D01*
X667412Y6825D01*
Y6865D01*
X667417Y6910D01*
X667427Y6950D01*
X667432Y6990D01*
X667447Y7035D01*
X667457Y7075D01*
X667472Y7115D01*
X667492Y7155D01*
X667507Y7190D01*
X667527Y7230D01*
X667627Y7370D01*
X667657Y7400D01*
Y9530D01*
X667667Y9655D01*
X667707Y9780D01*
X667767Y9890D01*
X667847Y9990D01*
X667947Y10070D01*
X668057Y10130D01*
X668182Y10170D01*
X668307Y10180D01*
X668432Y10170D01*
X668557Y10130D01*
X668667Y10070D01*
X668767Y9990D01*
X668847Y9890D01*
X668907Y9780D01*
X668947Y9655D01*
X668957Y9530D01*
Y7405D01*
X668987Y7375D01*
X669012Y7340D01*
X669042Y7305D01*
X669062Y7270D01*
X669087Y7235D01*
X669127Y7155D01*
X669172Y7035D01*
X669182Y6995D01*
X669192Y6950D01*
X669197Y6910D01*
X669207Y6865D01*
Y6695D01*
X669197Y6650D01*
X669192Y6610D01*
X669182Y6565D01*
X669172Y6525D01*
X669127Y6405D01*
X669087Y6325D01*
X669062Y6290D01*
X669042Y6255D01*
X669012Y6220D01*
X668987Y6185D01*
X668957Y6155D01*
Y3730D01*
X668947Y3605D01*
X668907Y3480D01*
X668847Y3370D01*
X668767Y3270D01*
X668667Y3190D01*
X668557Y3130D01*
X668432Y3090D01*
X668307Y3080D01*
G37*
G36*
G01X691929D02*
X691804Y3090D01*
X691679Y3130D01*
X691569Y3190D01*
X691469Y3270D01*
X691389Y3370D01*
X691329Y3480D01*
X691289Y3605D01*
X691279Y3730D01*
Y6160D01*
X691249Y6190D01*
X691149Y6330D01*
X691129Y6370D01*
X691114Y6405D01*
X691094Y6445D01*
X691079Y6485D01*
X691069Y6525D01*
X691054Y6570D01*
X691049Y6610D01*
X691039Y6650D01*
X691034Y6695D01*
Y6735D01*
X691029Y6780D01*
X691034Y6825D01*
Y6865D01*
X691039Y6910D01*
X691049Y6950D01*
X691054Y6990D01*
X691069Y7035D01*
X691079Y7075D01*
X691094Y7115D01*
X691114Y7155D01*
X691129Y7190D01*
X691149Y7230D01*
X691249Y7370D01*
X691279Y7400D01*
Y9530D01*
X691289Y9655D01*
X691329Y9780D01*
X691389Y9890D01*
X691469Y9990D01*
X691569Y10070D01*
X691679Y10130D01*
X691804Y10170D01*
X691929Y10180D01*
X692054Y10170D01*
X692179Y10130D01*
X692289Y10070D01*
X692389Y9990D01*
X692469Y9890D01*
X692529Y9780D01*
X692569Y9655D01*
X692579Y9530D01*
Y7405D01*
X692609Y7375D01*
X692634Y7340D01*
X692664Y7305D01*
X692684Y7270D01*
X692709Y7235D01*
X692749Y7155D01*
X692794Y7035D01*
X692804Y6995D01*
X692814Y6950D01*
X692819Y6910D01*
X692829Y6865D01*
Y6695D01*
X692819Y6650D01*
X692814Y6610D01*
X692804Y6565D01*
X692794Y6525D01*
X692749Y6405D01*
X692709Y6325D01*
X692684Y6290D01*
X692664Y6255D01*
X692634Y6220D01*
X692609Y6185D01*
X692579Y6155D01*
Y3730D01*
X692569Y3605D01*
X692529Y3480D01*
X692469Y3370D01*
X692389Y3270D01*
X692289Y3190D01*
X692179Y3130D01*
X692054Y3090D01*
X691929Y3080D01*
G37*
G36*
G01X687204D02*
X687079Y3090D01*
X686954Y3130D01*
X686844Y3190D01*
X686744Y3270D01*
X686664Y3370D01*
X686604Y3480D01*
X686564Y3605D01*
X686554Y3730D01*
Y6160D01*
X686524Y6190D01*
X686424Y6330D01*
X686404Y6370D01*
X686389Y6405D01*
X686369Y6445D01*
X686354Y6485D01*
X686344Y6525D01*
X686329Y6570D01*
X686324Y6610D01*
X686314Y6650D01*
X686309Y6695D01*
Y6735D01*
X686304Y6780D01*
X686309Y6825D01*
Y6865D01*
X686314Y6910D01*
X686324Y6950D01*
X686329Y6990D01*
X686344Y7035D01*
X686354Y7075D01*
X686369Y7115D01*
X686389Y7155D01*
X686404Y7190D01*
X686424Y7230D01*
X686524Y7370D01*
X686554Y7400D01*
Y9530D01*
X686564Y9655D01*
X686604Y9780D01*
X686664Y9890D01*
X686744Y9990D01*
X686844Y10070D01*
X686954Y10130D01*
X687079Y10170D01*
X687204Y10180D01*
X687329Y10170D01*
X687454Y10130D01*
X687564Y10070D01*
X687664Y9990D01*
X687744Y9890D01*
X687804Y9780D01*
X687844Y9655D01*
X687854Y9530D01*
Y7405D01*
X687884Y7375D01*
X687909Y7340D01*
X687939Y7305D01*
X687959Y7270D01*
X687984Y7235D01*
X688024Y7155D01*
X688069Y7035D01*
X688079Y6995D01*
X688089Y6950D01*
X688094Y6910D01*
X688104Y6865D01*
Y6695D01*
X688094Y6650D01*
X688089Y6610D01*
X688079Y6565D01*
X688069Y6525D01*
X688024Y6405D01*
X687984Y6325D01*
X687959Y6290D01*
X687939Y6255D01*
X687909Y6220D01*
X687884Y6185D01*
X687854Y6155D01*
Y3730D01*
X687844Y3605D01*
X687804Y3480D01*
X687744Y3370D01*
X687664Y3270D01*
X687564Y3190D01*
X687454Y3130D01*
X687329Y3090D01*
X687204Y3080D01*
G37*
G36*
G01X682480D02*
X682355Y3090D01*
X682230Y3130D01*
X682120Y3190D01*
X682020Y3270D01*
X681940Y3370D01*
X681880Y3480D01*
X681840Y3605D01*
X681830Y3730D01*
Y6160D01*
X681800Y6190D01*
X681700Y6330D01*
X681680Y6370D01*
X681665Y6405D01*
X681645Y6445D01*
X681630Y6485D01*
X681620Y6525D01*
X681605Y6570D01*
X681600Y6610D01*
X681590Y6650D01*
X681585Y6695D01*
Y6735D01*
X681580Y6780D01*
X681585Y6825D01*
Y6865D01*
X681590Y6910D01*
X681600Y6950D01*
X681605Y6990D01*
X681620Y7035D01*
X681630Y7075D01*
X681645Y7115D01*
X681665Y7155D01*
X681680Y7190D01*
X681700Y7230D01*
X681800Y7370D01*
X681830Y7400D01*
Y9530D01*
X681840Y9655D01*
X681880Y9780D01*
X681940Y9890D01*
X682020Y9990D01*
X682120Y10070D01*
X682230Y10130D01*
X682355Y10170D01*
X682480Y10180D01*
X682605Y10170D01*
X682730Y10130D01*
X682840Y10070D01*
X682940Y9990D01*
X683020Y9890D01*
X683080Y9780D01*
X683120Y9655D01*
X683130Y9530D01*
Y7405D01*
X683160Y7375D01*
X683185Y7340D01*
X683215Y7305D01*
X683235Y7270D01*
X683260Y7235D01*
X683300Y7155D01*
X683345Y7035D01*
X683355Y6995D01*
X683365Y6950D01*
X683370Y6910D01*
X683380Y6865D01*
Y6695D01*
X683370Y6650D01*
X683365Y6610D01*
X683355Y6565D01*
X683345Y6525D01*
X683300Y6405D01*
X683260Y6325D01*
X683235Y6290D01*
X683215Y6255D01*
X683185Y6220D01*
X683160Y6185D01*
X683130Y6155D01*
Y3730D01*
X683120Y3605D01*
X683080Y3480D01*
X683020Y3370D01*
X682940Y3270D01*
X682840Y3190D01*
X682730Y3130D01*
X682605Y3090D01*
X682480Y3080D01*
G37*
G36*
G01X710827D02*
X710702Y3090D01*
X710577Y3130D01*
X710467Y3190D01*
X710367Y3270D01*
X710287Y3370D01*
X710227Y3480D01*
X710187Y3605D01*
X710177Y3730D01*
Y6160D01*
X710147Y6190D01*
X710047Y6330D01*
X710027Y6370D01*
X710012Y6405D01*
X709992Y6445D01*
X709977Y6485D01*
X709967Y6525D01*
X709952Y6570D01*
X709947Y6610D01*
X709937Y6650D01*
X709932Y6695D01*
Y6735D01*
X709927Y6780D01*
X709932Y6825D01*
Y6865D01*
X709937Y6910D01*
X709947Y6950D01*
X709952Y6990D01*
X709967Y7035D01*
X709977Y7075D01*
X709992Y7115D01*
X710012Y7155D01*
X710027Y7190D01*
X710047Y7230D01*
X710147Y7370D01*
X710177Y7400D01*
Y9530D01*
X710187Y9655D01*
X710227Y9780D01*
X710287Y9890D01*
X710367Y9990D01*
X710467Y10070D01*
X710577Y10130D01*
X710702Y10170D01*
X710827Y10180D01*
X710952Y10170D01*
X711077Y10130D01*
X711187Y10070D01*
X711287Y9990D01*
X711367Y9890D01*
X711427Y9780D01*
X711467Y9655D01*
X711477Y9530D01*
Y7405D01*
X711507Y7375D01*
X711532Y7340D01*
X711562Y7305D01*
X711582Y7270D01*
X711607Y7235D01*
X711647Y7155D01*
X711692Y7035D01*
X711702Y6995D01*
X711712Y6950D01*
X711717Y6910D01*
X711727Y6865D01*
Y6695D01*
X711717Y6650D01*
X711712Y6610D01*
X711702Y6565D01*
X711692Y6525D01*
X711647Y6405D01*
X711607Y6325D01*
X711582Y6290D01*
X711562Y6255D01*
X711532Y6220D01*
X711507Y6185D01*
X711477Y6155D01*
Y3730D01*
X711467Y3605D01*
X711427Y3480D01*
X711367Y3370D01*
X711287Y3270D01*
X711187Y3190D01*
X711077Y3130D01*
X710952Y3090D01*
X710827Y3080D01*
G37*
G36*
G01X706102D02*
X705977Y3090D01*
X705852Y3130D01*
X705742Y3190D01*
X705642Y3270D01*
X705562Y3370D01*
X705502Y3480D01*
X705462Y3605D01*
X705452Y3730D01*
Y6160D01*
X705422Y6190D01*
X705322Y6330D01*
X705302Y6370D01*
X705287Y6405D01*
X705267Y6445D01*
X705252Y6485D01*
X705242Y6525D01*
X705227Y6570D01*
X705222Y6610D01*
X705212Y6650D01*
X705207Y6695D01*
Y6735D01*
X705202Y6780D01*
X705207Y6825D01*
Y6865D01*
X705212Y6910D01*
X705222Y6950D01*
X705227Y6990D01*
X705242Y7035D01*
X705252Y7075D01*
X705267Y7115D01*
X705287Y7155D01*
X705302Y7190D01*
X705322Y7230D01*
X705422Y7370D01*
X705452Y7400D01*
Y9530D01*
X705462Y9655D01*
X705502Y9780D01*
X705562Y9890D01*
X705642Y9990D01*
X705742Y10070D01*
X705852Y10130D01*
X705977Y10170D01*
X706102Y10180D01*
X706227Y10170D01*
X706352Y10130D01*
X706462Y10070D01*
X706562Y9990D01*
X706642Y9890D01*
X706702Y9780D01*
X706742Y9655D01*
X706752Y9530D01*
Y7405D01*
X706782Y7375D01*
X706807Y7340D01*
X706837Y7305D01*
X706857Y7270D01*
X706882Y7235D01*
X706922Y7155D01*
X706967Y7035D01*
X706977Y6995D01*
X706987Y6950D01*
X706992Y6910D01*
X707002Y6865D01*
Y6695D01*
X706992Y6650D01*
X706987Y6610D01*
X706977Y6565D01*
X706967Y6525D01*
X706922Y6405D01*
X706882Y6325D01*
X706857Y6290D01*
X706837Y6255D01*
X706807Y6220D01*
X706782Y6185D01*
X706752Y6155D01*
Y3730D01*
X706742Y3605D01*
X706702Y3480D01*
X706642Y3370D01*
X706562Y3270D01*
X706462Y3190D01*
X706352Y3130D01*
X706227Y3090D01*
X706102Y3080D01*
G37*
G36*
G01X701378D02*
X701253Y3090D01*
X701128Y3130D01*
X701018Y3190D01*
X700918Y3270D01*
X700838Y3370D01*
X700778Y3480D01*
X700738Y3605D01*
X700728Y3730D01*
Y6160D01*
X700698Y6190D01*
X700598Y6330D01*
X700578Y6370D01*
X700563Y6405D01*
X700543Y6445D01*
X700528Y6485D01*
X700518Y6525D01*
X700503Y6570D01*
X700498Y6610D01*
X700488Y6650D01*
X700483Y6695D01*
Y6735D01*
X700478Y6780D01*
X700483Y6825D01*
Y6865D01*
X700488Y6910D01*
X700498Y6950D01*
X700503Y6990D01*
X700518Y7035D01*
X700528Y7075D01*
X700543Y7115D01*
X700563Y7155D01*
X700578Y7190D01*
X700598Y7230D01*
X700698Y7370D01*
X700728Y7400D01*
Y9530D01*
X700738Y9655D01*
X700778Y9780D01*
X700838Y9890D01*
X700918Y9990D01*
X701018Y10070D01*
X701128Y10130D01*
X701253Y10170D01*
X701378Y10180D01*
X701503Y10170D01*
X701628Y10130D01*
X701738Y10070D01*
X701838Y9990D01*
X701918Y9890D01*
X701978Y9780D01*
X702018Y9655D01*
X702028Y9530D01*
Y7405D01*
X702058Y7375D01*
X702083Y7340D01*
X702113Y7305D01*
X702133Y7270D01*
X702158Y7235D01*
X702198Y7155D01*
X702243Y7035D01*
X702253Y6995D01*
X702263Y6950D01*
X702268Y6910D01*
X702278Y6865D01*
Y6695D01*
X702268Y6650D01*
X702263Y6610D01*
X702253Y6565D01*
X702243Y6525D01*
X702198Y6405D01*
X702158Y6325D01*
X702133Y6290D01*
X702113Y6255D01*
X702083Y6220D01*
X702058Y6185D01*
X702028Y6155D01*
Y3730D01*
X702018Y3605D01*
X701978Y3480D01*
X701918Y3370D01*
X701838Y3270D01*
X701738Y3190D01*
X701628Y3130D01*
X701503Y3090D01*
X701378Y3080D01*
G37*
G36*
G01X696653D02*
X696528Y3090D01*
X696403Y3130D01*
X696293Y3190D01*
X696193Y3270D01*
X696113Y3370D01*
X696053Y3480D01*
X696013Y3605D01*
X696003Y3730D01*
Y6160D01*
X695973Y6190D01*
X695873Y6330D01*
X695853Y6370D01*
X695838Y6405D01*
X695818Y6445D01*
X695803Y6485D01*
X695793Y6525D01*
X695778Y6570D01*
X695773Y6610D01*
X695763Y6650D01*
X695758Y6695D01*
Y6735D01*
X695753Y6780D01*
X695758Y6825D01*
Y6865D01*
X695763Y6910D01*
X695773Y6950D01*
X695778Y6990D01*
X695793Y7035D01*
X695803Y7075D01*
X695818Y7115D01*
X695838Y7155D01*
X695853Y7190D01*
X695873Y7230D01*
X695973Y7370D01*
X696003Y7400D01*
Y9530D01*
X696013Y9655D01*
X696053Y9780D01*
X696113Y9890D01*
X696193Y9990D01*
X696293Y10070D01*
X696403Y10130D01*
X696528Y10170D01*
X696653Y10180D01*
X696778Y10170D01*
X696903Y10130D01*
X697013Y10070D01*
X697113Y9990D01*
X697193Y9890D01*
X697253Y9780D01*
X697293Y9655D01*
X697303Y9530D01*
Y7405D01*
X697333Y7375D01*
X697358Y7340D01*
X697388Y7305D01*
X697408Y7270D01*
X697433Y7235D01*
X697473Y7155D01*
X697518Y7035D01*
X697528Y6995D01*
X697538Y6950D01*
X697543Y6910D01*
X697553Y6865D01*
Y6695D01*
X697543Y6650D01*
X697538Y6610D01*
X697528Y6565D01*
X697518Y6525D01*
X697473Y6405D01*
X697433Y6325D01*
X697408Y6290D01*
X697388Y6255D01*
X697358Y6220D01*
X697333Y6185D01*
X697303Y6155D01*
Y3730D01*
X697293Y3605D01*
X697253Y3480D01*
X697193Y3370D01*
X697113Y3270D01*
X697013Y3190D01*
X696903Y3130D01*
X696778Y3090D01*
X696653Y3080D01*
G37*
G36*
G01X725000D02*
X724875Y3090D01*
X724750Y3130D01*
X724640Y3190D01*
X724540Y3270D01*
X724460Y3370D01*
X724400Y3480D01*
X724360Y3605D01*
X724350Y3730D01*
Y6160D01*
X724320Y6190D01*
X724220Y6330D01*
X724200Y6370D01*
X724185Y6405D01*
X724165Y6445D01*
X724150Y6485D01*
X724140Y6525D01*
X724125Y6570D01*
X724120Y6610D01*
X724110Y6650D01*
X724105Y6695D01*
Y6735D01*
X724100Y6780D01*
X724105Y6825D01*
Y6865D01*
X724110Y6910D01*
X724120Y6950D01*
X724125Y6990D01*
X724140Y7035D01*
X724150Y7075D01*
X724165Y7115D01*
X724185Y7155D01*
X724200Y7190D01*
X724220Y7230D01*
X724320Y7370D01*
X724350Y7400D01*
Y9530D01*
X724360Y9655D01*
X724400Y9780D01*
X724460Y9890D01*
X724540Y9990D01*
X724640Y10070D01*
X724750Y10130D01*
X724875Y10170D01*
X725000Y10180D01*
X725125Y10170D01*
X725250Y10130D01*
X725360Y10070D01*
X725460Y9990D01*
X725540Y9890D01*
X725600Y9780D01*
X725640Y9655D01*
X725650Y9530D01*
Y7405D01*
X725680Y7375D01*
X725705Y7340D01*
X725735Y7305D01*
X725755Y7270D01*
X725780Y7235D01*
X725820Y7155D01*
X725865Y7035D01*
X725875Y6995D01*
X725885Y6950D01*
X725890Y6910D01*
X725900Y6865D01*
Y6695D01*
X725890Y6650D01*
X725885Y6610D01*
X725875Y6565D01*
X725865Y6525D01*
X725820Y6405D01*
X725780Y6325D01*
X725755Y6290D01*
X725735Y6255D01*
X725705Y6220D01*
X725680Y6185D01*
X725650Y6155D01*
Y3730D01*
X725640Y3605D01*
X725600Y3480D01*
X725540Y3370D01*
X725460Y3270D01*
X725360Y3190D01*
X725250Y3130D01*
X725125Y3090D01*
X725000Y3080D01*
G37*
G36*
G01X720275D02*
X720150Y3090D01*
X720025Y3130D01*
X719915Y3190D01*
X719815Y3270D01*
X719735Y3370D01*
X719675Y3480D01*
X719635Y3605D01*
X719625Y3730D01*
Y6160D01*
X719595Y6190D01*
X719495Y6330D01*
X719475Y6370D01*
X719460Y6405D01*
X719440Y6445D01*
X719425Y6485D01*
X719415Y6525D01*
X719400Y6570D01*
X719395Y6610D01*
X719385Y6650D01*
X719380Y6695D01*
Y6735D01*
X719375Y6780D01*
X719380Y6825D01*
Y6865D01*
X719385Y6910D01*
X719395Y6950D01*
X719400Y6990D01*
X719415Y7035D01*
X719425Y7075D01*
X719440Y7115D01*
X719460Y7155D01*
X719475Y7190D01*
X719495Y7230D01*
X719595Y7370D01*
X719625Y7400D01*
Y9530D01*
X719635Y9655D01*
X719675Y9780D01*
X719735Y9890D01*
X719815Y9990D01*
X719915Y10070D01*
X720025Y10130D01*
X720150Y10170D01*
X720275Y10180D01*
X720400Y10170D01*
X720525Y10130D01*
X720635Y10070D01*
X720735Y9990D01*
X720815Y9890D01*
X720875Y9780D01*
X720915Y9655D01*
X720925Y9530D01*
Y7405D01*
X720955Y7375D01*
X720980Y7340D01*
X721010Y7305D01*
X721030Y7270D01*
X721055Y7235D01*
X721095Y7155D01*
X721140Y7035D01*
X721150Y6995D01*
X721160Y6950D01*
X721165Y6910D01*
X721175Y6865D01*
Y6695D01*
X721165Y6650D01*
X721160Y6610D01*
X721150Y6565D01*
X721140Y6525D01*
X721095Y6405D01*
X721055Y6325D01*
X721030Y6290D01*
X721010Y6255D01*
X720980Y6220D01*
X720955Y6185D01*
X720925Y6155D01*
Y3730D01*
X720915Y3605D01*
X720875Y3480D01*
X720815Y3370D01*
X720735Y3270D01*
X720635Y3190D01*
X720525Y3130D01*
X720400Y3090D01*
X720275Y3080D01*
G37*
G36*
G01X715551D02*
X715426Y3090D01*
X715301Y3130D01*
X715191Y3190D01*
X715091Y3270D01*
X715011Y3370D01*
X714951Y3480D01*
X714911Y3605D01*
X714901Y3730D01*
Y6160D01*
X714871Y6190D01*
X714771Y6330D01*
X714751Y6370D01*
X714736Y6405D01*
X714716Y6445D01*
X714701Y6485D01*
X714691Y6525D01*
X714676Y6570D01*
X714671Y6610D01*
X714661Y6650D01*
X714656Y6695D01*
Y6735D01*
X714651Y6780D01*
X714656Y6825D01*
Y6865D01*
X714661Y6910D01*
X714671Y6950D01*
X714676Y6990D01*
X714691Y7035D01*
X714701Y7075D01*
X714716Y7115D01*
X714736Y7155D01*
X714751Y7190D01*
X714771Y7230D01*
X714871Y7370D01*
X714901Y7400D01*
Y9530D01*
X714911Y9655D01*
X714951Y9780D01*
X715011Y9890D01*
X715091Y9990D01*
X715191Y10070D01*
X715301Y10130D01*
X715426Y10170D01*
X715551Y10180D01*
X715676Y10170D01*
X715801Y10130D01*
X715911Y10070D01*
X716011Y9990D01*
X716091Y9890D01*
X716151Y9780D01*
X716191Y9655D01*
X716201Y9530D01*
Y7405D01*
X716231Y7375D01*
X716256Y7340D01*
X716286Y7305D01*
X716306Y7270D01*
X716331Y7235D01*
X716371Y7155D01*
X716416Y7035D01*
X716426Y6995D01*
X716436Y6950D01*
X716441Y6910D01*
X716451Y6865D01*
Y6695D01*
X716441Y6650D01*
X716436Y6610D01*
X716426Y6565D01*
X716416Y6525D01*
X716371Y6405D01*
X716331Y6325D01*
X716306Y6290D01*
X716286Y6255D01*
X716256Y6220D01*
X716231Y6185D01*
X716201Y6155D01*
Y3730D01*
X716191Y3605D01*
X716151Y3480D01*
X716091Y3370D01*
X716011Y3270D01*
X715911Y3190D01*
X715801Y3130D01*
X715676Y3090D01*
X715551Y3080D01*
G37*
G36*
G01X739173D02*
X739048Y3090D01*
X738923Y3130D01*
X738813Y3190D01*
X738713Y3270D01*
X738633Y3370D01*
X738573Y3480D01*
X738533Y3605D01*
X738523Y3730D01*
Y6160D01*
X738493Y6190D01*
X738393Y6330D01*
X738373Y6370D01*
X738358Y6405D01*
X738338Y6445D01*
X738323Y6485D01*
X738313Y6525D01*
X738298Y6570D01*
X738293Y6610D01*
X738283Y6650D01*
X738278Y6695D01*
Y6735D01*
X738273Y6780D01*
X738278Y6825D01*
Y6865D01*
X738283Y6910D01*
X738293Y6950D01*
X738298Y6990D01*
X738313Y7035D01*
X738323Y7075D01*
X738338Y7115D01*
X738358Y7155D01*
X738373Y7190D01*
X738393Y7230D01*
X738493Y7370D01*
X738523Y7400D01*
Y9530D01*
X738533Y9655D01*
X738573Y9780D01*
X738633Y9890D01*
X738713Y9990D01*
X738813Y10070D01*
X738923Y10130D01*
X739048Y10170D01*
X739173Y10180D01*
X739298Y10170D01*
X739423Y10130D01*
X739533Y10070D01*
X739633Y9990D01*
X739713Y9890D01*
X739773Y9780D01*
X739813Y9655D01*
X739823Y9530D01*
Y7405D01*
X739853Y7375D01*
X739878Y7340D01*
X739908Y7305D01*
X739928Y7270D01*
X739953Y7235D01*
X739993Y7155D01*
X740038Y7035D01*
X740048Y6995D01*
X740058Y6950D01*
X740063Y6910D01*
X740073Y6865D01*
Y6695D01*
X740063Y6650D01*
X740058Y6610D01*
X740048Y6565D01*
X740038Y6525D01*
X739993Y6405D01*
X739953Y6325D01*
X739928Y6290D01*
X739908Y6255D01*
X739878Y6220D01*
X739853Y6185D01*
X739823Y6155D01*
Y3730D01*
X739813Y3605D01*
X739773Y3480D01*
X739713Y3370D01*
X739633Y3270D01*
X739533Y3190D01*
X739423Y3130D01*
X739298Y3090D01*
X739173Y3080D01*
G37*
G36*
G01X734449D02*
X734324Y3090D01*
X734199Y3130D01*
X734089Y3190D01*
X733989Y3270D01*
X733909Y3370D01*
X733849Y3480D01*
X733809Y3605D01*
X733799Y3730D01*
Y6160D01*
X733769Y6190D01*
X733669Y6330D01*
X733649Y6370D01*
X733634Y6405D01*
X733614Y6445D01*
X733599Y6485D01*
X733589Y6525D01*
X733574Y6570D01*
X733569Y6610D01*
X733559Y6650D01*
X733554Y6695D01*
Y6735D01*
X733549Y6780D01*
X733554Y6825D01*
Y6865D01*
X733559Y6910D01*
X733569Y6950D01*
X733574Y6990D01*
X733589Y7035D01*
X733599Y7075D01*
X733614Y7115D01*
X733634Y7155D01*
X733649Y7190D01*
X733669Y7230D01*
X733769Y7370D01*
X733799Y7400D01*
Y9530D01*
X733809Y9655D01*
X733849Y9780D01*
X733909Y9890D01*
X733989Y9990D01*
X734089Y10070D01*
X734199Y10130D01*
X734324Y10170D01*
X734449Y10180D01*
X734574Y10170D01*
X734699Y10130D01*
X734809Y10070D01*
X734909Y9990D01*
X734989Y9890D01*
X735049Y9780D01*
X735089Y9655D01*
X735099Y9530D01*
Y7405D01*
X735129Y7375D01*
X735154Y7340D01*
X735184Y7305D01*
X735204Y7270D01*
X735229Y7235D01*
X735269Y7155D01*
X735314Y7035D01*
X735324Y6995D01*
X735334Y6950D01*
X735339Y6910D01*
X735349Y6865D01*
Y6695D01*
X735339Y6650D01*
X735334Y6610D01*
X735324Y6565D01*
X735314Y6525D01*
X735269Y6405D01*
X735229Y6325D01*
X735204Y6290D01*
X735184Y6255D01*
X735154Y6220D01*
X735129Y6185D01*
X735099Y6155D01*
Y3730D01*
X735089Y3605D01*
X735049Y3480D01*
X734989Y3370D01*
X734909Y3270D01*
X734809Y3190D01*
X734699Y3130D01*
X734574Y3090D01*
X734449Y3080D01*
G37*
G36*
G01X729724D02*
X729599Y3090D01*
X729474Y3130D01*
X729364Y3190D01*
X729264Y3270D01*
X729184Y3370D01*
X729124Y3480D01*
X729084Y3605D01*
X729074Y3730D01*
Y6160D01*
X729044Y6190D01*
X728944Y6330D01*
X728924Y6370D01*
X728909Y6405D01*
X728889Y6445D01*
X728874Y6485D01*
X728864Y6525D01*
X728849Y6570D01*
X728844Y6610D01*
X728834Y6650D01*
X728829Y6695D01*
Y6735D01*
X728824Y6780D01*
X728829Y6825D01*
Y6865D01*
X728834Y6910D01*
X728844Y6950D01*
X728849Y6990D01*
X728864Y7035D01*
X728874Y7075D01*
X728889Y7115D01*
X728909Y7155D01*
X728924Y7190D01*
X728944Y7230D01*
X729044Y7370D01*
X729074Y7400D01*
Y9530D01*
X729084Y9655D01*
X729124Y9780D01*
X729184Y9890D01*
X729264Y9990D01*
X729364Y10070D01*
X729474Y10130D01*
X729599Y10170D01*
X729724Y10180D01*
X729849Y10170D01*
X729974Y10130D01*
X730084Y10070D01*
X730184Y9990D01*
X730264Y9890D01*
X730324Y9780D01*
X730364Y9655D01*
X730374Y9530D01*
Y7405D01*
X730404Y7375D01*
X730429Y7340D01*
X730459Y7305D01*
X730479Y7270D01*
X730504Y7235D01*
X730544Y7155D01*
X730589Y7035D01*
X730599Y6995D01*
X730609Y6950D01*
X730614Y6910D01*
X730624Y6865D01*
Y6695D01*
X730614Y6650D01*
X730609Y6610D01*
X730599Y6565D01*
X730589Y6525D01*
X730544Y6405D01*
X730504Y6325D01*
X730479Y6290D01*
X730459Y6255D01*
X730429Y6220D01*
X730404Y6185D01*
X730374Y6155D01*
Y3730D01*
X730364Y3605D01*
X730324Y3480D01*
X730264Y3370D01*
X730184Y3270D01*
X730084Y3190D01*
X729974Y3130D01*
X729849Y3090D01*
X729724Y3080D01*
G37*
G36*
G01X753346D02*
X753221Y3090D01*
X753096Y3130D01*
X752986Y3190D01*
X752886Y3270D01*
X752806Y3370D01*
X752746Y3480D01*
X752706Y3605D01*
X752696Y3730D01*
Y6160D01*
X752666Y6190D01*
X752566Y6330D01*
X752546Y6370D01*
X752531Y6405D01*
X752511Y6445D01*
X752496Y6485D01*
X752486Y6525D01*
X752471Y6570D01*
X752466Y6610D01*
X752456Y6650D01*
X752451Y6695D01*
Y6735D01*
X752446Y6780D01*
X752451Y6825D01*
Y6865D01*
X752456Y6910D01*
X752466Y6950D01*
X752471Y6990D01*
X752486Y7035D01*
X752496Y7075D01*
X752511Y7115D01*
X752531Y7155D01*
X752546Y7190D01*
X752566Y7230D01*
X752666Y7370D01*
X752696Y7400D01*
Y9530D01*
X752706Y9655D01*
X752746Y9780D01*
X752806Y9890D01*
X752886Y9990D01*
X752986Y10070D01*
X753096Y10130D01*
X753221Y10170D01*
X753346Y10180D01*
X753471Y10170D01*
X753596Y10130D01*
X753706Y10070D01*
X753806Y9990D01*
X753886Y9890D01*
X753946Y9780D01*
X753986Y9655D01*
X753996Y9530D01*
Y7405D01*
X754026Y7375D01*
X754051Y7340D01*
X754081Y7305D01*
X754101Y7270D01*
X754126Y7235D01*
X754166Y7155D01*
X754211Y7035D01*
X754221Y6995D01*
X754231Y6950D01*
X754236Y6910D01*
X754246Y6865D01*
Y6695D01*
X754236Y6650D01*
X754231Y6610D01*
X754221Y6565D01*
X754211Y6525D01*
X754166Y6405D01*
X754126Y6325D01*
X754101Y6290D01*
X754081Y6255D01*
X754051Y6220D01*
X754026Y6185D01*
X753996Y6155D01*
Y3730D01*
X753986Y3605D01*
X753946Y3480D01*
X753886Y3370D01*
X753806Y3270D01*
X753706Y3190D01*
X753596Y3130D01*
X753471Y3090D01*
X753346Y3080D01*
G37*
G36*
G01X748622D02*
X748497Y3090D01*
X748372Y3130D01*
X748262Y3190D01*
X748162Y3270D01*
X748082Y3370D01*
X748022Y3480D01*
X747982Y3605D01*
X747972Y3730D01*
Y6160D01*
X747942Y6190D01*
X747842Y6330D01*
X747822Y6370D01*
X747807Y6405D01*
X747787Y6445D01*
X747772Y6485D01*
X747762Y6525D01*
X747747Y6570D01*
X747742Y6610D01*
X747732Y6650D01*
X747727Y6695D01*
Y6735D01*
X747722Y6780D01*
X747727Y6825D01*
Y6865D01*
X747732Y6910D01*
X747742Y6950D01*
X747747Y6990D01*
X747762Y7035D01*
X747772Y7075D01*
X747787Y7115D01*
X747807Y7155D01*
X747822Y7190D01*
X747842Y7230D01*
X747942Y7370D01*
X747972Y7400D01*
Y9530D01*
X747982Y9655D01*
X748022Y9780D01*
X748082Y9890D01*
X748162Y9990D01*
X748262Y10070D01*
X748372Y10130D01*
X748497Y10170D01*
X748622Y10180D01*
X748747Y10170D01*
X748872Y10130D01*
X748982Y10070D01*
X749082Y9990D01*
X749162Y9890D01*
X749222Y9780D01*
X749262Y9655D01*
X749272Y9530D01*
Y7405D01*
X749302Y7375D01*
X749327Y7340D01*
X749357Y7305D01*
X749377Y7270D01*
X749402Y7235D01*
X749442Y7155D01*
X749487Y7035D01*
X749497Y6995D01*
X749507Y6950D01*
X749512Y6910D01*
X749522Y6865D01*
Y6695D01*
X749512Y6650D01*
X749507Y6610D01*
X749497Y6565D01*
X749487Y6525D01*
X749442Y6405D01*
X749402Y6325D01*
X749377Y6290D01*
X749357Y6255D01*
X749327Y6220D01*
X749302Y6185D01*
X749272Y6155D01*
Y3730D01*
X749262Y3605D01*
X749222Y3480D01*
X749162Y3370D01*
X749082Y3270D01*
X748982Y3190D01*
X748872Y3130D01*
X748747Y3090D01*
X748622Y3080D01*
G37*
G36*
G01X743897D02*
X743772Y3090D01*
X743647Y3130D01*
X743537Y3190D01*
X743437Y3270D01*
X743357Y3370D01*
X743297Y3480D01*
X743257Y3605D01*
X743247Y3730D01*
Y6160D01*
X743217Y6190D01*
X743117Y6330D01*
X743097Y6370D01*
X743082Y6405D01*
X743062Y6445D01*
X743047Y6485D01*
X743037Y6525D01*
X743022Y6570D01*
X743017Y6610D01*
X743007Y6650D01*
X743002Y6695D01*
Y6735D01*
X742997Y6780D01*
X743002Y6825D01*
Y6865D01*
X743007Y6910D01*
X743017Y6950D01*
X743022Y6990D01*
X743037Y7035D01*
X743047Y7075D01*
X743062Y7115D01*
X743082Y7155D01*
X743097Y7190D01*
X743117Y7230D01*
X743217Y7370D01*
X743247Y7400D01*
Y9530D01*
X743257Y9655D01*
X743297Y9780D01*
X743357Y9890D01*
X743437Y9990D01*
X743537Y10070D01*
X743647Y10130D01*
X743772Y10170D01*
X743897Y10180D01*
X744022Y10170D01*
X744147Y10130D01*
X744257Y10070D01*
X744357Y9990D01*
X744437Y9890D01*
X744497Y9780D01*
X744537Y9655D01*
X744547Y9530D01*
Y7405D01*
X744577Y7375D01*
X744602Y7340D01*
X744632Y7305D01*
X744652Y7270D01*
X744677Y7235D01*
X744717Y7155D01*
X744762Y7035D01*
X744772Y6995D01*
X744782Y6950D01*
X744787Y6910D01*
X744797Y6865D01*
Y6695D01*
X744787Y6650D01*
X744782Y6610D01*
X744772Y6565D01*
X744762Y6525D01*
X744717Y6405D01*
X744677Y6325D01*
X744652Y6290D01*
X744632Y6255D01*
X744602Y6220D01*
X744577Y6185D01*
X744547Y6155D01*
Y3730D01*
X744537Y3605D01*
X744497Y3480D01*
X744437Y3370D01*
X744357Y3270D01*
X744257Y3190D01*
X744147Y3130D01*
X744022Y3090D01*
X743897Y3080D01*
G37*
G54D67*
X170561Y236000D03*
G54D58*
X140639Y252500D03*
X138080D03*
X135520D03*
X132961D03*
Y264500D03*
X135520D03*
X138080D03*
X140639D03*
G54D76*
X236100Y114300D03*
X244100Y110560D03*
Y118040D03*
G54D49*
X104000Y214100D03*
X109200D03*
X104000Y224200D03*
X109200D03*
X104000Y219100D03*
X109200D03*
X104000Y235400D03*
X109200D03*
X144400Y196000D03*
X149600D03*
X427100Y75500D03*
X432300D03*
X427396Y232063D03*
X432596D03*
X436896D03*
X442096D03*
X520400Y231000D03*
X525600D03*
X520400Y236000D03*
X525600D03*
X551900D03*
X557100D03*
X658400Y111500D03*
X663600D03*
X658400Y139500D03*
X663600D03*
X675400Y156500D03*
X680600D03*
X725900Y59000D03*
Y54000D03*
X718900Y90000D03*
X724100D03*
X731100Y59000D03*
Y54000D03*
X775900Y12000D03*
X781100D03*
X775900Y7000D03*
X781100D03*
X774100Y133000D03*
X779300D03*
X773900Y154500D03*
X779100D03*
X800400Y260600D03*
Y265600D03*
Y270600D03*
X805600Y260600D03*
Y265600D03*
Y270600D03*
G54D85*
G01X129500Y252500D02*
X132961D01*
G01X132800Y269000D02*
X132961Y268839D01*
Y264500D01*
G01X400982Y144881D02*
X402625D01*
X403132Y144374D01*
X317132Y105911D03*
X320332Y102711D03*
Y105911D03*
X323532Y102711D03*
X313932Y109111D03*
X317132D03*
X320332D03*
X313932Y112311D03*
Y115511D03*
Y196351D03*
Y193151D03*
X323532Y205951D03*
X320332D03*
X317132Y199551D03*
X313932D03*
X317132Y202751D03*
X320332Y199551D03*
Y202751D03*
X326732Y102711D03*
Y205951D03*
X431192Y102711D03*
X427992D03*
Y205951D03*
X431192D03*
X434392Y105911D03*
X437592Y109111D03*
X434392D03*
X440792Y112311D03*
Y115511D03*
Y196351D03*
Y193151D03*
X434392Y205951D03*
X437592Y199551D03*
X434392Y202751D03*
Y199551D03*
X440792D03*
X437592Y202751D03*
G36*
G01X510039Y3080D02*
X509914Y3090D01*
X509789Y3130D01*
X509679Y3190D01*
X509579Y3270D01*
X509499Y3370D01*
X509439Y3480D01*
X509399Y3605D01*
X509389Y3730D01*
Y7160D01*
X509359Y7190D01*
X509259Y7330D01*
X509239Y7370D01*
X509224Y7405D01*
X509204Y7445D01*
X509189Y7485D01*
X509179Y7525D01*
X509164Y7570D01*
X509159Y7610D01*
X509149Y7650D01*
X509144Y7695D01*
Y7735D01*
X509139Y7780D01*
X509144Y7825D01*
Y7865D01*
X509149Y7910D01*
X509159Y7950D01*
X509164Y7990D01*
X509179Y8035D01*
X509189Y8075D01*
X509204Y8115D01*
X509224Y8155D01*
X509239Y8190D01*
X509259Y8230D01*
X509359Y8370D01*
X509389Y8400D01*
Y9530D01*
X509399Y9655D01*
X509439Y9780D01*
X509499Y9890D01*
X509579Y9990D01*
X509679Y10070D01*
X509789Y10130D01*
X509914Y10170D01*
X510039Y10180D01*
X510164Y10170D01*
X510289Y10130D01*
X510399Y10070D01*
X510499Y9990D01*
X510579Y9890D01*
X510639Y9780D01*
X510679Y9655D01*
X510689Y9530D01*
Y8400D01*
X510719Y8370D01*
X510819Y8230D01*
X510839Y8190D01*
X510854Y8155D01*
X510874Y8115D01*
X510889Y8075D01*
X510899Y8035D01*
X510914Y7990D01*
X510919Y7950D01*
X510929Y7910D01*
X510934Y7865D01*
Y7825D01*
X510939Y7780D01*
X510934Y7735D01*
Y7695D01*
X510929Y7650D01*
X510919Y7610D01*
X510914Y7570D01*
X510899Y7525D01*
X510889Y7485D01*
X510874Y7445D01*
X510854Y7405D01*
X510839Y7370D01*
X510819Y7330D01*
X510719Y7190D01*
X510689Y7160D01*
Y3730D01*
X510679Y3605D01*
X510639Y3480D01*
X510579Y3370D01*
X510499Y3270D01*
X510399Y3190D01*
X510289Y3130D01*
X510164Y3090D01*
X510039Y3080D01*
G37*
G36*
G01X505315D02*
X505190Y3090D01*
X505065Y3130D01*
X504955Y3190D01*
X504855Y3270D01*
X504775Y3370D01*
X504715Y3480D01*
X504675Y3605D01*
X504665Y3730D01*
Y7160D01*
X504635Y7190D01*
X504535Y7330D01*
X504515Y7370D01*
X504500Y7405D01*
X504480Y7445D01*
X504465Y7485D01*
X504455Y7525D01*
X504440Y7570D01*
X504435Y7610D01*
X504425Y7650D01*
X504420Y7695D01*
Y7735D01*
X504415Y7780D01*
X504420Y7825D01*
Y7865D01*
X504425Y7910D01*
X504435Y7950D01*
X504440Y7990D01*
X504455Y8035D01*
X504465Y8075D01*
X504480Y8115D01*
X504500Y8155D01*
X504515Y8190D01*
X504535Y8230D01*
X504635Y8370D01*
X504665Y8400D01*
Y9530D01*
X504675Y9655D01*
X504715Y9780D01*
X504775Y9890D01*
X504855Y9990D01*
X504955Y10070D01*
X505065Y10130D01*
X505190Y10170D01*
X505315Y10180D01*
X505440Y10170D01*
X505565Y10130D01*
X505675Y10070D01*
X505775Y9990D01*
X505855Y9890D01*
X505915Y9780D01*
X505955Y9655D01*
X505965Y9530D01*
Y8400D01*
X505995Y8370D01*
X506095Y8230D01*
X506115Y8190D01*
X506130Y8155D01*
X506150Y8115D01*
X506165Y8075D01*
X506175Y8035D01*
X506190Y7990D01*
X506195Y7950D01*
X506205Y7910D01*
X506210Y7865D01*
Y7825D01*
X506215Y7780D01*
X506210Y7735D01*
Y7695D01*
X506205Y7650D01*
X506195Y7610D01*
X506190Y7570D01*
X506175Y7525D01*
X506165Y7485D01*
X506150Y7445D01*
X506130Y7405D01*
X506115Y7370D01*
X506095Y7330D01*
X505995Y7190D01*
X505965Y7160D01*
Y3730D01*
X505955Y3605D01*
X505915Y3480D01*
X505855Y3370D01*
X505775Y3270D01*
X505675Y3190D01*
X505565Y3130D01*
X505440Y3090D01*
X505315Y3080D01*
G37*
G36*
G01X524212D02*
X524087Y3090D01*
X523962Y3130D01*
X523852Y3190D01*
X523752Y3270D01*
X523672Y3370D01*
X523612Y3480D01*
X523572Y3605D01*
X523562Y3730D01*
Y7160D01*
X523532Y7190D01*
X523432Y7330D01*
X523412Y7370D01*
X523397Y7405D01*
X523377Y7445D01*
X523362Y7485D01*
X523352Y7525D01*
X523337Y7570D01*
X523332Y7610D01*
X523322Y7650D01*
X523317Y7695D01*
Y7735D01*
X523312Y7780D01*
X523317Y7825D01*
Y7865D01*
X523322Y7910D01*
X523332Y7950D01*
X523337Y7990D01*
X523352Y8035D01*
X523362Y8075D01*
X523377Y8115D01*
X523397Y8155D01*
X523412Y8190D01*
X523432Y8230D01*
X523532Y8370D01*
X523562Y8400D01*
Y9530D01*
X523572Y9655D01*
X523612Y9780D01*
X523672Y9890D01*
X523752Y9990D01*
X523852Y10070D01*
X523962Y10130D01*
X524087Y10170D01*
X524212Y10180D01*
X524337Y10170D01*
X524462Y10130D01*
X524572Y10070D01*
X524672Y9990D01*
X524752Y9890D01*
X524812Y9780D01*
X524852Y9655D01*
X524862Y9530D01*
Y8400D01*
X524892Y8370D01*
X524992Y8230D01*
X525012Y8190D01*
X525027Y8155D01*
X525047Y8115D01*
X525062Y8075D01*
X525072Y8035D01*
X525087Y7990D01*
X525092Y7950D01*
X525102Y7910D01*
X525107Y7865D01*
Y7825D01*
X525112Y7780D01*
X525107Y7735D01*
Y7695D01*
X525102Y7650D01*
X525092Y7610D01*
X525087Y7570D01*
X525072Y7525D01*
X525062Y7485D01*
X525047Y7445D01*
X525027Y7405D01*
X525012Y7370D01*
X524992Y7330D01*
X524892Y7190D01*
X524862Y7160D01*
Y3730D01*
X524852Y3605D01*
X524812Y3480D01*
X524752Y3370D01*
X524672Y3270D01*
X524572Y3190D01*
X524462Y3130D01*
X524337Y3090D01*
X524212Y3080D01*
G37*
G36*
G01X519488D02*
X519363Y3090D01*
X519238Y3130D01*
X519128Y3190D01*
X519028Y3270D01*
X518948Y3370D01*
X518888Y3480D01*
X518848Y3605D01*
X518838Y3730D01*
Y7160D01*
X518808Y7190D01*
X518708Y7330D01*
X518688Y7370D01*
X518673Y7405D01*
X518653Y7445D01*
X518638Y7485D01*
X518628Y7525D01*
X518613Y7570D01*
X518608Y7610D01*
X518598Y7650D01*
X518593Y7695D01*
Y7735D01*
X518588Y7780D01*
X518593Y7825D01*
Y7865D01*
X518598Y7910D01*
X518608Y7950D01*
X518613Y7990D01*
X518628Y8035D01*
X518638Y8075D01*
X518653Y8115D01*
X518673Y8155D01*
X518688Y8190D01*
X518708Y8230D01*
X518808Y8370D01*
X518838Y8400D01*
Y9530D01*
X518848Y9655D01*
X518888Y9780D01*
X518948Y9890D01*
X519028Y9990D01*
X519128Y10070D01*
X519238Y10130D01*
X519363Y10170D01*
X519488Y10180D01*
X519613Y10170D01*
X519738Y10130D01*
X519848Y10070D01*
X519948Y9990D01*
X520028Y9890D01*
X520088Y9780D01*
X520128Y9655D01*
X520138Y9530D01*
Y8400D01*
X520168Y8370D01*
X520268Y8230D01*
X520288Y8190D01*
X520303Y8155D01*
X520323Y8115D01*
X520338Y8075D01*
X520348Y8035D01*
X520363Y7990D01*
X520368Y7950D01*
X520378Y7910D01*
X520383Y7865D01*
Y7825D01*
X520388Y7780D01*
X520383Y7735D01*
Y7695D01*
X520378Y7650D01*
X520368Y7610D01*
X520363Y7570D01*
X520348Y7525D01*
X520338Y7485D01*
X520323Y7445D01*
X520303Y7405D01*
X520288Y7370D01*
X520268Y7330D01*
X520168Y7190D01*
X520138Y7160D01*
Y3730D01*
X520128Y3605D01*
X520088Y3480D01*
X520028Y3370D01*
X519948Y3270D01*
X519848Y3190D01*
X519738Y3130D01*
X519613Y3090D01*
X519488Y3080D01*
G37*
G36*
G01X514764D02*
X514639Y3090D01*
X514514Y3130D01*
X514404Y3190D01*
X514304Y3270D01*
X514224Y3370D01*
X514164Y3480D01*
X514124Y3605D01*
X514114Y3730D01*
Y7160D01*
X514084Y7190D01*
X513984Y7330D01*
X513964Y7370D01*
X513949Y7405D01*
X513929Y7445D01*
X513914Y7485D01*
X513904Y7525D01*
X513889Y7570D01*
X513884Y7610D01*
X513874Y7650D01*
X513869Y7695D01*
Y7735D01*
X513864Y7780D01*
X513869Y7825D01*
Y7865D01*
X513874Y7910D01*
X513884Y7950D01*
X513889Y7990D01*
X513904Y8035D01*
X513914Y8075D01*
X513929Y8115D01*
X513949Y8155D01*
X513964Y8190D01*
X513984Y8230D01*
X514084Y8370D01*
X514114Y8400D01*
Y9530D01*
X514124Y9655D01*
X514164Y9780D01*
X514224Y9890D01*
X514304Y9990D01*
X514404Y10070D01*
X514514Y10130D01*
X514639Y10170D01*
X514764Y10180D01*
X514889Y10170D01*
X515014Y10130D01*
X515124Y10070D01*
X515224Y9990D01*
X515304Y9890D01*
X515364Y9780D01*
X515404Y9655D01*
X515414Y9530D01*
Y8400D01*
X515444Y8370D01*
X515544Y8230D01*
X515564Y8190D01*
X515579Y8155D01*
X515599Y8115D01*
X515614Y8075D01*
X515624Y8035D01*
X515639Y7990D01*
X515644Y7950D01*
X515654Y7910D01*
X515659Y7865D01*
Y7825D01*
X515664Y7780D01*
X515659Y7735D01*
Y7695D01*
X515654Y7650D01*
X515644Y7610D01*
X515639Y7570D01*
X515624Y7525D01*
X515614Y7485D01*
X515599Y7445D01*
X515579Y7405D01*
X515564Y7370D01*
X515544Y7330D01*
X515444Y7190D01*
X515414Y7160D01*
Y3730D01*
X515404Y3605D01*
X515364Y3480D01*
X515304Y3370D01*
X515224Y3270D01*
X515124Y3190D01*
X515014Y3130D01*
X514889Y3090D01*
X514764Y3080D01*
G37*
G36*
G01X538386D02*
X538261Y3090D01*
X538136Y3130D01*
X538026Y3190D01*
X537926Y3270D01*
X537846Y3370D01*
X537786Y3480D01*
X537746Y3605D01*
X537736Y3730D01*
Y7160D01*
X537706Y7190D01*
X537606Y7330D01*
X537586Y7370D01*
X537571Y7405D01*
X537551Y7445D01*
X537536Y7485D01*
X537526Y7525D01*
X537511Y7570D01*
X537506Y7610D01*
X537496Y7650D01*
X537491Y7695D01*
Y7735D01*
X537486Y7780D01*
X537491Y7825D01*
Y7865D01*
X537496Y7910D01*
X537506Y7950D01*
X537511Y7990D01*
X537526Y8035D01*
X537536Y8075D01*
X537551Y8115D01*
X537571Y8155D01*
X537586Y8190D01*
X537606Y8230D01*
X537706Y8370D01*
X537736Y8400D01*
Y9530D01*
X537746Y9655D01*
X537786Y9780D01*
X537846Y9890D01*
X537926Y9990D01*
X538026Y10070D01*
X538136Y10130D01*
X538261Y10170D01*
X538386Y10180D01*
X538511Y10170D01*
X538636Y10130D01*
X538746Y10070D01*
X538846Y9990D01*
X538926Y9890D01*
X538986Y9780D01*
X539026Y9655D01*
X539036Y9530D01*
Y8400D01*
X539066Y8370D01*
X539166Y8230D01*
X539186Y8190D01*
X539201Y8155D01*
X539221Y8115D01*
X539236Y8075D01*
X539246Y8035D01*
X539261Y7990D01*
X539266Y7950D01*
X539276Y7910D01*
X539281Y7865D01*
Y7825D01*
X539286Y7780D01*
X539281Y7735D01*
Y7695D01*
X539276Y7650D01*
X539266Y7610D01*
X539261Y7570D01*
X539246Y7525D01*
X539236Y7485D01*
X539221Y7445D01*
X539201Y7405D01*
X539186Y7370D01*
X539166Y7330D01*
X539066Y7190D01*
X539036Y7160D01*
Y3730D01*
X539026Y3605D01*
X538986Y3480D01*
X538926Y3370D01*
X538846Y3270D01*
X538746Y3190D01*
X538636Y3130D01*
X538511Y3090D01*
X538386Y3080D01*
G37*
G36*
G01X533661D02*
X533536Y3090D01*
X533411Y3130D01*
X533301Y3190D01*
X533201Y3270D01*
X533121Y3370D01*
X533061Y3480D01*
X533021Y3605D01*
X533011Y3730D01*
Y7160D01*
X532981Y7190D01*
X532881Y7330D01*
X532861Y7370D01*
X532846Y7405D01*
X532826Y7445D01*
X532811Y7485D01*
X532801Y7525D01*
X532786Y7570D01*
X532781Y7610D01*
X532771Y7650D01*
X532766Y7695D01*
Y7735D01*
X532761Y7780D01*
X532766Y7825D01*
Y7865D01*
X532771Y7910D01*
X532781Y7950D01*
X532786Y7990D01*
X532801Y8035D01*
X532811Y8075D01*
X532826Y8115D01*
X532846Y8155D01*
X532861Y8190D01*
X532881Y8230D01*
X532981Y8370D01*
X533011Y8400D01*
Y9530D01*
X533021Y9655D01*
X533061Y9780D01*
X533121Y9890D01*
X533201Y9990D01*
X533301Y10070D01*
X533411Y10130D01*
X533536Y10170D01*
X533661Y10180D01*
X533786Y10170D01*
X533911Y10130D01*
X534021Y10070D01*
X534121Y9990D01*
X534201Y9890D01*
X534261Y9780D01*
X534301Y9655D01*
X534311Y9530D01*
Y8400D01*
X534341Y8370D01*
X534441Y8230D01*
X534461Y8190D01*
X534476Y8155D01*
X534496Y8115D01*
X534511Y8075D01*
X534521Y8035D01*
X534536Y7990D01*
X534541Y7950D01*
X534551Y7910D01*
X534556Y7865D01*
Y7825D01*
X534561Y7780D01*
X534556Y7735D01*
Y7695D01*
X534551Y7650D01*
X534541Y7610D01*
X534536Y7570D01*
X534521Y7525D01*
X534511Y7485D01*
X534496Y7445D01*
X534476Y7405D01*
X534461Y7370D01*
X534441Y7330D01*
X534341Y7190D01*
X534311Y7160D01*
Y3730D01*
X534301Y3605D01*
X534261Y3480D01*
X534201Y3370D01*
X534121Y3270D01*
X534021Y3190D01*
X533911Y3130D01*
X533786Y3090D01*
X533661Y3080D01*
G37*
G36*
G01X528937D02*
X528812Y3090D01*
X528687Y3130D01*
X528577Y3190D01*
X528477Y3270D01*
X528397Y3370D01*
X528337Y3480D01*
X528297Y3605D01*
X528287Y3730D01*
Y7160D01*
X528257Y7190D01*
X528157Y7330D01*
X528137Y7370D01*
X528122Y7405D01*
X528102Y7445D01*
X528087Y7485D01*
X528077Y7525D01*
X528062Y7570D01*
X528057Y7610D01*
X528047Y7650D01*
X528042Y7695D01*
Y7735D01*
X528037Y7780D01*
X528042Y7825D01*
Y7865D01*
X528047Y7910D01*
X528057Y7950D01*
X528062Y7990D01*
X528077Y8035D01*
X528087Y8075D01*
X528102Y8115D01*
X528122Y8155D01*
X528137Y8190D01*
X528157Y8230D01*
X528257Y8370D01*
X528287Y8400D01*
Y9530D01*
X528297Y9655D01*
X528337Y9780D01*
X528397Y9890D01*
X528477Y9990D01*
X528577Y10070D01*
X528687Y10130D01*
X528812Y10170D01*
X528937Y10180D01*
X529062Y10170D01*
X529187Y10130D01*
X529297Y10070D01*
X529397Y9990D01*
X529477Y9890D01*
X529537Y9780D01*
X529577Y9655D01*
X529587Y9530D01*
Y8400D01*
X529617Y8370D01*
X529717Y8230D01*
X529737Y8190D01*
X529752Y8155D01*
X529772Y8115D01*
X529787Y8075D01*
X529797Y8035D01*
X529812Y7990D01*
X529817Y7950D01*
X529827Y7910D01*
X529832Y7865D01*
Y7825D01*
X529837Y7780D01*
X529832Y7735D01*
Y7695D01*
X529827Y7650D01*
X529817Y7610D01*
X529812Y7570D01*
X529797Y7525D01*
X529787Y7485D01*
X529772Y7445D01*
X529752Y7405D01*
X529737Y7370D01*
X529717Y7330D01*
X529617Y7190D01*
X529587Y7160D01*
Y3730D01*
X529577Y3605D01*
X529537Y3480D01*
X529477Y3370D01*
X529397Y3270D01*
X529297Y3190D01*
X529187Y3130D01*
X529062Y3090D01*
X528937Y3080D01*
G37*
G36*
G01X557283D02*
X557158Y3090D01*
X557033Y3130D01*
X556923Y3190D01*
X556823Y3270D01*
X556743Y3370D01*
X556683Y3480D01*
X556643Y3605D01*
X556633Y3730D01*
Y7160D01*
X556603Y7190D01*
X556503Y7330D01*
X556483Y7370D01*
X556468Y7405D01*
X556448Y7445D01*
X556433Y7485D01*
X556423Y7525D01*
X556408Y7570D01*
X556403Y7610D01*
X556393Y7650D01*
X556388Y7695D01*
Y7735D01*
X556383Y7780D01*
X556388Y7825D01*
Y7865D01*
X556393Y7910D01*
X556403Y7950D01*
X556408Y7990D01*
X556423Y8035D01*
X556433Y8075D01*
X556448Y8115D01*
X556468Y8155D01*
X556483Y8190D01*
X556503Y8230D01*
X556603Y8370D01*
X556633Y8400D01*
Y9530D01*
X556643Y9655D01*
X556683Y9780D01*
X556743Y9890D01*
X556823Y9990D01*
X556923Y10070D01*
X557033Y10130D01*
X557158Y10170D01*
X557283Y10180D01*
X557408Y10170D01*
X557533Y10130D01*
X557643Y10070D01*
X557743Y9990D01*
X557823Y9890D01*
X557883Y9780D01*
X557923Y9655D01*
X557933Y9530D01*
Y8400D01*
X557963Y8370D01*
X558063Y8230D01*
X558083Y8190D01*
X558098Y8155D01*
X558118Y8115D01*
X558133Y8075D01*
X558143Y8035D01*
X558158Y7990D01*
X558163Y7950D01*
X558173Y7910D01*
X558178Y7865D01*
Y7825D01*
X558183Y7780D01*
X558178Y7735D01*
Y7695D01*
X558173Y7650D01*
X558163Y7610D01*
X558158Y7570D01*
X558143Y7525D01*
X558133Y7485D01*
X558118Y7445D01*
X558098Y7405D01*
X558083Y7370D01*
X558063Y7330D01*
X557963Y7190D01*
X557933Y7160D01*
Y3730D01*
X557923Y3605D01*
X557883Y3480D01*
X557823Y3370D01*
X557743Y3270D01*
X557643Y3190D01*
X557533Y3130D01*
X557408Y3090D01*
X557283Y3080D01*
G37*
G36*
G01X552559D02*
X552434Y3090D01*
X552309Y3130D01*
X552199Y3190D01*
X552099Y3270D01*
X552019Y3370D01*
X551959Y3480D01*
X551919Y3605D01*
X551909Y3730D01*
Y7160D01*
X551879Y7190D01*
X551779Y7330D01*
X551759Y7370D01*
X551744Y7405D01*
X551724Y7445D01*
X551709Y7485D01*
X551699Y7525D01*
X551684Y7570D01*
X551679Y7610D01*
X551669Y7650D01*
X551664Y7695D01*
Y7735D01*
X551659Y7780D01*
X551664Y7825D01*
Y7865D01*
X551669Y7910D01*
X551679Y7950D01*
X551684Y7990D01*
X551699Y8035D01*
X551709Y8075D01*
X551724Y8115D01*
X551744Y8155D01*
X551759Y8190D01*
X551779Y8230D01*
X551879Y8370D01*
X551909Y8400D01*
Y9530D01*
X551919Y9655D01*
X551959Y9780D01*
X552019Y9890D01*
X552099Y9990D01*
X552199Y10070D01*
X552309Y10130D01*
X552434Y10170D01*
X552559Y10180D01*
X552684Y10170D01*
X552809Y10130D01*
X552919Y10070D01*
X553019Y9990D01*
X553099Y9890D01*
X553159Y9780D01*
X553199Y9655D01*
X553209Y9530D01*
Y8400D01*
X553239Y8370D01*
X553339Y8230D01*
X553359Y8190D01*
X553374Y8155D01*
X553394Y8115D01*
X553409Y8075D01*
X553419Y8035D01*
X553434Y7990D01*
X553439Y7950D01*
X553449Y7910D01*
X553454Y7865D01*
Y7825D01*
X553459Y7780D01*
X553454Y7735D01*
Y7695D01*
X553449Y7650D01*
X553439Y7610D01*
X553434Y7570D01*
X553419Y7525D01*
X553409Y7485D01*
X553394Y7445D01*
X553374Y7405D01*
X553359Y7370D01*
X553339Y7330D01*
X553239Y7190D01*
X553209Y7160D01*
Y3730D01*
X553199Y3605D01*
X553159Y3480D01*
X553099Y3370D01*
X553019Y3270D01*
X552919Y3190D01*
X552809Y3130D01*
X552684Y3090D01*
X552559Y3080D01*
G37*
G36*
G01X547834D02*
X547709Y3090D01*
X547584Y3130D01*
X547474Y3190D01*
X547374Y3270D01*
X547294Y3370D01*
X547234Y3480D01*
X547194Y3605D01*
X547184Y3730D01*
Y7160D01*
X547154Y7190D01*
X547054Y7330D01*
X547034Y7370D01*
X547019Y7405D01*
X546999Y7445D01*
X546984Y7485D01*
X546974Y7525D01*
X546959Y7570D01*
X546954Y7610D01*
X546944Y7650D01*
X546939Y7695D01*
Y7735D01*
X546934Y7780D01*
X546939Y7825D01*
Y7865D01*
X546944Y7910D01*
X546954Y7950D01*
X546959Y7990D01*
X546974Y8035D01*
X546984Y8075D01*
X546999Y8115D01*
X547019Y8155D01*
X547034Y8190D01*
X547054Y8230D01*
X547154Y8370D01*
X547184Y8400D01*
Y9530D01*
X547194Y9655D01*
X547234Y9780D01*
X547294Y9890D01*
X547374Y9990D01*
X547474Y10070D01*
X547584Y10130D01*
X547709Y10170D01*
X547834Y10180D01*
X547959Y10170D01*
X548084Y10130D01*
X548194Y10070D01*
X548294Y9990D01*
X548374Y9890D01*
X548434Y9780D01*
X548474Y9655D01*
X548484Y9530D01*
Y8400D01*
X548514Y8370D01*
X548614Y8230D01*
X548634Y8190D01*
X548649Y8155D01*
X548669Y8115D01*
X548684Y8075D01*
X548694Y8035D01*
X548709Y7990D01*
X548714Y7950D01*
X548724Y7910D01*
X548729Y7865D01*
Y7825D01*
X548734Y7780D01*
X548729Y7735D01*
Y7695D01*
X548724Y7650D01*
X548714Y7610D01*
X548709Y7570D01*
X548694Y7525D01*
X548684Y7485D01*
X548669Y7445D01*
X548649Y7405D01*
X548634Y7370D01*
X548614Y7330D01*
X548514Y7190D01*
X548484Y7160D01*
Y3730D01*
X548474Y3605D01*
X548434Y3480D01*
X548374Y3370D01*
X548294Y3270D01*
X548194Y3190D01*
X548084Y3130D01*
X547959Y3090D01*
X547834Y3080D01*
G37*
G36*
G01X543110D02*
X542985Y3090D01*
X542860Y3130D01*
X542750Y3190D01*
X542650Y3270D01*
X542570Y3370D01*
X542510Y3480D01*
X542470Y3605D01*
X542460Y3730D01*
Y7160D01*
X542430Y7190D01*
X542330Y7330D01*
X542310Y7370D01*
X542295Y7405D01*
X542275Y7445D01*
X542260Y7485D01*
X542250Y7525D01*
X542235Y7570D01*
X542230Y7610D01*
X542220Y7650D01*
X542215Y7695D01*
Y7735D01*
X542210Y7780D01*
X542215Y7825D01*
Y7865D01*
X542220Y7910D01*
X542230Y7950D01*
X542235Y7990D01*
X542250Y8035D01*
X542260Y8075D01*
X542275Y8115D01*
X542295Y8155D01*
X542310Y8190D01*
X542330Y8230D01*
X542430Y8370D01*
X542460Y8400D01*
Y9530D01*
X542470Y9655D01*
X542510Y9780D01*
X542570Y9890D01*
X542650Y9990D01*
X542750Y10070D01*
X542860Y10130D01*
X542985Y10170D01*
X543110Y10180D01*
X543235Y10170D01*
X543360Y10130D01*
X543470Y10070D01*
X543570Y9990D01*
X543650Y9890D01*
X543710Y9780D01*
X543750Y9655D01*
X543760Y9530D01*
Y8400D01*
X543790Y8370D01*
X543890Y8230D01*
X543910Y8190D01*
X543925Y8155D01*
X543945Y8115D01*
X543960Y8075D01*
X543970Y8035D01*
X543985Y7990D01*
X543990Y7950D01*
X544000Y7910D01*
X544005Y7865D01*
Y7825D01*
X544010Y7780D01*
X544005Y7735D01*
Y7695D01*
X544000Y7650D01*
X543990Y7610D01*
X543985Y7570D01*
X543970Y7525D01*
X543960Y7485D01*
X543945Y7445D01*
X543925Y7405D01*
X543910Y7370D01*
X543890Y7330D01*
X543790Y7190D01*
X543760Y7160D01*
Y3730D01*
X543750Y3605D01*
X543710Y3480D01*
X543650Y3370D01*
X543570Y3270D01*
X543470Y3190D01*
X543360Y3130D01*
X543235Y3090D01*
X543110Y3080D01*
G37*
G36*
G01X571456D02*
X571331Y3090D01*
X571206Y3130D01*
X571096Y3190D01*
X570996Y3270D01*
X570916Y3370D01*
X570856Y3480D01*
X570816Y3605D01*
X570806Y3730D01*
Y7160D01*
X570776Y7190D01*
X570676Y7330D01*
X570656Y7370D01*
X570641Y7405D01*
X570621Y7445D01*
X570606Y7485D01*
X570596Y7525D01*
X570581Y7570D01*
X570576Y7610D01*
X570566Y7650D01*
X570561Y7695D01*
Y7735D01*
X570556Y7780D01*
X570561Y7825D01*
Y7865D01*
X570566Y7910D01*
X570576Y7950D01*
X570581Y7990D01*
X570596Y8035D01*
X570606Y8075D01*
X570621Y8115D01*
X570641Y8155D01*
X570656Y8190D01*
X570676Y8230D01*
X570776Y8370D01*
X570806Y8400D01*
Y9530D01*
X570816Y9655D01*
X570856Y9780D01*
X570916Y9890D01*
X570996Y9990D01*
X571096Y10070D01*
X571206Y10130D01*
X571331Y10170D01*
X571456Y10180D01*
X571581Y10170D01*
X571706Y10130D01*
X571816Y10070D01*
X571916Y9990D01*
X571996Y9890D01*
X572056Y9780D01*
X572096Y9655D01*
X572106Y9530D01*
Y8400D01*
X572136Y8370D01*
X572236Y8230D01*
X572256Y8190D01*
X572271Y8155D01*
X572291Y8115D01*
X572306Y8075D01*
X572316Y8035D01*
X572331Y7990D01*
X572336Y7950D01*
X572346Y7910D01*
X572351Y7865D01*
Y7825D01*
X572356Y7780D01*
X572351Y7735D01*
Y7695D01*
X572346Y7650D01*
X572336Y7610D01*
X572331Y7570D01*
X572316Y7525D01*
X572306Y7485D01*
X572291Y7445D01*
X572271Y7405D01*
X572256Y7370D01*
X572236Y7330D01*
X572136Y7190D01*
X572106Y7160D01*
Y3730D01*
X572096Y3605D01*
X572056Y3480D01*
X571996Y3370D01*
X571916Y3270D01*
X571816Y3190D01*
X571706Y3130D01*
X571581Y3090D01*
X571456Y3080D01*
G37*
G36*
G01X566732D02*
X566607Y3090D01*
X566482Y3130D01*
X566372Y3190D01*
X566272Y3270D01*
X566192Y3370D01*
X566132Y3480D01*
X566092Y3605D01*
X566082Y3730D01*
Y7160D01*
X566052Y7190D01*
X565952Y7330D01*
X565932Y7370D01*
X565917Y7405D01*
X565897Y7445D01*
X565882Y7485D01*
X565872Y7525D01*
X565857Y7570D01*
X565852Y7610D01*
X565842Y7650D01*
X565837Y7695D01*
Y7735D01*
X565832Y7780D01*
X565837Y7825D01*
Y7865D01*
X565842Y7910D01*
X565852Y7950D01*
X565857Y7990D01*
X565872Y8035D01*
X565882Y8075D01*
X565897Y8115D01*
X565917Y8155D01*
X565932Y8190D01*
X565952Y8230D01*
X566052Y8370D01*
X566082Y8400D01*
Y9530D01*
X566092Y9655D01*
X566132Y9780D01*
X566192Y9890D01*
X566272Y9990D01*
X566372Y10070D01*
X566482Y10130D01*
X566607Y10170D01*
X566732Y10180D01*
X566857Y10170D01*
X566982Y10130D01*
X567092Y10070D01*
X567192Y9990D01*
X567272Y9890D01*
X567332Y9780D01*
X567372Y9655D01*
X567382Y9530D01*
Y8400D01*
X567412Y8370D01*
X567512Y8230D01*
X567532Y8190D01*
X567547Y8155D01*
X567567Y8115D01*
X567582Y8075D01*
X567592Y8035D01*
X567607Y7990D01*
X567612Y7950D01*
X567622Y7910D01*
X567627Y7865D01*
Y7825D01*
X567632Y7780D01*
X567627Y7735D01*
Y7695D01*
X567622Y7650D01*
X567612Y7610D01*
X567607Y7570D01*
X567592Y7525D01*
X567582Y7485D01*
X567567Y7445D01*
X567547Y7405D01*
X567532Y7370D01*
X567512Y7330D01*
X567412Y7190D01*
X567382Y7160D01*
Y3730D01*
X567372Y3605D01*
X567332Y3480D01*
X567272Y3370D01*
X567192Y3270D01*
X567092Y3190D01*
X566982Y3130D01*
X566857Y3090D01*
X566732Y3080D01*
G37*
G36*
G01X562008D02*
X561883Y3090D01*
X561758Y3130D01*
X561648Y3190D01*
X561548Y3270D01*
X561468Y3370D01*
X561408Y3480D01*
X561368Y3605D01*
X561358Y3730D01*
Y7160D01*
X561328Y7190D01*
X561228Y7330D01*
X561208Y7370D01*
X561193Y7405D01*
X561173Y7445D01*
X561158Y7485D01*
X561148Y7525D01*
X561133Y7570D01*
X561128Y7610D01*
X561118Y7650D01*
X561113Y7695D01*
Y7735D01*
X561108Y7780D01*
X561113Y7825D01*
Y7865D01*
X561118Y7910D01*
X561128Y7950D01*
X561133Y7990D01*
X561148Y8035D01*
X561158Y8075D01*
X561173Y8115D01*
X561193Y8155D01*
X561208Y8190D01*
X561228Y8230D01*
X561328Y8370D01*
X561358Y8400D01*
Y9530D01*
X561368Y9655D01*
X561408Y9780D01*
X561468Y9890D01*
X561548Y9990D01*
X561648Y10070D01*
X561758Y10130D01*
X561883Y10170D01*
X562008Y10180D01*
X562133Y10170D01*
X562258Y10130D01*
X562368Y10070D01*
X562468Y9990D01*
X562548Y9890D01*
X562608Y9780D01*
X562648Y9655D01*
X562658Y9530D01*
Y8400D01*
X562688Y8370D01*
X562788Y8230D01*
X562808Y8190D01*
X562823Y8155D01*
X562843Y8115D01*
X562858Y8075D01*
X562868Y8035D01*
X562883Y7990D01*
X562888Y7950D01*
X562898Y7910D01*
X562903Y7865D01*
Y7825D01*
X562908Y7780D01*
X562903Y7735D01*
Y7695D01*
X562898Y7650D01*
X562888Y7610D01*
X562883Y7570D01*
X562868Y7525D01*
X562858Y7485D01*
X562843Y7445D01*
X562823Y7405D01*
X562808Y7370D01*
X562788Y7330D01*
X562688Y7190D01*
X562658Y7160D01*
Y3730D01*
X562648Y3605D01*
X562608Y3480D01*
X562548Y3370D01*
X562468Y3270D01*
X562368Y3190D01*
X562258Y3130D01*
X562133Y3090D01*
X562008Y3080D01*
G37*
G36*
G01X585630D02*
X585505Y3090D01*
X585380Y3130D01*
X585270Y3190D01*
X585170Y3270D01*
X585090Y3370D01*
X585030Y3480D01*
X584990Y3605D01*
X584980Y3730D01*
Y7160D01*
X584950Y7190D01*
X584850Y7330D01*
X584830Y7370D01*
X584815Y7405D01*
X584795Y7445D01*
X584780Y7485D01*
X584770Y7525D01*
X584755Y7570D01*
X584750Y7610D01*
X584740Y7650D01*
X584735Y7695D01*
Y7735D01*
X584730Y7780D01*
X584735Y7825D01*
Y7865D01*
X584740Y7910D01*
X584750Y7950D01*
X584755Y7990D01*
X584770Y8035D01*
X584780Y8075D01*
X584795Y8115D01*
X584815Y8155D01*
X584830Y8190D01*
X584850Y8230D01*
X584950Y8370D01*
X584980Y8400D01*
Y9530D01*
X584990Y9655D01*
X585030Y9780D01*
X585090Y9890D01*
X585170Y9990D01*
X585270Y10070D01*
X585380Y10130D01*
X585505Y10170D01*
X585630Y10180D01*
X585755Y10170D01*
X585880Y10130D01*
X585990Y10070D01*
X586090Y9990D01*
X586170Y9890D01*
X586230Y9780D01*
X586270Y9655D01*
X586280Y9530D01*
Y8400D01*
X586310Y8370D01*
X586410Y8230D01*
X586430Y8190D01*
X586445Y8155D01*
X586465Y8115D01*
X586480Y8075D01*
X586490Y8035D01*
X586505Y7990D01*
X586510Y7950D01*
X586520Y7910D01*
X586525Y7865D01*
Y7825D01*
X586530Y7780D01*
X586525Y7735D01*
Y7695D01*
X586520Y7650D01*
X586510Y7610D01*
X586505Y7570D01*
X586490Y7525D01*
X586480Y7485D01*
X586465Y7445D01*
X586445Y7405D01*
X586430Y7370D01*
X586410Y7330D01*
X586310Y7190D01*
X586280Y7160D01*
Y3730D01*
X586270Y3605D01*
X586230Y3480D01*
X586170Y3370D01*
X586090Y3270D01*
X585990Y3190D01*
X585880Y3130D01*
X585755Y3090D01*
X585630Y3080D01*
G37*
G36*
G01X580905D02*
X580780Y3090D01*
X580655Y3130D01*
X580545Y3190D01*
X580445Y3270D01*
X580365Y3370D01*
X580305Y3480D01*
X580265Y3605D01*
X580255Y3730D01*
Y7160D01*
X580225Y7190D01*
X580125Y7330D01*
X580105Y7370D01*
X580090Y7405D01*
X580070Y7445D01*
X580055Y7485D01*
X580045Y7525D01*
X580030Y7570D01*
X580025Y7610D01*
X580015Y7650D01*
X580010Y7695D01*
Y7735D01*
X580005Y7780D01*
X580010Y7825D01*
Y7865D01*
X580015Y7910D01*
X580025Y7950D01*
X580030Y7990D01*
X580045Y8035D01*
X580055Y8075D01*
X580070Y8115D01*
X580090Y8155D01*
X580105Y8190D01*
X580125Y8230D01*
X580225Y8370D01*
X580255Y8400D01*
Y9530D01*
X580265Y9655D01*
X580305Y9780D01*
X580365Y9890D01*
X580445Y9990D01*
X580545Y10070D01*
X580655Y10130D01*
X580780Y10170D01*
X580905Y10180D01*
X581030Y10170D01*
X581155Y10130D01*
X581265Y10070D01*
X581365Y9990D01*
X581445Y9890D01*
X581505Y9780D01*
X581545Y9655D01*
X581555Y9530D01*
Y8400D01*
X581585Y8370D01*
X581685Y8230D01*
X581705Y8190D01*
X581720Y8155D01*
X581740Y8115D01*
X581755Y8075D01*
X581765Y8035D01*
X581780Y7990D01*
X581785Y7950D01*
X581795Y7910D01*
X581800Y7865D01*
Y7825D01*
X581805Y7780D01*
X581800Y7735D01*
Y7695D01*
X581795Y7650D01*
X581785Y7610D01*
X581780Y7570D01*
X581765Y7525D01*
X581755Y7485D01*
X581740Y7445D01*
X581720Y7405D01*
X581705Y7370D01*
X581685Y7330D01*
X581585Y7190D01*
X581555Y7160D01*
Y3730D01*
X581545Y3605D01*
X581505Y3480D01*
X581445Y3370D01*
X581365Y3270D01*
X581265Y3190D01*
X581155Y3130D01*
X581030Y3090D01*
X580905Y3080D01*
G37*
G36*
G01X576181D02*
X576056Y3090D01*
X575931Y3130D01*
X575821Y3190D01*
X575721Y3270D01*
X575641Y3370D01*
X575581Y3480D01*
X575541Y3605D01*
X575531Y3730D01*
Y7160D01*
X575501Y7190D01*
X575401Y7330D01*
X575381Y7370D01*
X575366Y7405D01*
X575346Y7445D01*
X575331Y7485D01*
X575321Y7525D01*
X575306Y7570D01*
X575301Y7610D01*
X575291Y7650D01*
X575286Y7695D01*
Y7735D01*
X575281Y7780D01*
X575286Y7825D01*
Y7865D01*
X575291Y7910D01*
X575301Y7950D01*
X575306Y7990D01*
X575321Y8035D01*
X575331Y8075D01*
X575346Y8115D01*
X575366Y8155D01*
X575381Y8190D01*
X575401Y8230D01*
X575501Y8370D01*
X575531Y8400D01*
Y9530D01*
X575541Y9655D01*
X575581Y9780D01*
X575641Y9890D01*
X575721Y9990D01*
X575821Y10070D01*
X575931Y10130D01*
X576056Y10170D01*
X576181Y10180D01*
X576306Y10170D01*
X576431Y10130D01*
X576541Y10070D01*
X576641Y9990D01*
X576721Y9890D01*
X576781Y9780D01*
X576821Y9655D01*
X576831Y9530D01*
Y8400D01*
X576861Y8370D01*
X576961Y8230D01*
X576981Y8190D01*
X576996Y8155D01*
X577016Y8115D01*
X577031Y8075D01*
X577041Y8035D01*
X577056Y7990D01*
X577061Y7950D01*
X577071Y7910D01*
X577076Y7865D01*
Y7825D01*
X577081Y7780D01*
X577076Y7735D01*
Y7695D01*
X577071Y7650D01*
X577061Y7610D01*
X577056Y7570D01*
X577041Y7525D01*
X577031Y7485D01*
X577016Y7445D01*
X576996Y7405D01*
X576981Y7370D01*
X576961Y7330D01*
X576861Y7190D01*
X576831Y7160D01*
Y3730D01*
X576821Y3605D01*
X576781Y3480D01*
X576721Y3370D01*
X576641Y3270D01*
X576541Y3190D01*
X576431Y3130D01*
X576306Y3090D01*
X576181Y3080D01*
G37*
G36*
G01X599803D02*
X599678Y3090D01*
X599553Y3130D01*
X599443Y3190D01*
X599343Y3270D01*
X599263Y3370D01*
X599203Y3480D01*
X599163Y3605D01*
X599153Y3730D01*
Y7160D01*
X599123Y7190D01*
X599023Y7330D01*
X599003Y7370D01*
X598988Y7405D01*
X598968Y7445D01*
X598953Y7485D01*
X598943Y7525D01*
X598928Y7570D01*
X598923Y7610D01*
X598913Y7650D01*
X598908Y7695D01*
Y7735D01*
X598903Y7780D01*
X598908Y7825D01*
Y7865D01*
X598913Y7910D01*
X598923Y7950D01*
X598928Y7990D01*
X598943Y8035D01*
X598953Y8075D01*
X598968Y8115D01*
X598988Y8155D01*
X599003Y8190D01*
X599023Y8230D01*
X599123Y8370D01*
X599153Y8400D01*
Y9530D01*
X599163Y9655D01*
X599203Y9780D01*
X599263Y9890D01*
X599343Y9990D01*
X599443Y10070D01*
X599553Y10130D01*
X599678Y10170D01*
X599803Y10180D01*
X599928Y10170D01*
X600053Y10130D01*
X600163Y10070D01*
X600263Y9990D01*
X600343Y9890D01*
X600403Y9780D01*
X600443Y9655D01*
X600453Y9530D01*
Y8400D01*
X600483Y8370D01*
X600583Y8230D01*
X600603Y8190D01*
X600618Y8155D01*
X600638Y8115D01*
X600653Y8075D01*
X600663Y8035D01*
X600678Y7990D01*
X600683Y7950D01*
X600693Y7910D01*
X600698Y7865D01*
Y7825D01*
X600703Y7780D01*
X600698Y7735D01*
Y7695D01*
X600693Y7650D01*
X600683Y7610D01*
X600678Y7570D01*
X600663Y7525D01*
X600653Y7485D01*
X600638Y7445D01*
X600618Y7405D01*
X600603Y7370D01*
X600583Y7330D01*
X600483Y7190D01*
X600453Y7160D01*
Y3730D01*
X600443Y3605D01*
X600403Y3480D01*
X600343Y3370D01*
X600263Y3270D01*
X600163Y3190D01*
X600053Y3130D01*
X599928Y3090D01*
X599803Y3080D01*
G37*
G36*
G01X618701D02*
X618576Y3090D01*
X618451Y3130D01*
X618341Y3190D01*
X618241Y3270D01*
X618161Y3370D01*
X618101Y3480D01*
X618061Y3605D01*
X618051Y3730D01*
Y7160D01*
X618021Y7190D01*
X617921Y7330D01*
X617901Y7370D01*
X617886Y7405D01*
X617866Y7445D01*
X617851Y7485D01*
X617841Y7525D01*
X617826Y7570D01*
X617821Y7610D01*
X617811Y7650D01*
X617806Y7695D01*
Y7735D01*
X617801Y7780D01*
X617806Y7825D01*
Y7865D01*
X617811Y7910D01*
X617821Y7950D01*
X617826Y7990D01*
X617841Y8035D01*
X617851Y8075D01*
X617866Y8115D01*
X617886Y8155D01*
X617901Y8190D01*
X617921Y8230D01*
X618021Y8370D01*
X618051Y8400D01*
Y9530D01*
X618061Y9655D01*
X618101Y9780D01*
X618161Y9890D01*
X618241Y9990D01*
X618341Y10070D01*
X618451Y10130D01*
X618576Y10170D01*
X618701Y10180D01*
X618826Y10170D01*
X618951Y10130D01*
X619061Y10070D01*
X619161Y9990D01*
X619241Y9890D01*
X619301Y9780D01*
X619341Y9655D01*
X619351Y9530D01*
Y8400D01*
X619381Y8370D01*
X619481Y8230D01*
X619501Y8190D01*
X619516Y8155D01*
X619536Y8115D01*
X619551Y8075D01*
X619561Y8035D01*
X619576Y7990D01*
X619581Y7950D01*
X619591Y7910D01*
X619596Y7865D01*
Y7825D01*
X619601Y7780D01*
X619596Y7735D01*
Y7695D01*
X619591Y7650D01*
X619581Y7610D01*
X619576Y7570D01*
X619561Y7525D01*
X619551Y7485D01*
X619536Y7445D01*
X619516Y7405D01*
X619501Y7370D01*
X619481Y7330D01*
X619381Y7190D01*
X619351Y7160D01*
Y3730D01*
X619341Y3605D01*
X619301Y3480D01*
X619241Y3370D01*
X619161Y3270D01*
X619061Y3190D01*
X618951Y3130D01*
X618826Y3090D01*
X618701Y3080D01*
G37*
G36*
G01X613976D02*
X613851Y3090D01*
X613726Y3130D01*
X613616Y3190D01*
X613516Y3270D01*
X613436Y3370D01*
X613376Y3480D01*
X613336Y3605D01*
X613326Y3730D01*
Y7160D01*
X613296Y7190D01*
X613196Y7330D01*
X613176Y7370D01*
X613161Y7405D01*
X613141Y7445D01*
X613126Y7485D01*
X613116Y7525D01*
X613101Y7570D01*
X613096Y7610D01*
X613086Y7650D01*
X613081Y7695D01*
Y7735D01*
X613076Y7780D01*
X613081Y7825D01*
Y7865D01*
X613086Y7910D01*
X613096Y7950D01*
X613101Y7990D01*
X613116Y8035D01*
X613126Y8075D01*
X613141Y8115D01*
X613161Y8155D01*
X613176Y8190D01*
X613196Y8230D01*
X613296Y8370D01*
X613326Y8400D01*
Y9530D01*
X613336Y9655D01*
X613376Y9780D01*
X613436Y9890D01*
X613516Y9990D01*
X613616Y10070D01*
X613726Y10130D01*
X613851Y10170D01*
X613976Y10180D01*
X614101Y10170D01*
X614226Y10130D01*
X614336Y10070D01*
X614436Y9990D01*
X614516Y9890D01*
X614576Y9780D01*
X614616Y9655D01*
X614626Y9530D01*
Y8400D01*
X614656Y8370D01*
X614756Y8230D01*
X614776Y8190D01*
X614791Y8155D01*
X614811Y8115D01*
X614826Y8075D01*
X614836Y8035D01*
X614851Y7990D01*
X614856Y7950D01*
X614866Y7910D01*
X614871Y7865D01*
Y7825D01*
X614876Y7780D01*
X614871Y7735D01*
Y7695D01*
X614866Y7650D01*
X614856Y7610D01*
X614851Y7570D01*
X614836Y7525D01*
X614826Y7485D01*
X614811Y7445D01*
X614791Y7405D01*
X614776Y7370D01*
X614756Y7330D01*
X614656Y7190D01*
X614626Y7160D01*
Y3730D01*
X614616Y3605D01*
X614576Y3480D01*
X614516Y3370D01*
X614436Y3270D01*
X614336Y3190D01*
X614226Y3130D01*
X614101Y3090D01*
X613976Y3080D01*
G37*
G36*
G01X609252D02*
X609127Y3090D01*
X609002Y3130D01*
X608892Y3190D01*
X608792Y3270D01*
X608712Y3370D01*
X608652Y3480D01*
X608612Y3605D01*
X608602Y3730D01*
Y7160D01*
X608572Y7190D01*
X608472Y7330D01*
X608452Y7370D01*
X608437Y7405D01*
X608417Y7445D01*
X608402Y7485D01*
X608392Y7525D01*
X608377Y7570D01*
X608372Y7610D01*
X608362Y7650D01*
X608357Y7695D01*
Y7735D01*
X608352Y7780D01*
X608357Y7825D01*
Y7865D01*
X608362Y7910D01*
X608372Y7950D01*
X608377Y7990D01*
X608392Y8035D01*
X608402Y8075D01*
X608417Y8115D01*
X608437Y8155D01*
X608452Y8190D01*
X608472Y8230D01*
X608572Y8370D01*
X608602Y8400D01*
Y9530D01*
X608612Y9655D01*
X608652Y9780D01*
X608712Y9890D01*
X608792Y9990D01*
X608892Y10070D01*
X609002Y10130D01*
X609127Y10170D01*
X609252Y10180D01*
X609377Y10170D01*
X609502Y10130D01*
X609612Y10070D01*
X609712Y9990D01*
X609792Y9890D01*
X609852Y9780D01*
X609892Y9655D01*
X609902Y9530D01*
Y8400D01*
X609932Y8370D01*
X610032Y8230D01*
X610052Y8190D01*
X610067Y8155D01*
X610087Y8115D01*
X610102Y8075D01*
X610112Y8035D01*
X610127Y7990D01*
X610132Y7950D01*
X610142Y7910D01*
X610147Y7865D01*
Y7825D01*
X610152Y7780D01*
X610147Y7735D01*
Y7695D01*
X610142Y7650D01*
X610132Y7610D01*
X610127Y7570D01*
X610112Y7525D01*
X610102Y7485D01*
X610087Y7445D01*
X610067Y7405D01*
X610052Y7370D01*
X610032Y7330D01*
X609932Y7190D01*
X609902Y7160D01*
Y3730D01*
X609892Y3605D01*
X609852Y3480D01*
X609792Y3370D01*
X609712Y3270D01*
X609612Y3190D01*
X609502Y3130D01*
X609377Y3090D01*
X609252Y3080D01*
G37*
G36*
G01X604527D02*
X604402Y3090D01*
X604277Y3130D01*
X604167Y3190D01*
X604067Y3270D01*
X603987Y3370D01*
X603927Y3480D01*
X603887Y3605D01*
X603877Y3730D01*
Y7160D01*
X603847Y7190D01*
X603747Y7330D01*
X603727Y7370D01*
X603712Y7405D01*
X603692Y7445D01*
X603677Y7485D01*
X603667Y7525D01*
X603652Y7570D01*
X603647Y7610D01*
X603637Y7650D01*
X603632Y7695D01*
Y7735D01*
X603627Y7780D01*
X603632Y7825D01*
Y7865D01*
X603637Y7910D01*
X603647Y7950D01*
X603652Y7990D01*
X603667Y8035D01*
X603677Y8075D01*
X603692Y8115D01*
X603712Y8155D01*
X603727Y8190D01*
X603747Y8230D01*
X603847Y8370D01*
X603877Y8400D01*
Y9530D01*
X603887Y9655D01*
X603927Y9780D01*
X603987Y9890D01*
X604067Y9990D01*
X604167Y10070D01*
X604277Y10130D01*
X604402Y10170D01*
X604527Y10180D01*
X604652Y10170D01*
X604777Y10130D01*
X604887Y10070D01*
X604987Y9990D01*
X605067Y9890D01*
X605127Y9780D01*
X605167Y9655D01*
X605177Y9530D01*
Y8400D01*
X605207Y8370D01*
X605307Y8230D01*
X605327Y8190D01*
X605342Y8155D01*
X605362Y8115D01*
X605377Y8075D01*
X605387Y8035D01*
X605402Y7990D01*
X605407Y7950D01*
X605417Y7910D01*
X605422Y7865D01*
Y7825D01*
X605427Y7780D01*
X605422Y7735D01*
Y7695D01*
X605417Y7650D01*
X605407Y7610D01*
X605402Y7570D01*
X605387Y7525D01*
X605377Y7485D01*
X605362Y7445D01*
X605342Y7405D01*
X605327Y7370D01*
X605307Y7330D01*
X605207Y7190D01*
X605177Y7160D01*
Y3730D01*
X605167Y3605D01*
X605127Y3480D01*
X605067Y3370D01*
X604987Y3270D01*
X604887Y3190D01*
X604777Y3130D01*
X604652Y3090D01*
X604527Y3080D01*
G37*
G36*
G01X632874D02*
X632749Y3090D01*
X632624Y3130D01*
X632514Y3190D01*
X632414Y3270D01*
X632334Y3370D01*
X632274Y3480D01*
X632234Y3605D01*
X632224Y3730D01*
Y7160D01*
X632194Y7190D01*
X632094Y7330D01*
X632074Y7370D01*
X632059Y7405D01*
X632039Y7445D01*
X632024Y7485D01*
X632014Y7525D01*
X631999Y7570D01*
X631994Y7610D01*
X631984Y7650D01*
X631979Y7695D01*
Y7735D01*
X631974Y7780D01*
X631979Y7825D01*
Y7865D01*
X631984Y7910D01*
X631994Y7950D01*
X631999Y7990D01*
X632014Y8035D01*
X632024Y8075D01*
X632039Y8115D01*
X632059Y8155D01*
X632074Y8190D01*
X632094Y8230D01*
X632194Y8370D01*
X632224Y8400D01*
Y9530D01*
X632234Y9655D01*
X632274Y9780D01*
X632334Y9890D01*
X632414Y9990D01*
X632514Y10070D01*
X632624Y10130D01*
X632749Y10170D01*
X632874Y10180D01*
X632999Y10170D01*
X633124Y10130D01*
X633234Y10070D01*
X633334Y9990D01*
X633414Y9890D01*
X633474Y9780D01*
X633514Y9655D01*
X633524Y9530D01*
Y8400D01*
X633554Y8370D01*
X633654Y8230D01*
X633674Y8190D01*
X633689Y8155D01*
X633709Y8115D01*
X633724Y8075D01*
X633734Y8035D01*
X633749Y7990D01*
X633754Y7950D01*
X633764Y7910D01*
X633769Y7865D01*
Y7825D01*
X633774Y7780D01*
X633769Y7735D01*
Y7695D01*
X633764Y7650D01*
X633754Y7610D01*
X633749Y7570D01*
X633734Y7525D01*
X633724Y7485D01*
X633709Y7445D01*
X633689Y7405D01*
X633674Y7370D01*
X633654Y7330D01*
X633554Y7190D01*
X633524Y7160D01*
Y3730D01*
X633514Y3605D01*
X633474Y3480D01*
X633414Y3370D01*
X633334Y3270D01*
X633234Y3190D01*
X633124Y3130D01*
X632999Y3090D01*
X632874Y3080D01*
G37*
G36*
G01X628149D02*
X628024Y3090D01*
X627899Y3130D01*
X627789Y3190D01*
X627689Y3270D01*
X627609Y3370D01*
X627549Y3480D01*
X627509Y3605D01*
X627499Y3730D01*
Y7160D01*
X627469Y7190D01*
X627369Y7330D01*
X627349Y7370D01*
X627334Y7405D01*
X627314Y7445D01*
X627299Y7485D01*
X627289Y7525D01*
X627274Y7570D01*
X627269Y7610D01*
X627259Y7650D01*
X627254Y7695D01*
Y7735D01*
X627249Y7780D01*
X627254Y7825D01*
Y7865D01*
X627259Y7910D01*
X627269Y7950D01*
X627274Y7990D01*
X627289Y8035D01*
X627299Y8075D01*
X627314Y8115D01*
X627334Y8155D01*
X627349Y8190D01*
X627369Y8230D01*
X627469Y8370D01*
X627499Y8400D01*
Y9530D01*
X627509Y9655D01*
X627549Y9780D01*
X627609Y9890D01*
X627689Y9990D01*
X627789Y10070D01*
X627899Y10130D01*
X628024Y10170D01*
X628149Y10180D01*
X628274Y10170D01*
X628399Y10130D01*
X628509Y10070D01*
X628609Y9990D01*
X628689Y9890D01*
X628749Y9780D01*
X628789Y9655D01*
X628799Y9530D01*
Y8400D01*
X628829Y8370D01*
X628929Y8230D01*
X628949Y8190D01*
X628964Y8155D01*
X628984Y8115D01*
X628999Y8075D01*
X629009Y8035D01*
X629024Y7990D01*
X629029Y7950D01*
X629039Y7910D01*
X629044Y7865D01*
Y7825D01*
X629049Y7780D01*
X629044Y7735D01*
Y7695D01*
X629039Y7650D01*
X629029Y7610D01*
X629024Y7570D01*
X629009Y7525D01*
X628999Y7485D01*
X628984Y7445D01*
X628964Y7405D01*
X628949Y7370D01*
X628929Y7330D01*
X628829Y7190D01*
X628799Y7160D01*
Y3730D01*
X628789Y3605D01*
X628749Y3480D01*
X628689Y3370D01*
X628609Y3270D01*
X628509Y3190D01*
X628399Y3130D01*
X628274Y3090D01*
X628149Y3080D01*
G37*
G36*
G01X623425D02*
X623300Y3090D01*
X623175Y3130D01*
X623065Y3190D01*
X622965Y3270D01*
X622885Y3370D01*
X622825Y3480D01*
X622785Y3605D01*
X622775Y3730D01*
Y7160D01*
X622745Y7190D01*
X622645Y7330D01*
X622625Y7370D01*
X622610Y7405D01*
X622590Y7445D01*
X622575Y7485D01*
X622565Y7525D01*
X622550Y7570D01*
X622545Y7610D01*
X622535Y7650D01*
X622530Y7695D01*
Y7735D01*
X622525Y7780D01*
X622530Y7825D01*
Y7865D01*
X622535Y7910D01*
X622545Y7950D01*
X622550Y7990D01*
X622565Y8035D01*
X622575Y8075D01*
X622590Y8115D01*
X622610Y8155D01*
X622625Y8190D01*
X622645Y8230D01*
X622745Y8370D01*
X622775Y8400D01*
Y9530D01*
X622785Y9655D01*
X622825Y9780D01*
X622885Y9890D01*
X622965Y9990D01*
X623065Y10070D01*
X623175Y10130D01*
X623300Y10170D01*
X623425Y10180D01*
X623550Y10170D01*
X623675Y10130D01*
X623785Y10070D01*
X623885Y9990D01*
X623965Y9890D01*
X624025Y9780D01*
X624065Y9655D01*
X624075Y9530D01*
Y8400D01*
X624105Y8370D01*
X624205Y8230D01*
X624225Y8190D01*
X624240Y8155D01*
X624260Y8115D01*
X624275Y8075D01*
X624285Y8035D01*
X624300Y7990D01*
X624305Y7950D01*
X624315Y7910D01*
X624320Y7865D01*
Y7825D01*
X624325Y7780D01*
X624320Y7735D01*
Y7695D01*
X624315Y7650D01*
X624305Y7610D01*
X624300Y7570D01*
X624285Y7525D01*
X624275Y7485D01*
X624260Y7445D01*
X624240Y7405D01*
X624225Y7370D01*
X624205Y7330D01*
X624105Y7190D01*
X624075Y7160D01*
Y3730D01*
X624065Y3605D01*
X624025Y3480D01*
X623965Y3370D01*
X623885Y3270D01*
X623785Y3190D01*
X623675Y3130D01*
X623550Y3090D01*
X623425Y3080D01*
G37*
G36*
G01X647047D02*
X646922Y3090D01*
X646797Y3130D01*
X646687Y3190D01*
X646587Y3270D01*
X646507Y3370D01*
X646447Y3480D01*
X646407Y3605D01*
X646397Y3730D01*
Y7160D01*
X646367Y7190D01*
X646267Y7330D01*
X646247Y7370D01*
X646232Y7405D01*
X646212Y7445D01*
X646197Y7485D01*
X646187Y7525D01*
X646172Y7570D01*
X646167Y7610D01*
X646157Y7650D01*
X646152Y7695D01*
Y7735D01*
X646147Y7780D01*
X646152Y7825D01*
Y7865D01*
X646157Y7910D01*
X646167Y7950D01*
X646172Y7990D01*
X646187Y8035D01*
X646197Y8075D01*
X646212Y8115D01*
X646232Y8155D01*
X646247Y8190D01*
X646267Y8230D01*
X646367Y8370D01*
X646397Y8400D01*
Y9530D01*
X646407Y9655D01*
X646447Y9780D01*
X646507Y9890D01*
X646587Y9990D01*
X646687Y10070D01*
X646797Y10130D01*
X646922Y10170D01*
X647047Y10180D01*
X647172Y10170D01*
X647297Y10130D01*
X647407Y10070D01*
X647507Y9990D01*
X647587Y9890D01*
X647647Y9780D01*
X647687Y9655D01*
X647697Y9530D01*
Y8400D01*
X647727Y8370D01*
X647827Y8230D01*
X647847Y8190D01*
X647862Y8155D01*
X647882Y8115D01*
X647897Y8075D01*
X647907Y8035D01*
X647922Y7990D01*
X647927Y7950D01*
X647937Y7910D01*
X647942Y7865D01*
Y7825D01*
X647947Y7780D01*
X647942Y7735D01*
Y7695D01*
X647937Y7650D01*
X647927Y7610D01*
X647922Y7570D01*
X647907Y7525D01*
X647897Y7485D01*
X647882Y7445D01*
X647862Y7405D01*
X647847Y7370D01*
X647827Y7330D01*
X647727Y7190D01*
X647697Y7160D01*
Y3730D01*
X647687Y3605D01*
X647647Y3480D01*
X647587Y3370D01*
X647507Y3270D01*
X647407Y3190D01*
X647297Y3130D01*
X647172Y3090D01*
X647047Y3080D01*
G37*
G36*
G01X642323D02*
X642198Y3090D01*
X642073Y3130D01*
X641963Y3190D01*
X641863Y3270D01*
X641783Y3370D01*
X641723Y3480D01*
X641683Y3605D01*
X641673Y3730D01*
Y7160D01*
X641643Y7190D01*
X641543Y7330D01*
X641523Y7370D01*
X641508Y7405D01*
X641488Y7445D01*
X641473Y7485D01*
X641463Y7525D01*
X641448Y7570D01*
X641443Y7610D01*
X641433Y7650D01*
X641428Y7695D01*
Y7735D01*
X641423Y7780D01*
X641428Y7825D01*
Y7865D01*
X641433Y7910D01*
X641443Y7950D01*
X641448Y7990D01*
X641463Y8035D01*
X641473Y8075D01*
X641488Y8115D01*
X641508Y8155D01*
X641523Y8190D01*
X641543Y8230D01*
X641643Y8370D01*
X641673Y8400D01*
Y9530D01*
X641683Y9655D01*
X641723Y9780D01*
X641783Y9890D01*
X641863Y9990D01*
X641963Y10070D01*
X642073Y10130D01*
X642198Y10170D01*
X642323Y10180D01*
X642448Y10170D01*
X642573Y10130D01*
X642683Y10070D01*
X642783Y9990D01*
X642863Y9890D01*
X642923Y9780D01*
X642963Y9655D01*
X642973Y9530D01*
Y8400D01*
X643003Y8370D01*
X643103Y8230D01*
X643123Y8190D01*
X643138Y8155D01*
X643158Y8115D01*
X643173Y8075D01*
X643183Y8035D01*
X643198Y7990D01*
X643203Y7950D01*
X643213Y7910D01*
X643218Y7865D01*
Y7825D01*
X643223Y7780D01*
X643218Y7735D01*
Y7695D01*
X643213Y7650D01*
X643203Y7610D01*
X643198Y7570D01*
X643183Y7525D01*
X643173Y7485D01*
X643158Y7445D01*
X643138Y7405D01*
X643123Y7370D01*
X643103Y7330D01*
X643003Y7190D01*
X642973Y7160D01*
Y3730D01*
X642963Y3605D01*
X642923Y3480D01*
X642863Y3370D01*
X642783Y3270D01*
X642683Y3190D01*
X642573Y3130D01*
X642448Y3090D01*
X642323Y3080D01*
G37*
G36*
G01X637598D02*
X637473Y3090D01*
X637348Y3130D01*
X637238Y3190D01*
X637138Y3270D01*
X637058Y3370D01*
X636998Y3480D01*
X636958Y3605D01*
X636948Y3730D01*
Y7160D01*
X636918Y7190D01*
X636818Y7330D01*
X636798Y7370D01*
X636783Y7405D01*
X636763Y7445D01*
X636748Y7485D01*
X636738Y7525D01*
X636723Y7570D01*
X636718Y7610D01*
X636708Y7650D01*
X636703Y7695D01*
Y7735D01*
X636698Y7780D01*
X636703Y7825D01*
Y7865D01*
X636708Y7910D01*
X636718Y7950D01*
X636723Y7990D01*
X636738Y8035D01*
X636748Y8075D01*
X636763Y8115D01*
X636783Y8155D01*
X636798Y8190D01*
X636818Y8230D01*
X636918Y8370D01*
X636948Y8400D01*
Y9530D01*
X636958Y9655D01*
X636998Y9780D01*
X637058Y9890D01*
X637138Y9990D01*
X637238Y10070D01*
X637348Y10130D01*
X637473Y10170D01*
X637598Y10180D01*
X637723Y10170D01*
X637848Y10130D01*
X637958Y10070D01*
X638058Y9990D01*
X638138Y9890D01*
X638198Y9780D01*
X638238Y9655D01*
X638248Y9530D01*
Y8400D01*
X638278Y8370D01*
X638378Y8230D01*
X638398Y8190D01*
X638413Y8155D01*
X638433Y8115D01*
X638448Y8075D01*
X638458Y8035D01*
X638473Y7990D01*
X638478Y7950D01*
X638488Y7910D01*
X638493Y7865D01*
Y7825D01*
X638498Y7780D01*
X638493Y7735D01*
Y7695D01*
X638488Y7650D01*
X638478Y7610D01*
X638473Y7570D01*
X638458Y7525D01*
X638448Y7485D01*
X638433Y7445D01*
X638413Y7405D01*
X638398Y7370D01*
X638378Y7330D01*
X638278Y7190D01*
X638248Y7160D01*
Y3730D01*
X638238Y3605D01*
X638198Y3480D01*
X638138Y3370D01*
X638058Y3270D01*
X637958Y3190D01*
X637848Y3130D01*
X637723Y3090D01*
X637598Y3080D01*
G37*
G36*
G01X661220D02*
X661095Y3090D01*
X660970Y3130D01*
X660860Y3190D01*
X660760Y3270D01*
X660680Y3370D01*
X660620Y3480D01*
X660580Y3605D01*
X660570Y3730D01*
Y7160D01*
X660540Y7190D01*
X660440Y7330D01*
X660420Y7370D01*
X660405Y7405D01*
X660385Y7445D01*
X660370Y7485D01*
X660360Y7525D01*
X660345Y7570D01*
X660340Y7610D01*
X660330Y7650D01*
X660325Y7695D01*
Y7735D01*
X660320Y7780D01*
X660325Y7825D01*
Y7865D01*
X660330Y7910D01*
X660340Y7950D01*
X660345Y7990D01*
X660360Y8035D01*
X660370Y8075D01*
X660385Y8115D01*
X660405Y8155D01*
X660420Y8190D01*
X660440Y8230D01*
X660540Y8370D01*
X660570Y8400D01*
Y9530D01*
X660580Y9655D01*
X660620Y9780D01*
X660680Y9890D01*
X660760Y9990D01*
X660860Y10070D01*
X660970Y10130D01*
X661095Y10170D01*
X661220Y10180D01*
X661345Y10170D01*
X661470Y10130D01*
X661580Y10070D01*
X661680Y9990D01*
X661760Y9890D01*
X661820Y9780D01*
X661860Y9655D01*
X661870Y9530D01*
Y8400D01*
X661900Y8370D01*
X662000Y8230D01*
X662020Y8190D01*
X662035Y8155D01*
X662055Y8115D01*
X662070Y8075D01*
X662080Y8035D01*
X662095Y7990D01*
X662100Y7950D01*
X662110Y7910D01*
X662115Y7865D01*
Y7825D01*
X662120Y7780D01*
X662115Y7735D01*
Y7695D01*
X662110Y7650D01*
X662100Y7610D01*
X662095Y7570D01*
X662080Y7525D01*
X662070Y7485D01*
X662055Y7445D01*
X662035Y7405D01*
X662020Y7370D01*
X662000Y7330D01*
X661900Y7190D01*
X661870Y7160D01*
Y3730D01*
X661860Y3605D01*
X661820Y3480D01*
X661760Y3370D01*
X661680Y3270D01*
X661580Y3190D01*
X661470Y3130D01*
X661345Y3090D01*
X661220Y3080D01*
G37*
G36*
G01X656496D02*
X656371Y3090D01*
X656246Y3130D01*
X656136Y3190D01*
X656036Y3270D01*
X655956Y3370D01*
X655896Y3480D01*
X655856Y3605D01*
X655846Y3730D01*
Y7160D01*
X655816Y7190D01*
X655716Y7330D01*
X655696Y7370D01*
X655681Y7405D01*
X655661Y7445D01*
X655646Y7485D01*
X655636Y7525D01*
X655621Y7570D01*
X655616Y7610D01*
X655606Y7650D01*
X655601Y7695D01*
Y7735D01*
X655596Y7780D01*
X655601Y7825D01*
Y7865D01*
X655606Y7910D01*
X655616Y7950D01*
X655621Y7990D01*
X655636Y8035D01*
X655646Y8075D01*
X655661Y8115D01*
X655681Y8155D01*
X655696Y8190D01*
X655716Y8230D01*
X655816Y8370D01*
X655846Y8400D01*
Y9530D01*
X655856Y9655D01*
X655896Y9780D01*
X655956Y9890D01*
X656036Y9990D01*
X656136Y10070D01*
X656246Y10130D01*
X656371Y10170D01*
X656496Y10180D01*
X656621Y10170D01*
X656746Y10130D01*
X656856Y10070D01*
X656956Y9990D01*
X657036Y9890D01*
X657096Y9780D01*
X657136Y9655D01*
X657146Y9530D01*
Y8400D01*
X657176Y8370D01*
X657276Y8230D01*
X657296Y8190D01*
X657311Y8155D01*
X657331Y8115D01*
X657346Y8075D01*
X657356Y8035D01*
X657371Y7990D01*
X657376Y7950D01*
X657386Y7910D01*
X657391Y7865D01*
Y7825D01*
X657396Y7780D01*
X657391Y7735D01*
Y7695D01*
X657386Y7650D01*
X657376Y7610D01*
X657371Y7570D01*
X657356Y7525D01*
X657346Y7485D01*
X657331Y7445D01*
X657311Y7405D01*
X657296Y7370D01*
X657276Y7330D01*
X657176Y7190D01*
X657146Y7160D01*
Y3730D01*
X657136Y3605D01*
X657096Y3480D01*
X657036Y3370D01*
X656956Y3270D01*
X656856Y3190D01*
X656746Y3130D01*
X656621Y3090D01*
X656496Y3080D01*
G37*
G36*
G01X651771D02*
X651646Y3090D01*
X651521Y3130D01*
X651411Y3190D01*
X651311Y3270D01*
X651231Y3370D01*
X651171Y3480D01*
X651131Y3605D01*
X651121Y3730D01*
Y7160D01*
X651091Y7190D01*
X650991Y7330D01*
X650971Y7370D01*
X650956Y7405D01*
X650936Y7445D01*
X650921Y7485D01*
X650911Y7525D01*
X650896Y7570D01*
X650891Y7610D01*
X650881Y7650D01*
X650876Y7695D01*
Y7735D01*
X650871Y7780D01*
X650876Y7825D01*
Y7865D01*
X650881Y7910D01*
X650891Y7950D01*
X650896Y7990D01*
X650911Y8035D01*
X650921Y8075D01*
X650936Y8115D01*
X650956Y8155D01*
X650971Y8190D01*
X650991Y8230D01*
X651091Y8370D01*
X651121Y8400D01*
Y9530D01*
X651131Y9655D01*
X651171Y9780D01*
X651231Y9890D01*
X651311Y9990D01*
X651411Y10070D01*
X651521Y10130D01*
X651646Y10170D01*
X651771Y10180D01*
X651896Y10170D01*
X652021Y10130D01*
X652131Y10070D01*
X652231Y9990D01*
X652311Y9890D01*
X652371Y9780D01*
X652411Y9655D01*
X652421Y9530D01*
Y8400D01*
X652451Y8370D01*
X652551Y8230D01*
X652571Y8190D01*
X652586Y8155D01*
X652606Y8115D01*
X652621Y8075D01*
X652631Y8035D01*
X652646Y7990D01*
X652651Y7950D01*
X652661Y7910D01*
X652666Y7865D01*
Y7825D01*
X652671Y7780D01*
X652666Y7735D01*
Y7695D01*
X652661Y7650D01*
X652651Y7610D01*
X652646Y7570D01*
X652631Y7525D01*
X652621Y7485D01*
X652606Y7445D01*
X652586Y7405D01*
X652571Y7370D01*
X652551Y7330D01*
X652451Y7190D01*
X652421Y7160D01*
Y3730D01*
X652411Y3605D01*
X652371Y3480D01*
X652311Y3370D01*
X652231Y3270D01*
X652131Y3190D01*
X652021Y3130D01*
X651896Y3090D01*
X651771Y3080D01*
G37*
G36*
G01X680118D02*
X679993Y3090D01*
X679868Y3130D01*
X679758Y3190D01*
X679658Y3270D01*
X679578Y3370D01*
X679518Y3480D01*
X679478Y3605D01*
X679468Y3730D01*
Y7160D01*
X679438Y7190D01*
X679338Y7330D01*
X679318Y7370D01*
X679303Y7405D01*
X679283Y7445D01*
X679268Y7485D01*
X679258Y7525D01*
X679243Y7570D01*
X679238Y7610D01*
X679228Y7650D01*
X679223Y7695D01*
Y7735D01*
X679218Y7780D01*
X679223Y7825D01*
Y7865D01*
X679228Y7910D01*
X679238Y7950D01*
X679243Y7990D01*
X679258Y8035D01*
X679268Y8075D01*
X679283Y8115D01*
X679303Y8155D01*
X679318Y8190D01*
X679338Y8230D01*
X679438Y8370D01*
X679468Y8400D01*
Y9530D01*
X679478Y9655D01*
X679518Y9780D01*
X679578Y9890D01*
X679658Y9990D01*
X679758Y10070D01*
X679868Y10130D01*
X679993Y10170D01*
X680118Y10180D01*
X680243Y10170D01*
X680368Y10130D01*
X680478Y10070D01*
X680578Y9990D01*
X680658Y9890D01*
X680718Y9780D01*
X680758Y9655D01*
X680768Y9530D01*
Y8400D01*
X680798Y8370D01*
X680898Y8230D01*
X680918Y8190D01*
X680933Y8155D01*
X680953Y8115D01*
X680968Y8075D01*
X680978Y8035D01*
X680993Y7990D01*
X680998Y7950D01*
X681008Y7910D01*
X681013Y7865D01*
Y7825D01*
X681018Y7780D01*
X681013Y7735D01*
Y7695D01*
X681008Y7650D01*
X680998Y7610D01*
X680993Y7570D01*
X680978Y7525D01*
X680968Y7485D01*
X680953Y7445D01*
X680933Y7405D01*
X680918Y7370D01*
X680898Y7330D01*
X680798Y7190D01*
X680768Y7160D01*
Y3730D01*
X680758Y3605D01*
X680718Y3480D01*
X680658Y3370D01*
X680578Y3270D01*
X680478Y3190D01*
X680368Y3130D01*
X680243Y3090D01*
X680118Y3080D01*
G37*
G36*
G01X675393D02*
X675268Y3090D01*
X675143Y3130D01*
X675033Y3190D01*
X674933Y3270D01*
X674853Y3370D01*
X674793Y3480D01*
X674753Y3605D01*
X674743Y3730D01*
Y7160D01*
X674713Y7190D01*
X674613Y7330D01*
X674593Y7370D01*
X674578Y7405D01*
X674558Y7445D01*
X674543Y7485D01*
X674533Y7525D01*
X674518Y7570D01*
X674513Y7610D01*
X674503Y7650D01*
X674498Y7695D01*
Y7735D01*
X674493Y7780D01*
X674498Y7825D01*
Y7865D01*
X674503Y7910D01*
X674513Y7950D01*
X674518Y7990D01*
X674533Y8035D01*
X674543Y8075D01*
X674558Y8115D01*
X674578Y8155D01*
X674593Y8190D01*
X674613Y8230D01*
X674713Y8370D01*
X674743Y8400D01*
Y9530D01*
X674753Y9655D01*
X674793Y9780D01*
X674853Y9890D01*
X674933Y9990D01*
X675033Y10070D01*
X675143Y10130D01*
X675268Y10170D01*
X675393Y10180D01*
X675518Y10170D01*
X675643Y10130D01*
X675753Y10070D01*
X675853Y9990D01*
X675933Y9890D01*
X675993Y9780D01*
X676033Y9655D01*
X676043Y9530D01*
Y8400D01*
X676073Y8370D01*
X676173Y8230D01*
X676193Y8190D01*
X676208Y8155D01*
X676228Y8115D01*
X676243Y8075D01*
X676253Y8035D01*
X676268Y7990D01*
X676273Y7950D01*
X676283Y7910D01*
X676288Y7865D01*
Y7825D01*
X676293Y7780D01*
X676288Y7735D01*
Y7695D01*
X676283Y7650D01*
X676273Y7610D01*
X676268Y7570D01*
X676253Y7525D01*
X676243Y7485D01*
X676228Y7445D01*
X676208Y7405D01*
X676193Y7370D01*
X676173Y7330D01*
X676073Y7190D01*
X676043Y7160D01*
Y3730D01*
X676033Y3605D01*
X675993Y3480D01*
X675933Y3370D01*
X675853Y3270D01*
X675753Y3190D01*
X675643Y3130D01*
X675518Y3090D01*
X675393Y3080D01*
G37*
G36*
G01X670669D02*
X670544Y3090D01*
X670419Y3130D01*
X670309Y3190D01*
X670209Y3270D01*
X670129Y3370D01*
X670069Y3480D01*
X670029Y3605D01*
X670019Y3730D01*
Y7160D01*
X669989Y7190D01*
X669889Y7330D01*
X669869Y7370D01*
X669854Y7405D01*
X669834Y7445D01*
X669819Y7485D01*
X669809Y7525D01*
X669794Y7570D01*
X669789Y7610D01*
X669779Y7650D01*
X669774Y7695D01*
Y7735D01*
X669769Y7780D01*
X669774Y7825D01*
Y7865D01*
X669779Y7910D01*
X669789Y7950D01*
X669794Y7990D01*
X669809Y8035D01*
X669819Y8075D01*
X669834Y8115D01*
X669854Y8155D01*
X669869Y8190D01*
X669889Y8230D01*
X669989Y8370D01*
X670019Y8400D01*
Y9530D01*
X670029Y9655D01*
X670069Y9780D01*
X670129Y9890D01*
X670209Y9990D01*
X670309Y10070D01*
X670419Y10130D01*
X670544Y10170D01*
X670669Y10180D01*
X670794Y10170D01*
X670919Y10130D01*
X671029Y10070D01*
X671129Y9990D01*
X671209Y9890D01*
X671269Y9780D01*
X671309Y9655D01*
X671319Y9530D01*
Y8400D01*
X671349Y8370D01*
X671449Y8230D01*
X671469Y8190D01*
X671484Y8155D01*
X671504Y8115D01*
X671519Y8075D01*
X671529Y8035D01*
X671544Y7990D01*
X671549Y7950D01*
X671559Y7910D01*
X671564Y7865D01*
Y7825D01*
X671569Y7780D01*
X671564Y7735D01*
Y7695D01*
X671559Y7650D01*
X671549Y7610D01*
X671544Y7570D01*
X671529Y7525D01*
X671519Y7485D01*
X671504Y7445D01*
X671484Y7405D01*
X671469Y7370D01*
X671449Y7330D01*
X671349Y7190D01*
X671319Y7160D01*
Y3730D01*
X671309Y3605D01*
X671269Y3480D01*
X671209Y3370D01*
X671129Y3270D01*
X671029Y3190D01*
X670919Y3130D01*
X670794Y3090D01*
X670669Y3080D01*
G37*
G36*
G01X665945D02*
X665820Y3090D01*
X665695Y3130D01*
X665585Y3190D01*
X665485Y3270D01*
X665405Y3370D01*
X665345Y3480D01*
X665305Y3605D01*
X665295Y3730D01*
Y7160D01*
X665265Y7190D01*
X665165Y7330D01*
X665145Y7370D01*
X665130Y7405D01*
X665110Y7445D01*
X665095Y7485D01*
X665085Y7525D01*
X665070Y7570D01*
X665065Y7610D01*
X665055Y7650D01*
X665050Y7695D01*
Y7735D01*
X665045Y7780D01*
X665050Y7825D01*
Y7865D01*
X665055Y7910D01*
X665065Y7950D01*
X665070Y7990D01*
X665085Y8035D01*
X665095Y8075D01*
X665110Y8115D01*
X665130Y8155D01*
X665145Y8190D01*
X665165Y8230D01*
X665265Y8370D01*
X665295Y8400D01*
Y9530D01*
X665305Y9655D01*
X665345Y9780D01*
X665405Y9890D01*
X665485Y9990D01*
X665585Y10070D01*
X665695Y10130D01*
X665820Y10170D01*
X665945Y10180D01*
X666070Y10170D01*
X666195Y10130D01*
X666305Y10070D01*
X666405Y9990D01*
X666485Y9890D01*
X666545Y9780D01*
X666585Y9655D01*
X666595Y9530D01*
Y8400D01*
X666625Y8370D01*
X666725Y8230D01*
X666745Y8190D01*
X666760Y8155D01*
X666780Y8115D01*
X666795Y8075D01*
X666805Y8035D01*
X666820Y7990D01*
X666825Y7950D01*
X666835Y7910D01*
X666840Y7865D01*
Y7825D01*
X666845Y7780D01*
X666840Y7735D01*
Y7695D01*
X666835Y7650D01*
X666825Y7610D01*
X666820Y7570D01*
X666805Y7525D01*
X666795Y7485D01*
X666780Y7445D01*
X666760Y7405D01*
X666745Y7370D01*
X666725Y7330D01*
X666625Y7190D01*
X666595Y7160D01*
Y3730D01*
X666585Y3605D01*
X666545Y3480D01*
X666485Y3370D01*
X666405Y3270D01*
X666305Y3190D01*
X666195Y3130D01*
X666070Y3090D01*
X665945Y3080D01*
G37*
G36*
G01X694291D02*
X694166Y3090D01*
X694041Y3130D01*
X693931Y3190D01*
X693831Y3270D01*
X693751Y3370D01*
X693691Y3480D01*
X693651Y3605D01*
X693641Y3730D01*
Y7160D01*
X693611Y7190D01*
X693511Y7330D01*
X693491Y7370D01*
X693476Y7405D01*
X693456Y7445D01*
X693441Y7485D01*
X693431Y7525D01*
X693416Y7570D01*
X693411Y7610D01*
X693401Y7650D01*
X693396Y7695D01*
Y7735D01*
X693391Y7780D01*
X693396Y7825D01*
Y7865D01*
X693401Y7910D01*
X693411Y7950D01*
X693416Y7990D01*
X693431Y8035D01*
X693441Y8075D01*
X693456Y8115D01*
X693476Y8155D01*
X693491Y8190D01*
X693511Y8230D01*
X693611Y8370D01*
X693641Y8400D01*
Y9530D01*
X693651Y9655D01*
X693691Y9780D01*
X693751Y9890D01*
X693831Y9990D01*
X693931Y10070D01*
X694041Y10130D01*
X694166Y10170D01*
X694291Y10180D01*
X694416Y10170D01*
X694541Y10130D01*
X694651Y10070D01*
X694751Y9990D01*
X694831Y9890D01*
X694891Y9780D01*
X694931Y9655D01*
X694941Y9530D01*
Y8400D01*
X694971Y8370D01*
X695071Y8230D01*
X695091Y8190D01*
X695106Y8155D01*
X695126Y8115D01*
X695141Y8075D01*
X695151Y8035D01*
X695166Y7990D01*
X695171Y7950D01*
X695181Y7910D01*
X695186Y7865D01*
Y7825D01*
X695191Y7780D01*
X695186Y7735D01*
Y7695D01*
X695181Y7650D01*
X695171Y7610D01*
X695166Y7570D01*
X695151Y7525D01*
X695141Y7485D01*
X695126Y7445D01*
X695106Y7405D01*
X695091Y7370D01*
X695071Y7330D01*
X694971Y7190D01*
X694941Y7160D01*
Y3730D01*
X694931Y3605D01*
X694891Y3480D01*
X694831Y3370D01*
X694751Y3270D01*
X694651Y3190D01*
X694541Y3130D01*
X694416Y3090D01*
X694291Y3080D01*
G37*
G36*
G01X689567D02*
X689442Y3090D01*
X689317Y3130D01*
X689207Y3190D01*
X689107Y3270D01*
X689027Y3370D01*
X688967Y3480D01*
X688927Y3605D01*
X688917Y3730D01*
Y7160D01*
X688887Y7190D01*
X688787Y7330D01*
X688767Y7370D01*
X688752Y7405D01*
X688732Y7445D01*
X688717Y7485D01*
X688707Y7525D01*
X688692Y7570D01*
X688687Y7610D01*
X688677Y7650D01*
X688672Y7695D01*
Y7735D01*
X688667Y7780D01*
X688672Y7825D01*
Y7865D01*
X688677Y7910D01*
X688687Y7950D01*
X688692Y7990D01*
X688707Y8035D01*
X688717Y8075D01*
X688732Y8115D01*
X688752Y8155D01*
X688767Y8190D01*
X688787Y8230D01*
X688887Y8370D01*
X688917Y8400D01*
Y9530D01*
X688927Y9655D01*
X688967Y9780D01*
X689027Y9890D01*
X689107Y9990D01*
X689207Y10070D01*
X689317Y10130D01*
X689442Y10170D01*
X689567Y10180D01*
X689692Y10170D01*
X689817Y10130D01*
X689927Y10070D01*
X690027Y9990D01*
X690107Y9890D01*
X690167Y9780D01*
X690207Y9655D01*
X690217Y9530D01*
Y8400D01*
X690247Y8370D01*
X690347Y8230D01*
X690367Y8190D01*
X690382Y8155D01*
X690402Y8115D01*
X690417Y8075D01*
X690427Y8035D01*
X690442Y7990D01*
X690447Y7950D01*
X690457Y7910D01*
X690462Y7865D01*
Y7825D01*
X690467Y7780D01*
X690462Y7735D01*
Y7695D01*
X690457Y7650D01*
X690447Y7610D01*
X690442Y7570D01*
X690427Y7525D01*
X690417Y7485D01*
X690402Y7445D01*
X690382Y7405D01*
X690367Y7370D01*
X690347Y7330D01*
X690247Y7190D01*
X690217Y7160D01*
Y3730D01*
X690207Y3605D01*
X690167Y3480D01*
X690107Y3370D01*
X690027Y3270D01*
X689927Y3190D01*
X689817Y3130D01*
X689692Y3090D01*
X689567Y3080D01*
G37*
G36*
G01X684842D02*
X684717Y3090D01*
X684592Y3130D01*
X684482Y3190D01*
X684382Y3270D01*
X684302Y3370D01*
X684242Y3480D01*
X684202Y3605D01*
X684192Y3730D01*
Y7160D01*
X684162Y7190D01*
X684062Y7330D01*
X684042Y7370D01*
X684027Y7405D01*
X684007Y7445D01*
X683992Y7485D01*
X683982Y7525D01*
X683967Y7570D01*
X683962Y7610D01*
X683952Y7650D01*
X683947Y7695D01*
Y7735D01*
X683942Y7780D01*
X683947Y7825D01*
Y7865D01*
X683952Y7910D01*
X683962Y7950D01*
X683967Y7990D01*
X683982Y8035D01*
X683992Y8075D01*
X684007Y8115D01*
X684027Y8155D01*
X684042Y8190D01*
X684062Y8230D01*
X684162Y8370D01*
X684192Y8400D01*
Y9530D01*
X684202Y9655D01*
X684242Y9780D01*
X684302Y9890D01*
X684382Y9990D01*
X684482Y10070D01*
X684592Y10130D01*
X684717Y10170D01*
X684842Y10180D01*
X684967Y10170D01*
X685092Y10130D01*
X685202Y10070D01*
X685302Y9990D01*
X685382Y9890D01*
X685442Y9780D01*
X685482Y9655D01*
X685492Y9530D01*
Y8400D01*
X685522Y8370D01*
X685622Y8230D01*
X685642Y8190D01*
X685657Y8155D01*
X685677Y8115D01*
X685692Y8075D01*
X685702Y8035D01*
X685717Y7990D01*
X685722Y7950D01*
X685732Y7910D01*
X685737Y7865D01*
Y7825D01*
X685742Y7780D01*
X685737Y7735D01*
Y7695D01*
X685732Y7650D01*
X685722Y7610D01*
X685717Y7570D01*
X685702Y7525D01*
X685692Y7485D01*
X685677Y7445D01*
X685657Y7405D01*
X685642Y7370D01*
X685622Y7330D01*
X685522Y7190D01*
X685492Y7160D01*
Y3730D01*
X685482Y3605D01*
X685442Y3480D01*
X685382Y3370D01*
X685302Y3270D01*
X685202Y3190D01*
X685092Y3130D01*
X684967Y3090D01*
X684842Y3080D01*
G37*
G36*
G01X708464D02*
X708339Y3090D01*
X708214Y3130D01*
X708104Y3190D01*
X708004Y3270D01*
X707924Y3370D01*
X707864Y3480D01*
X707824Y3605D01*
X707814Y3730D01*
Y7160D01*
X707784Y7190D01*
X707684Y7330D01*
X707664Y7370D01*
X707649Y7405D01*
X707629Y7445D01*
X707614Y7485D01*
X707604Y7525D01*
X707589Y7570D01*
X707584Y7610D01*
X707574Y7650D01*
X707569Y7695D01*
Y7735D01*
X707564Y7780D01*
X707569Y7825D01*
Y7865D01*
X707574Y7910D01*
X707584Y7950D01*
X707589Y7990D01*
X707604Y8035D01*
X707614Y8075D01*
X707629Y8115D01*
X707649Y8155D01*
X707664Y8190D01*
X707684Y8230D01*
X707784Y8370D01*
X707814Y8400D01*
Y9530D01*
X707824Y9655D01*
X707864Y9780D01*
X707924Y9890D01*
X708004Y9990D01*
X708104Y10070D01*
X708214Y10130D01*
X708339Y10170D01*
X708464Y10180D01*
X708589Y10170D01*
X708714Y10130D01*
X708824Y10070D01*
X708924Y9990D01*
X709004Y9890D01*
X709064Y9780D01*
X709104Y9655D01*
X709114Y9530D01*
Y8400D01*
X709144Y8370D01*
X709244Y8230D01*
X709264Y8190D01*
X709279Y8155D01*
X709299Y8115D01*
X709314Y8075D01*
X709324Y8035D01*
X709339Y7990D01*
X709344Y7950D01*
X709354Y7910D01*
X709359Y7865D01*
Y7825D01*
X709364Y7780D01*
X709359Y7735D01*
Y7695D01*
X709354Y7650D01*
X709344Y7610D01*
X709339Y7570D01*
X709324Y7525D01*
X709314Y7485D01*
X709299Y7445D01*
X709279Y7405D01*
X709264Y7370D01*
X709244Y7330D01*
X709144Y7190D01*
X709114Y7160D01*
Y3730D01*
X709104Y3605D01*
X709064Y3480D01*
X709004Y3370D01*
X708924Y3270D01*
X708824Y3190D01*
X708714Y3130D01*
X708589Y3090D01*
X708464Y3080D01*
G37*
G36*
G01X703740D02*
X703615Y3090D01*
X703490Y3130D01*
X703380Y3190D01*
X703280Y3270D01*
X703200Y3370D01*
X703140Y3480D01*
X703100Y3605D01*
X703090Y3730D01*
Y7160D01*
X703060Y7190D01*
X702960Y7330D01*
X702940Y7370D01*
X702925Y7405D01*
X702905Y7445D01*
X702890Y7485D01*
X702880Y7525D01*
X702865Y7570D01*
X702860Y7610D01*
X702850Y7650D01*
X702845Y7695D01*
Y7735D01*
X702840Y7780D01*
X702845Y7825D01*
Y7865D01*
X702850Y7910D01*
X702860Y7950D01*
X702865Y7990D01*
X702880Y8035D01*
X702890Y8075D01*
X702905Y8115D01*
X702925Y8155D01*
X702940Y8190D01*
X702960Y8230D01*
X703060Y8370D01*
X703090Y8400D01*
Y9530D01*
X703100Y9655D01*
X703140Y9780D01*
X703200Y9890D01*
X703280Y9990D01*
X703380Y10070D01*
X703490Y10130D01*
X703615Y10170D01*
X703740Y10180D01*
X703865Y10170D01*
X703990Y10130D01*
X704100Y10070D01*
X704200Y9990D01*
X704280Y9890D01*
X704340Y9780D01*
X704380Y9655D01*
X704390Y9530D01*
Y8400D01*
X704420Y8370D01*
X704520Y8230D01*
X704540Y8190D01*
X704555Y8155D01*
X704575Y8115D01*
X704590Y8075D01*
X704600Y8035D01*
X704615Y7990D01*
X704620Y7950D01*
X704630Y7910D01*
X704635Y7865D01*
Y7825D01*
X704640Y7780D01*
X704635Y7735D01*
Y7695D01*
X704630Y7650D01*
X704620Y7610D01*
X704615Y7570D01*
X704600Y7525D01*
X704590Y7485D01*
X704575Y7445D01*
X704555Y7405D01*
X704540Y7370D01*
X704520Y7330D01*
X704420Y7190D01*
X704390Y7160D01*
Y3730D01*
X704380Y3605D01*
X704340Y3480D01*
X704280Y3370D01*
X704200Y3270D01*
X704100Y3190D01*
X703990Y3130D01*
X703865Y3090D01*
X703740Y3080D01*
G37*
G36*
G01X699015D02*
X698890Y3090D01*
X698765Y3130D01*
X698655Y3190D01*
X698555Y3270D01*
X698475Y3370D01*
X698415Y3480D01*
X698375Y3605D01*
X698365Y3730D01*
Y7160D01*
X698335Y7190D01*
X698235Y7330D01*
X698215Y7370D01*
X698200Y7405D01*
X698180Y7445D01*
X698165Y7485D01*
X698155Y7525D01*
X698140Y7570D01*
X698135Y7610D01*
X698125Y7650D01*
X698120Y7695D01*
Y7735D01*
X698115Y7780D01*
X698120Y7825D01*
Y7865D01*
X698125Y7910D01*
X698135Y7950D01*
X698140Y7990D01*
X698155Y8035D01*
X698165Y8075D01*
X698180Y8115D01*
X698200Y8155D01*
X698215Y8190D01*
X698235Y8230D01*
X698335Y8370D01*
X698365Y8400D01*
Y9530D01*
X698375Y9655D01*
X698415Y9780D01*
X698475Y9890D01*
X698555Y9990D01*
X698655Y10070D01*
X698765Y10130D01*
X698890Y10170D01*
X699015Y10180D01*
X699140Y10170D01*
X699265Y10130D01*
X699375Y10070D01*
X699475Y9990D01*
X699555Y9890D01*
X699615Y9780D01*
X699655Y9655D01*
X699665Y9530D01*
Y8400D01*
X699695Y8370D01*
X699795Y8230D01*
X699815Y8190D01*
X699830Y8155D01*
X699850Y8115D01*
X699865Y8075D01*
X699875Y8035D01*
X699890Y7990D01*
X699895Y7950D01*
X699905Y7910D01*
X699910Y7865D01*
Y7825D01*
X699915Y7780D01*
X699910Y7735D01*
Y7695D01*
X699905Y7650D01*
X699895Y7610D01*
X699890Y7570D01*
X699875Y7525D01*
X699865Y7485D01*
X699850Y7445D01*
X699830Y7405D01*
X699815Y7370D01*
X699795Y7330D01*
X699695Y7190D01*
X699665Y7160D01*
Y3730D01*
X699655Y3605D01*
X699615Y3480D01*
X699555Y3370D01*
X699475Y3270D01*
X699375Y3190D01*
X699265Y3130D01*
X699140Y3090D01*
X699015Y3080D01*
G37*
G36*
G01X722638D02*
X722513Y3090D01*
X722388Y3130D01*
X722278Y3190D01*
X722178Y3270D01*
X722098Y3370D01*
X722038Y3480D01*
X721998Y3605D01*
X721988Y3730D01*
Y7160D01*
X721958Y7190D01*
X721858Y7330D01*
X721838Y7370D01*
X721823Y7405D01*
X721803Y7445D01*
X721788Y7485D01*
X721778Y7525D01*
X721763Y7570D01*
X721758Y7610D01*
X721748Y7650D01*
X721743Y7695D01*
Y7735D01*
X721738Y7780D01*
X721743Y7825D01*
Y7865D01*
X721748Y7910D01*
X721758Y7950D01*
X721763Y7990D01*
X721778Y8035D01*
X721788Y8075D01*
X721803Y8115D01*
X721823Y8155D01*
X721838Y8190D01*
X721858Y8230D01*
X721958Y8370D01*
X721988Y8400D01*
Y9530D01*
X721998Y9655D01*
X722038Y9780D01*
X722098Y9890D01*
X722178Y9990D01*
X722278Y10070D01*
X722388Y10130D01*
X722513Y10170D01*
X722638Y10180D01*
X722763Y10170D01*
X722888Y10130D01*
X722998Y10070D01*
X723098Y9990D01*
X723178Y9890D01*
X723238Y9780D01*
X723278Y9655D01*
X723288Y9530D01*
Y8400D01*
X723318Y8370D01*
X723418Y8230D01*
X723438Y8190D01*
X723453Y8155D01*
X723473Y8115D01*
X723488Y8075D01*
X723498Y8035D01*
X723513Y7990D01*
X723518Y7950D01*
X723528Y7910D01*
X723533Y7865D01*
Y7825D01*
X723538Y7780D01*
X723533Y7735D01*
Y7695D01*
X723528Y7650D01*
X723518Y7610D01*
X723513Y7570D01*
X723498Y7525D01*
X723488Y7485D01*
X723473Y7445D01*
X723453Y7405D01*
X723438Y7370D01*
X723418Y7330D01*
X723318Y7190D01*
X723288Y7160D01*
Y3730D01*
X723278Y3605D01*
X723238Y3480D01*
X723178Y3370D01*
X723098Y3270D01*
X722998Y3190D01*
X722888Y3130D01*
X722763Y3090D01*
X722638Y3080D01*
G37*
G36*
G01X717913D02*
X717788Y3090D01*
X717663Y3130D01*
X717553Y3190D01*
X717453Y3270D01*
X717373Y3370D01*
X717313Y3480D01*
X717273Y3605D01*
X717263Y3730D01*
Y7160D01*
X717233Y7190D01*
X717133Y7330D01*
X717113Y7370D01*
X717098Y7405D01*
X717078Y7445D01*
X717063Y7485D01*
X717053Y7525D01*
X717038Y7570D01*
X717033Y7610D01*
X717023Y7650D01*
X717018Y7695D01*
Y7735D01*
X717013Y7780D01*
X717018Y7825D01*
Y7865D01*
X717023Y7910D01*
X717033Y7950D01*
X717038Y7990D01*
X717053Y8035D01*
X717063Y8075D01*
X717078Y8115D01*
X717098Y8155D01*
X717113Y8190D01*
X717133Y8230D01*
X717233Y8370D01*
X717263Y8400D01*
Y9530D01*
X717273Y9655D01*
X717313Y9780D01*
X717373Y9890D01*
X717453Y9990D01*
X717553Y10070D01*
X717663Y10130D01*
X717788Y10170D01*
X717913Y10180D01*
X718038Y10170D01*
X718163Y10130D01*
X718273Y10070D01*
X718373Y9990D01*
X718453Y9890D01*
X718513Y9780D01*
X718553Y9655D01*
X718563Y9530D01*
Y8400D01*
X718593Y8370D01*
X718693Y8230D01*
X718713Y8190D01*
X718728Y8155D01*
X718748Y8115D01*
X718763Y8075D01*
X718773Y8035D01*
X718788Y7990D01*
X718793Y7950D01*
X718803Y7910D01*
X718808Y7865D01*
Y7825D01*
X718813Y7780D01*
X718808Y7735D01*
Y7695D01*
X718803Y7650D01*
X718793Y7610D01*
X718788Y7570D01*
X718773Y7525D01*
X718763Y7485D01*
X718748Y7445D01*
X718728Y7405D01*
X718713Y7370D01*
X718693Y7330D01*
X718593Y7190D01*
X718563Y7160D01*
Y3730D01*
X718553Y3605D01*
X718513Y3480D01*
X718453Y3370D01*
X718373Y3270D01*
X718273Y3190D01*
X718163Y3130D01*
X718038Y3090D01*
X717913Y3080D01*
G37*
G36*
G01X713189D02*
X713064Y3090D01*
X712939Y3130D01*
X712829Y3190D01*
X712729Y3270D01*
X712649Y3370D01*
X712589Y3480D01*
X712549Y3605D01*
X712539Y3730D01*
Y7160D01*
X712509Y7190D01*
X712409Y7330D01*
X712389Y7370D01*
X712374Y7405D01*
X712354Y7445D01*
X712339Y7485D01*
X712329Y7525D01*
X712314Y7570D01*
X712309Y7610D01*
X712299Y7650D01*
X712294Y7695D01*
Y7735D01*
X712289Y7780D01*
X712294Y7825D01*
Y7865D01*
X712299Y7910D01*
X712309Y7950D01*
X712314Y7990D01*
X712329Y8035D01*
X712339Y8075D01*
X712354Y8115D01*
X712374Y8155D01*
X712389Y8190D01*
X712409Y8230D01*
X712509Y8370D01*
X712539Y8400D01*
Y9530D01*
X712549Y9655D01*
X712589Y9780D01*
X712649Y9890D01*
X712729Y9990D01*
X712829Y10070D01*
X712939Y10130D01*
X713064Y10170D01*
X713189Y10180D01*
X713314Y10170D01*
X713439Y10130D01*
X713549Y10070D01*
X713649Y9990D01*
X713729Y9890D01*
X713789Y9780D01*
X713829Y9655D01*
X713839Y9530D01*
Y8400D01*
X713869Y8370D01*
X713969Y8230D01*
X713989Y8190D01*
X714004Y8155D01*
X714024Y8115D01*
X714039Y8075D01*
X714049Y8035D01*
X714064Y7990D01*
X714069Y7950D01*
X714079Y7910D01*
X714084Y7865D01*
Y7825D01*
X714089Y7780D01*
X714084Y7735D01*
Y7695D01*
X714079Y7650D01*
X714069Y7610D01*
X714064Y7570D01*
X714049Y7525D01*
X714039Y7485D01*
X714024Y7445D01*
X714004Y7405D01*
X713989Y7370D01*
X713969Y7330D01*
X713869Y7190D01*
X713839Y7160D01*
Y3730D01*
X713829Y3605D01*
X713789Y3480D01*
X713729Y3370D01*
X713649Y3270D01*
X713549Y3190D01*
X713439Y3130D01*
X713314Y3090D01*
X713189Y3080D01*
G37*
G36*
G01X741535D02*
X741410Y3090D01*
X741285Y3130D01*
X741175Y3190D01*
X741075Y3270D01*
X740995Y3370D01*
X740935Y3480D01*
X740895Y3605D01*
X740885Y3730D01*
Y7160D01*
X740855Y7190D01*
X740755Y7330D01*
X740735Y7370D01*
X740720Y7405D01*
X740700Y7445D01*
X740685Y7485D01*
X740675Y7525D01*
X740660Y7570D01*
X740655Y7610D01*
X740645Y7650D01*
X740640Y7695D01*
Y7735D01*
X740635Y7780D01*
X740640Y7825D01*
Y7865D01*
X740645Y7910D01*
X740655Y7950D01*
X740660Y7990D01*
X740675Y8035D01*
X740685Y8075D01*
X740700Y8115D01*
X740720Y8155D01*
X740735Y8190D01*
X740755Y8230D01*
X740855Y8370D01*
X740885Y8400D01*
Y9530D01*
X740895Y9655D01*
X740935Y9780D01*
X740995Y9890D01*
X741075Y9990D01*
X741175Y10070D01*
X741285Y10130D01*
X741410Y10170D01*
X741535Y10180D01*
X741660Y10170D01*
X741785Y10130D01*
X741895Y10070D01*
X741995Y9990D01*
X742075Y9890D01*
X742135Y9780D01*
X742175Y9655D01*
X742185Y9530D01*
Y8400D01*
X742215Y8370D01*
X742315Y8230D01*
X742335Y8190D01*
X742350Y8155D01*
X742370Y8115D01*
X742385Y8075D01*
X742395Y8035D01*
X742410Y7990D01*
X742415Y7950D01*
X742425Y7910D01*
X742430Y7865D01*
Y7825D01*
X742435Y7780D01*
X742430Y7735D01*
Y7695D01*
X742425Y7650D01*
X742415Y7610D01*
X742410Y7570D01*
X742395Y7525D01*
X742385Y7485D01*
X742370Y7445D01*
X742350Y7405D01*
X742335Y7370D01*
X742315Y7330D01*
X742215Y7190D01*
X742185Y7160D01*
Y3730D01*
X742175Y3605D01*
X742135Y3480D01*
X742075Y3370D01*
X741995Y3270D01*
X741895Y3190D01*
X741785Y3130D01*
X741660Y3090D01*
X741535Y3080D01*
G37*
G36*
G01X736811D02*
X736686Y3090D01*
X736561Y3130D01*
X736451Y3190D01*
X736351Y3270D01*
X736271Y3370D01*
X736211Y3480D01*
X736171Y3605D01*
X736161Y3730D01*
Y7160D01*
X736131Y7190D01*
X736031Y7330D01*
X736011Y7370D01*
X735996Y7405D01*
X735976Y7445D01*
X735961Y7485D01*
X735951Y7525D01*
X735936Y7570D01*
X735931Y7610D01*
X735921Y7650D01*
X735916Y7695D01*
Y7735D01*
X735911Y7780D01*
X735916Y7825D01*
Y7865D01*
X735921Y7910D01*
X735931Y7950D01*
X735936Y7990D01*
X735951Y8035D01*
X735961Y8075D01*
X735976Y8115D01*
X735996Y8155D01*
X736011Y8190D01*
X736031Y8230D01*
X736131Y8370D01*
X736161Y8400D01*
Y9530D01*
X736171Y9655D01*
X736211Y9780D01*
X736271Y9890D01*
X736351Y9990D01*
X736451Y10070D01*
X736561Y10130D01*
X736686Y10170D01*
X736811Y10180D01*
X736936Y10170D01*
X737061Y10130D01*
X737171Y10070D01*
X737271Y9990D01*
X737351Y9890D01*
X737411Y9780D01*
X737451Y9655D01*
X737461Y9530D01*
Y8400D01*
X737491Y8370D01*
X737591Y8230D01*
X737611Y8190D01*
X737626Y8155D01*
X737646Y8115D01*
X737661Y8075D01*
X737671Y8035D01*
X737686Y7990D01*
X737691Y7950D01*
X737701Y7910D01*
X737706Y7865D01*
Y7825D01*
X737711Y7780D01*
X737706Y7735D01*
Y7695D01*
X737701Y7650D01*
X737691Y7610D01*
X737686Y7570D01*
X737671Y7525D01*
X737661Y7485D01*
X737646Y7445D01*
X737626Y7405D01*
X737611Y7370D01*
X737591Y7330D01*
X737491Y7190D01*
X737461Y7160D01*
Y3730D01*
X737451Y3605D01*
X737411Y3480D01*
X737351Y3370D01*
X737271Y3270D01*
X737171Y3190D01*
X737061Y3130D01*
X736936Y3090D01*
X736811Y3080D01*
G37*
G36*
G01X732086D02*
X731961Y3090D01*
X731836Y3130D01*
X731726Y3190D01*
X731626Y3270D01*
X731546Y3370D01*
X731486Y3480D01*
X731446Y3605D01*
X731436Y3730D01*
Y7160D01*
X731406Y7190D01*
X731306Y7330D01*
X731286Y7370D01*
X731271Y7405D01*
X731251Y7445D01*
X731236Y7485D01*
X731226Y7525D01*
X731211Y7570D01*
X731206Y7610D01*
X731196Y7650D01*
X731191Y7695D01*
Y7735D01*
X731186Y7780D01*
X731191Y7825D01*
Y7865D01*
X731196Y7910D01*
X731206Y7950D01*
X731211Y7990D01*
X731226Y8035D01*
X731236Y8075D01*
X731251Y8115D01*
X731271Y8155D01*
X731286Y8190D01*
X731306Y8230D01*
X731406Y8370D01*
X731436Y8400D01*
Y9530D01*
X731446Y9655D01*
X731486Y9780D01*
X731546Y9890D01*
X731626Y9990D01*
X731726Y10070D01*
X731836Y10130D01*
X731961Y10170D01*
X732086Y10180D01*
X732211Y10170D01*
X732336Y10130D01*
X732446Y10070D01*
X732546Y9990D01*
X732626Y9890D01*
X732686Y9780D01*
X732726Y9655D01*
X732736Y9530D01*
Y8400D01*
X732766Y8370D01*
X732866Y8230D01*
X732886Y8190D01*
X732901Y8155D01*
X732921Y8115D01*
X732936Y8075D01*
X732946Y8035D01*
X732961Y7990D01*
X732966Y7950D01*
X732976Y7910D01*
X732981Y7865D01*
Y7825D01*
X732986Y7780D01*
X732981Y7735D01*
Y7695D01*
X732976Y7650D01*
X732966Y7610D01*
X732961Y7570D01*
X732946Y7525D01*
X732936Y7485D01*
X732921Y7445D01*
X732901Y7405D01*
X732886Y7370D01*
X732866Y7330D01*
X732766Y7190D01*
X732736Y7160D01*
Y3730D01*
X732726Y3605D01*
X732686Y3480D01*
X732626Y3370D01*
X732546Y3270D01*
X732446Y3190D01*
X732336Y3130D01*
X732211Y3090D01*
X732086Y3080D01*
G37*
G36*
G01X727362D02*
X727237Y3090D01*
X727112Y3130D01*
X727002Y3190D01*
X726902Y3270D01*
X726822Y3370D01*
X726762Y3480D01*
X726722Y3605D01*
X726712Y3730D01*
Y7160D01*
X726682Y7190D01*
X726582Y7330D01*
X726562Y7370D01*
X726547Y7405D01*
X726527Y7445D01*
X726512Y7485D01*
X726502Y7525D01*
X726487Y7570D01*
X726482Y7610D01*
X726472Y7650D01*
X726467Y7695D01*
Y7735D01*
X726462Y7780D01*
X726467Y7825D01*
Y7865D01*
X726472Y7910D01*
X726482Y7950D01*
X726487Y7990D01*
X726502Y8035D01*
X726512Y8075D01*
X726527Y8115D01*
X726547Y8155D01*
X726562Y8190D01*
X726582Y8230D01*
X726682Y8370D01*
X726712Y8400D01*
Y9530D01*
X726722Y9655D01*
X726762Y9780D01*
X726822Y9890D01*
X726902Y9990D01*
X727002Y10070D01*
X727112Y10130D01*
X727237Y10170D01*
X727362Y10180D01*
X727487Y10170D01*
X727612Y10130D01*
X727722Y10070D01*
X727822Y9990D01*
X727902Y9890D01*
X727962Y9780D01*
X728002Y9655D01*
X728012Y9530D01*
Y8400D01*
X728042Y8370D01*
X728142Y8230D01*
X728162Y8190D01*
X728177Y8155D01*
X728197Y8115D01*
X728212Y8075D01*
X728222Y8035D01*
X728237Y7990D01*
X728242Y7950D01*
X728252Y7910D01*
X728257Y7865D01*
Y7825D01*
X728262Y7780D01*
X728257Y7735D01*
Y7695D01*
X728252Y7650D01*
X728242Y7610D01*
X728237Y7570D01*
X728222Y7525D01*
X728212Y7485D01*
X728197Y7445D01*
X728177Y7405D01*
X728162Y7370D01*
X728142Y7330D01*
X728042Y7190D01*
X728012Y7160D01*
Y3730D01*
X728002Y3605D01*
X727962Y3480D01*
X727902Y3370D01*
X727822Y3270D01*
X727722Y3190D01*
X727612Y3130D01*
X727487Y3090D01*
X727362Y3080D01*
G37*
G36*
G01X750984D02*
X750859Y3090D01*
X750734Y3130D01*
X750624Y3190D01*
X750524Y3270D01*
X750444Y3370D01*
X750384Y3480D01*
X750344Y3605D01*
X750334Y3730D01*
Y7160D01*
X750304Y7190D01*
X750204Y7330D01*
X750184Y7370D01*
X750169Y7405D01*
X750149Y7445D01*
X750134Y7485D01*
X750124Y7525D01*
X750109Y7570D01*
X750104Y7610D01*
X750094Y7650D01*
X750089Y7695D01*
Y7735D01*
X750084Y7780D01*
X750089Y7825D01*
Y7865D01*
X750094Y7910D01*
X750104Y7950D01*
X750109Y7990D01*
X750124Y8035D01*
X750134Y8075D01*
X750149Y8115D01*
X750169Y8155D01*
X750184Y8190D01*
X750204Y8230D01*
X750304Y8370D01*
X750334Y8400D01*
Y9530D01*
X750344Y9655D01*
X750384Y9780D01*
X750444Y9890D01*
X750524Y9990D01*
X750624Y10070D01*
X750734Y10130D01*
X750859Y10170D01*
X750984Y10180D01*
X751109Y10170D01*
X751234Y10130D01*
X751344Y10070D01*
X751444Y9990D01*
X751524Y9890D01*
X751584Y9780D01*
X751624Y9655D01*
X751634Y9530D01*
Y8400D01*
X751664Y8370D01*
X751764Y8230D01*
X751784Y8190D01*
X751799Y8155D01*
X751819Y8115D01*
X751834Y8075D01*
X751844Y8035D01*
X751859Y7990D01*
X751864Y7950D01*
X751874Y7910D01*
X751879Y7865D01*
Y7825D01*
X751884Y7780D01*
X751879Y7735D01*
Y7695D01*
X751874Y7650D01*
X751864Y7610D01*
X751859Y7570D01*
X751844Y7525D01*
X751834Y7485D01*
X751819Y7445D01*
X751799Y7405D01*
X751784Y7370D01*
X751764Y7330D01*
X751664Y7190D01*
X751634Y7160D01*
Y3730D01*
X751624Y3605D01*
X751584Y3480D01*
X751524Y3370D01*
X751444Y3270D01*
X751344Y3190D01*
X751234Y3130D01*
X751109Y3090D01*
X750984Y3080D01*
G37*
G36*
G01X746260D02*
X746135Y3090D01*
X746010Y3130D01*
X745900Y3190D01*
X745800Y3270D01*
X745720Y3370D01*
X745660Y3480D01*
X745620Y3605D01*
X745610Y3730D01*
Y7160D01*
X745580Y7190D01*
X745480Y7330D01*
X745460Y7370D01*
X745445Y7405D01*
X745425Y7445D01*
X745410Y7485D01*
X745400Y7525D01*
X745385Y7570D01*
X745380Y7610D01*
X745370Y7650D01*
X745365Y7695D01*
Y7735D01*
X745360Y7780D01*
X745365Y7825D01*
Y7865D01*
X745370Y7910D01*
X745380Y7950D01*
X745385Y7990D01*
X745400Y8035D01*
X745410Y8075D01*
X745425Y8115D01*
X745445Y8155D01*
X745460Y8190D01*
X745480Y8230D01*
X745580Y8370D01*
X745610Y8400D01*
Y9530D01*
X745620Y9655D01*
X745660Y9780D01*
X745720Y9890D01*
X745800Y9990D01*
X745900Y10070D01*
X746010Y10130D01*
X746135Y10170D01*
X746260Y10180D01*
X746385Y10170D01*
X746510Y10130D01*
X746620Y10070D01*
X746720Y9990D01*
X746800Y9890D01*
X746860Y9780D01*
X746900Y9655D01*
X746910Y9530D01*
Y8400D01*
X746940Y8370D01*
X747040Y8230D01*
X747060Y8190D01*
X747075Y8155D01*
X747095Y8115D01*
X747110Y8075D01*
X747120Y8035D01*
X747135Y7990D01*
X747140Y7950D01*
X747150Y7910D01*
X747155Y7865D01*
Y7825D01*
X747160Y7780D01*
X747155Y7735D01*
Y7695D01*
X747150Y7650D01*
X747140Y7610D01*
X747135Y7570D01*
X747120Y7525D01*
X747110Y7485D01*
X747095Y7445D01*
X747075Y7405D01*
X747060Y7370D01*
X747040Y7330D01*
X746940Y7190D01*
X746910Y7160D01*
Y3730D01*
X746900Y3605D01*
X746860Y3480D01*
X746800Y3370D01*
X746720Y3270D01*
X746620Y3190D01*
X746510Y3130D01*
X746385Y3090D01*
X746260Y3080D01*
G37*
G54D77*
X237000Y128600D03*
X241000D03*
X239000Y123400D03*
X518500Y193600D03*
X522500D03*
X520500Y188400D03*
G54D68*
X183840Y117340D03*
X176360D03*
X183840Y119900D03*
X176360D03*
X183840Y122460D03*
X176360D03*
X269260Y53060D03*
X276740D03*
X269260Y50500D03*
Y47940D03*
X276740D03*
Y50500D03*
X721260Y187440D03*
Y190000D03*
Y192560D03*
X728740D03*
Y190000D03*
Y187440D03*
G54D59*
X155740Y180020D03*
Y187380D03*
X163060Y165320D03*
X157940D03*
X163060Y172680D03*
X157940D03*
X160500D03*
X160860Y180020D03*
Y187380D03*
X158300D03*
X447940Y262820D03*
Y270180D03*
X453060D03*
Y262820D03*
X450500D03*
G54D86*
X313392Y118471D03*
Y136191D03*
Y130531D03*
Y124131D03*
Y148261D03*
Y141861D03*
Y165991D03*
Y153921D03*
Y159591D03*
Y177311D03*
Y171651D03*
Y189381D03*
Y183711D03*
X441332Y119281D03*
Y131351D03*
Y124951D03*
Y149071D03*
Y137011D03*
Y142671D03*
Y166801D03*
Y160401D03*
Y154741D03*
Y172471D03*
Y178131D03*
Y190191D03*
Y184531D03*
G36*
G01X508858Y35416D02*
X508733Y35426D01*
X508608Y35466D01*
X508498Y35526D01*
X508398Y35606D01*
X508318Y35706D01*
X508258Y35816D01*
X508218Y35941D01*
X508208Y36066D01*
Y38191D01*
X508178Y38221D01*
X508153Y38256D01*
X508123Y38291D01*
X508103Y38326D01*
X508078Y38361D01*
X508038Y38441D01*
X507993Y38561D01*
X507983Y38601D01*
X507973Y38646D01*
X507968Y38686D01*
X507958Y38731D01*
Y38901D01*
X507968Y38946D01*
X507973Y38986D01*
X507983Y39031D01*
X507993Y39071D01*
X508038Y39191D01*
X508078Y39271D01*
X508103Y39306D01*
X508123Y39341D01*
X508153Y39376D01*
X508178Y39411D01*
X508208Y39441D01*
Y41866D01*
X508218Y41991D01*
X508258Y42116D01*
X508318Y42226D01*
X508398Y42326D01*
X508498Y42406D01*
X508608Y42466D01*
X508733Y42506D01*
X508858Y42516D01*
X508983Y42506D01*
X509108Y42466D01*
X509218Y42406D01*
X509318Y42326D01*
X509398Y42226D01*
X509458Y42116D01*
X509498Y41991D01*
X509508Y41866D01*
Y39436D01*
X509538Y39406D01*
X509638Y39266D01*
X509658Y39226D01*
X509673Y39191D01*
X509693Y39151D01*
X509708Y39111D01*
X509718Y39071D01*
X509733Y39026D01*
X509738Y38986D01*
X509748Y38946D01*
X509753Y38901D01*
Y38861D01*
X509758Y38816D01*
X509753Y38771D01*
Y38731D01*
X509748Y38686D01*
X509738Y38646D01*
X509733Y38606D01*
X509718Y38561D01*
X509708Y38521D01*
X509693Y38481D01*
X509673Y38441D01*
X509658Y38406D01*
X509638Y38366D01*
X509538Y38226D01*
X509508Y38196D01*
Y36066D01*
X509498Y35941D01*
X509458Y35816D01*
X509398Y35706D01*
X509318Y35606D01*
X509218Y35526D01*
X509108Y35466D01*
X508983Y35426D01*
X508858Y35416D01*
G37*
G36*
G01X523031D02*
X522906Y35426D01*
X522781Y35466D01*
X522671Y35526D01*
X522571Y35606D01*
X522491Y35706D01*
X522431Y35816D01*
X522391Y35941D01*
X522381Y36066D01*
Y38191D01*
X522351Y38221D01*
X522326Y38256D01*
X522296Y38291D01*
X522276Y38326D01*
X522251Y38361D01*
X522211Y38441D01*
X522166Y38561D01*
X522156Y38601D01*
X522146Y38646D01*
X522141Y38686D01*
X522131Y38731D01*
Y38901D01*
X522141Y38946D01*
X522146Y38986D01*
X522156Y39031D01*
X522166Y39071D01*
X522211Y39191D01*
X522251Y39271D01*
X522276Y39306D01*
X522296Y39341D01*
X522326Y39376D01*
X522351Y39411D01*
X522381Y39441D01*
Y41866D01*
X522391Y41991D01*
X522431Y42116D01*
X522491Y42226D01*
X522571Y42326D01*
X522671Y42406D01*
X522781Y42466D01*
X522906Y42506D01*
X523031Y42516D01*
X523156Y42506D01*
X523281Y42466D01*
X523391Y42406D01*
X523491Y42326D01*
X523571Y42226D01*
X523631Y42116D01*
X523671Y41991D01*
X523681Y41866D01*
Y39436D01*
X523711Y39406D01*
X523811Y39266D01*
X523831Y39226D01*
X523846Y39191D01*
X523866Y39151D01*
X523881Y39111D01*
X523891Y39071D01*
X523906Y39026D01*
X523911Y38986D01*
X523921Y38946D01*
X523926Y38901D01*
Y38861D01*
X523931Y38816D01*
X523926Y38771D01*
Y38731D01*
X523921Y38686D01*
X523911Y38646D01*
X523906Y38606D01*
X523891Y38561D01*
X523881Y38521D01*
X523866Y38481D01*
X523846Y38441D01*
X523831Y38406D01*
X523811Y38366D01*
X523711Y38226D01*
X523681Y38196D01*
Y36066D01*
X523671Y35941D01*
X523631Y35816D01*
X523571Y35706D01*
X523491Y35606D01*
X523391Y35526D01*
X523281Y35466D01*
X523156Y35426D01*
X523031Y35416D01*
G37*
G36*
G01X518307D02*
X518182Y35426D01*
X518057Y35466D01*
X517947Y35526D01*
X517847Y35606D01*
X517767Y35706D01*
X517707Y35816D01*
X517667Y35941D01*
X517657Y36066D01*
Y38191D01*
X517627Y38221D01*
X517602Y38256D01*
X517572Y38291D01*
X517552Y38326D01*
X517527Y38361D01*
X517487Y38441D01*
X517442Y38561D01*
X517432Y38601D01*
X517422Y38646D01*
X517417Y38686D01*
X517407Y38731D01*
Y38901D01*
X517417Y38946D01*
X517422Y38986D01*
X517432Y39031D01*
X517442Y39071D01*
X517487Y39191D01*
X517527Y39271D01*
X517552Y39306D01*
X517572Y39341D01*
X517602Y39376D01*
X517627Y39411D01*
X517657Y39441D01*
Y41866D01*
X517667Y41991D01*
X517707Y42116D01*
X517767Y42226D01*
X517847Y42326D01*
X517947Y42406D01*
X518057Y42466D01*
X518182Y42506D01*
X518307Y42516D01*
X518432Y42506D01*
X518557Y42466D01*
X518667Y42406D01*
X518767Y42326D01*
X518847Y42226D01*
X518907Y42116D01*
X518947Y41991D01*
X518957Y41866D01*
Y39436D01*
X518987Y39406D01*
X519087Y39266D01*
X519107Y39226D01*
X519122Y39191D01*
X519142Y39151D01*
X519157Y39111D01*
X519167Y39071D01*
X519182Y39026D01*
X519187Y38986D01*
X519197Y38946D01*
X519202Y38901D01*
Y38861D01*
X519207Y38816D01*
X519202Y38771D01*
Y38731D01*
X519197Y38686D01*
X519187Y38646D01*
X519182Y38606D01*
X519167Y38561D01*
X519157Y38521D01*
X519142Y38481D01*
X519122Y38441D01*
X519107Y38406D01*
X519087Y38366D01*
X518987Y38226D01*
X518957Y38196D01*
Y36066D01*
X518947Y35941D01*
X518907Y35816D01*
X518847Y35706D01*
X518767Y35606D01*
X518667Y35526D01*
X518557Y35466D01*
X518432Y35426D01*
X518307Y35416D01*
G37*
G36*
G01X513582D02*
X513457Y35426D01*
X513332Y35466D01*
X513222Y35526D01*
X513122Y35606D01*
X513042Y35706D01*
X512982Y35816D01*
X512942Y35941D01*
X512932Y36066D01*
Y38191D01*
X512902Y38221D01*
X512877Y38256D01*
X512847Y38291D01*
X512827Y38326D01*
X512802Y38361D01*
X512762Y38441D01*
X512717Y38561D01*
X512707Y38601D01*
X512697Y38646D01*
X512692Y38686D01*
X512682Y38731D01*
Y38901D01*
X512692Y38946D01*
X512697Y38986D01*
X512707Y39031D01*
X512717Y39071D01*
X512762Y39191D01*
X512802Y39271D01*
X512827Y39306D01*
X512847Y39341D01*
X512877Y39376D01*
X512902Y39411D01*
X512932Y39441D01*
Y41866D01*
X512942Y41991D01*
X512982Y42116D01*
X513042Y42226D01*
X513122Y42326D01*
X513222Y42406D01*
X513332Y42466D01*
X513457Y42506D01*
X513582Y42516D01*
X513707Y42506D01*
X513832Y42466D01*
X513942Y42406D01*
X514042Y42326D01*
X514122Y42226D01*
X514182Y42116D01*
X514222Y41991D01*
X514232Y41866D01*
Y39436D01*
X514262Y39406D01*
X514362Y39266D01*
X514382Y39226D01*
X514397Y39191D01*
X514417Y39151D01*
X514432Y39111D01*
X514442Y39071D01*
X514457Y39026D01*
X514462Y38986D01*
X514472Y38946D01*
X514477Y38901D01*
Y38861D01*
X514482Y38816D01*
X514477Y38771D01*
Y38731D01*
X514472Y38686D01*
X514462Y38646D01*
X514457Y38606D01*
X514442Y38561D01*
X514432Y38521D01*
X514417Y38481D01*
X514397Y38441D01*
X514382Y38406D01*
X514362Y38366D01*
X514262Y38226D01*
X514232Y38196D01*
Y36066D01*
X514222Y35941D01*
X514182Y35816D01*
X514122Y35706D01*
X514042Y35606D01*
X513942Y35526D01*
X513832Y35466D01*
X513707Y35426D01*
X513582Y35416D01*
G37*
G36*
G01X541929D02*
X541804Y35426D01*
X541679Y35466D01*
X541569Y35526D01*
X541469Y35606D01*
X541389Y35706D01*
X541329Y35816D01*
X541289Y35941D01*
X541279Y36066D01*
Y38191D01*
X541249Y38221D01*
X541224Y38256D01*
X541194Y38291D01*
X541174Y38326D01*
X541149Y38361D01*
X541109Y38441D01*
X541064Y38561D01*
X541054Y38601D01*
X541044Y38646D01*
X541039Y38686D01*
X541029Y38731D01*
Y38901D01*
X541039Y38946D01*
X541044Y38986D01*
X541054Y39031D01*
X541064Y39071D01*
X541109Y39191D01*
X541149Y39271D01*
X541174Y39306D01*
X541194Y39341D01*
X541224Y39376D01*
X541249Y39411D01*
X541279Y39441D01*
Y41866D01*
X541289Y41991D01*
X541329Y42116D01*
X541389Y42226D01*
X541469Y42326D01*
X541569Y42406D01*
X541679Y42466D01*
X541804Y42506D01*
X541929Y42516D01*
X542054Y42506D01*
X542179Y42466D01*
X542289Y42406D01*
X542389Y42326D01*
X542469Y42226D01*
X542529Y42116D01*
X542569Y41991D01*
X542579Y41866D01*
Y39436D01*
X542609Y39406D01*
X542709Y39266D01*
X542729Y39226D01*
X542744Y39191D01*
X542764Y39151D01*
X542779Y39111D01*
X542789Y39071D01*
X542804Y39026D01*
X542809Y38986D01*
X542819Y38946D01*
X542824Y38901D01*
Y38861D01*
X542829Y38816D01*
X542824Y38771D01*
Y38731D01*
X542819Y38686D01*
X542809Y38646D01*
X542804Y38606D01*
X542789Y38561D01*
X542779Y38521D01*
X542764Y38481D01*
X542744Y38441D01*
X542729Y38406D01*
X542709Y38366D01*
X542609Y38226D01*
X542579Y38196D01*
Y36066D01*
X542569Y35941D01*
X542529Y35816D01*
X542469Y35706D01*
X542389Y35606D01*
X542289Y35526D01*
X542179Y35466D01*
X542054Y35426D01*
X541929Y35416D01*
G37*
G36*
G01X537204D02*
X537079Y35426D01*
X536954Y35466D01*
X536844Y35526D01*
X536744Y35606D01*
X536664Y35706D01*
X536604Y35816D01*
X536564Y35941D01*
X536554Y36066D01*
Y38191D01*
X536524Y38221D01*
X536499Y38256D01*
X536469Y38291D01*
X536449Y38326D01*
X536424Y38361D01*
X536384Y38441D01*
X536339Y38561D01*
X536329Y38601D01*
X536319Y38646D01*
X536314Y38686D01*
X536304Y38731D01*
Y38901D01*
X536314Y38946D01*
X536319Y38986D01*
X536329Y39031D01*
X536339Y39071D01*
X536384Y39191D01*
X536424Y39271D01*
X536449Y39306D01*
X536469Y39341D01*
X536499Y39376D01*
X536524Y39411D01*
X536554Y39441D01*
Y41866D01*
X536564Y41991D01*
X536604Y42116D01*
X536664Y42226D01*
X536744Y42326D01*
X536844Y42406D01*
X536954Y42466D01*
X537079Y42506D01*
X537204Y42516D01*
X537329Y42506D01*
X537454Y42466D01*
X537564Y42406D01*
X537664Y42326D01*
X537744Y42226D01*
X537804Y42116D01*
X537844Y41991D01*
X537854Y41866D01*
Y39436D01*
X537884Y39406D01*
X537984Y39266D01*
X538004Y39226D01*
X538019Y39191D01*
X538039Y39151D01*
X538054Y39111D01*
X538064Y39071D01*
X538079Y39026D01*
X538084Y38986D01*
X538094Y38946D01*
X538099Y38901D01*
Y38861D01*
X538104Y38816D01*
X538099Y38771D01*
Y38731D01*
X538094Y38686D01*
X538084Y38646D01*
X538079Y38606D01*
X538064Y38561D01*
X538054Y38521D01*
X538039Y38481D01*
X538019Y38441D01*
X538004Y38406D01*
X537984Y38366D01*
X537884Y38226D01*
X537854Y38196D01*
Y36066D01*
X537844Y35941D01*
X537804Y35816D01*
X537744Y35706D01*
X537664Y35606D01*
X537564Y35526D01*
X537454Y35466D01*
X537329Y35426D01*
X537204Y35416D01*
G37*
G36*
G01X532480D02*
X532355Y35426D01*
X532230Y35466D01*
X532120Y35526D01*
X532020Y35606D01*
X531940Y35706D01*
X531880Y35816D01*
X531840Y35941D01*
X531830Y36066D01*
Y38191D01*
X531800Y38221D01*
X531775Y38256D01*
X531745Y38291D01*
X531725Y38326D01*
X531700Y38361D01*
X531660Y38441D01*
X531615Y38561D01*
X531605Y38601D01*
X531595Y38646D01*
X531590Y38686D01*
X531580Y38731D01*
Y38901D01*
X531590Y38946D01*
X531595Y38986D01*
X531605Y39031D01*
X531615Y39071D01*
X531660Y39191D01*
X531700Y39271D01*
X531725Y39306D01*
X531745Y39341D01*
X531775Y39376D01*
X531800Y39411D01*
X531830Y39441D01*
Y41866D01*
X531840Y41991D01*
X531880Y42116D01*
X531940Y42226D01*
X532020Y42326D01*
X532120Y42406D01*
X532230Y42466D01*
X532355Y42506D01*
X532480Y42516D01*
X532605Y42506D01*
X532730Y42466D01*
X532840Y42406D01*
X532940Y42326D01*
X533020Y42226D01*
X533080Y42116D01*
X533120Y41991D01*
X533130Y41866D01*
Y39436D01*
X533160Y39406D01*
X533260Y39266D01*
X533280Y39226D01*
X533295Y39191D01*
X533315Y39151D01*
X533330Y39111D01*
X533340Y39071D01*
X533355Y39026D01*
X533360Y38986D01*
X533370Y38946D01*
X533375Y38901D01*
Y38861D01*
X533380Y38816D01*
X533375Y38771D01*
Y38731D01*
X533370Y38686D01*
X533360Y38646D01*
X533355Y38606D01*
X533340Y38561D01*
X533330Y38521D01*
X533315Y38481D01*
X533295Y38441D01*
X533280Y38406D01*
X533260Y38366D01*
X533160Y38226D01*
X533130Y38196D01*
Y36066D01*
X533120Y35941D01*
X533080Y35816D01*
X533020Y35706D01*
X532940Y35606D01*
X532840Y35526D01*
X532730Y35466D01*
X532605Y35426D01*
X532480Y35416D01*
G37*
G36*
G01X527756D02*
X527631Y35426D01*
X527506Y35466D01*
X527396Y35526D01*
X527296Y35606D01*
X527216Y35706D01*
X527156Y35816D01*
X527116Y35941D01*
X527106Y36066D01*
Y38191D01*
X527076Y38221D01*
X527051Y38256D01*
X527021Y38291D01*
X527001Y38326D01*
X526976Y38361D01*
X526936Y38441D01*
X526891Y38561D01*
X526881Y38601D01*
X526871Y38646D01*
X526866Y38686D01*
X526856Y38731D01*
Y38901D01*
X526866Y38946D01*
X526871Y38986D01*
X526881Y39031D01*
X526891Y39071D01*
X526936Y39191D01*
X526976Y39271D01*
X527001Y39306D01*
X527021Y39341D01*
X527051Y39376D01*
X527076Y39411D01*
X527106Y39441D01*
Y41866D01*
X527116Y41991D01*
X527156Y42116D01*
X527216Y42226D01*
X527296Y42326D01*
X527396Y42406D01*
X527506Y42466D01*
X527631Y42506D01*
X527756Y42516D01*
X527881Y42506D01*
X528006Y42466D01*
X528116Y42406D01*
X528216Y42326D01*
X528296Y42226D01*
X528356Y42116D01*
X528396Y41991D01*
X528406Y41866D01*
Y39436D01*
X528436Y39406D01*
X528536Y39266D01*
X528556Y39226D01*
X528571Y39191D01*
X528591Y39151D01*
X528606Y39111D01*
X528616Y39071D01*
X528631Y39026D01*
X528636Y38986D01*
X528646Y38946D01*
X528651Y38901D01*
Y38861D01*
X528656Y38816D01*
X528651Y38771D01*
Y38731D01*
X528646Y38686D01*
X528636Y38646D01*
X528631Y38606D01*
X528616Y38561D01*
X528606Y38521D01*
X528591Y38481D01*
X528571Y38441D01*
X528556Y38406D01*
X528536Y38366D01*
X528436Y38226D01*
X528406Y38196D01*
Y36066D01*
X528396Y35941D01*
X528356Y35816D01*
X528296Y35706D01*
X528216Y35606D01*
X528116Y35526D01*
X528006Y35466D01*
X527881Y35426D01*
X527756Y35416D01*
G37*
G36*
G01X556102D02*
X555977Y35426D01*
X555852Y35466D01*
X555742Y35526D01*
X555642Y35606D01*
X555562Y35706D01*
X555502Y35816D01*
X555462Y35941D01*
X555452Y36066D01*
Y38191D01*
X555422Y38221D01*
X555397Y38256D01*
X555367Y38291D01*
X555347Y38326D01*
X555322Y38361D01*
X555282Y38441D01*
X555237Y38561D01*
X555227Y38601D01*
X555217Y38646D01*
X555212Y38686D01*
X555202Y38731D01*
Y38901D01*
X555212Y38946D01*
X555217Y38986D01*
X555227Y39031D01*
X555237Y39071D01*
X555282Y39191D01*
X555322Y39271D01*
X555347Y39306D01*
X555367Y39341D01*
X555397Y39376D01*
X555422Y39411D01*
X555452Y39441D01*
Y41866D01*
X555462Y41991D01*
X555502Y42116D01*
X555562Y42226D01*
X555642Y42326D01*
X555742Y42406D01*
X555852Y42466D01*
X555977Y42506D01*
X556102Y42516D01*
X556227Y42506D01*
X556352Y42466D01*
X556462Y42406D01*
X556562Y42326D01*
X556642Y42226D01*
X556702Y42116D01*
X556742Y41991D01*
X556752Y41866D01*
Y39436D01*
X556782Y39406D01*
X556882Y39266D01*
X556902Y39226D01*
X556917Y39191D01*
X556937Y39151D01*
X556952Y39111D01*
X556962Y39071D01*
X556977Y39026D01*
X556982Y38986D01*
X556992Y38946D01*
X556997Y38901D01*
Y38861D01*
X557002Y38816D01*
X556997Y38771D01*
Y38731D01*
X556992Y38686D01*
X556982Y38646D01*
X556977Y38606D01*
X556962Y38561D01*
X556952Y38521D01*
X556937Y38481D01*
X556917Y38441D01*
X556902Y38406D01*
X556882Y38366D01*
X556782Y38226D01*
X556752Y38196D01*
Y36066D01*
X556742Y35941D01*
X556702Y35816D01*
X556642Y35706D01*
X556562Y35606D01*
X556462Y35526D01*
X556352Y35466D01*
X556227Y35426D01*
X556102Y35416D01*
G37*
G36*
G01X551378D02*
X551253Y35426D01*
X551128Y35466D01*
X551018Y35526D01*
X550918Y35606D01*
X550838Y35706D01*
X550778Y35816D01*
X550738Y35941D01*
X550728Y36066D01*
Y38191D01*
X550698Y38221D01*
X550673Y38256D01*
X550643Y38291D01*
X550623Y38326D01*
X550598Y38361D01*
X550558Y38441D01*
X550513Y38561D01*
X550503Y38601D01*
X550493Y38646D01*
X550488Y38686D01*
X550478Y38731D01*
Y38901D01*
X550488Y38946D01*
X550493Y38986D01*
X550503Y39031D01*
X550513Y39071D01*
X550558Y39191D01*
X550598Y39271D01*
X550623Y39306D01*
X550643Y39341D01*
X550673Y39376D01*
X550698Y39411D01*
X550728Y39441D01*
Y41866D01*
X550738Y41991D01*
X550778Y42116D01*
X550838Y42226D01*
X550918Y42326D01*
X551018Y42406D01*
X551128Y42466D01*
X551253Y42506D01*
X551378Y42516D01*
X551503Y42506D01*
X551628Y42466D01*
X551738Y42406D01*
X551838Y42326D01*
X551918Y42226D01*
X551978Y42116D01*
X552018Y41991D01*
X552028Y41866D01*
Y39436D01*
X552058Y39406D01*
X552158Y39266D01*
X552178Y39226D01*
X552193Y39191D01*
X552213Y39151D01*
X552228Y39111D01*
X552238Y39071D01*
X552253Y39026D01*
X552258Y38986D01*
X552268Y38946D01*
X552273Y38901D01*
Y38861D01*
X552278Y38816D01*
X552273Y38771D01*
Y38731D01*
X552268Y38686D01*
X552258Y38646D01*
X552253Y38606D01*
X552238Y38561D01*
X552228Y38521D01*
X552213Y38481D01*
X552193Y38441D01*
X552178Y38406D01*
X552158Y38366D01*
X552058Y38226D01*
X552028Y38196D01*
Y36066D01*
X552018Y35941D01*
X551978Y35816D01*
X551918Y35706D01*
X551838Y35606D01*
X551738Y35526D01*
X551628Y35466D01*
X551503Y35426D01*
X551378Y35416D01*
G37*
G36*
G01X546653D02*
X546528Y35426D01*
X546403Y35466D01*
X546293Y35526D01*
X546193Y35606D01*
X546113Y35706D01*
X546053Y35816D01*
X546013Y35941D01*
X546003Y36066D01*
Y38191D01*
X545973Y38221D01*
X545948Y38256D01*
X545918Y38291D01*
X545898Y38326D01*
X545873Y38361D01*
X545833Y38441D01*
X545788Y38561D01*
X545778Y38601D01*
X545768Y38646D01*
X545763Y38686D01*
X545753Y38731D01*
Y38901D01*
X545763Y38946D01*
X545768Y38986D01*
X545778Y39031D01*
X545788Y39071D01*
X545833Y39191D01*
X545873Y39271D01*
X545898Y39306D01*
X545918Y39341D01*
X545948Y39376D01*
X545973Y39411D01*
X546003Y39441D01*
Y41866D01*
X546013Y41991D01*
X546053Y42116D01*
X546113Y42226D01*
X546193Y42326D01*
X546293Y42406D01*
X546403Y42466D01*
X546528Y42506D01*
X546653Y42516D01*
X546778Y42506D01*
X546903Y42466D01*
X547013Y42406D01*
X547113Y42326D01*
X547193Y42226D01*
X547253Y42116D01*
X547293Y41991D01*
X547303Y41866D01*
Y39436D01*
X547333Y39406D01*
X547433Y39266D01*
X547453Y39226D01*
X547468Y39191D01*
X547488Y39151D01*
X547503Y39111D01*
X547513Y39071D01*
X547528Y39026D01*
X547533Y38986D01*
X547543Y38946D01*
X547548Y38901D01*
Y38861D01*
X547553Y38816D01*
X547548Y38771D01*
Y38731D01*
X547543Y38686D01*
X547533Y38646D01*
X547528Y38606D01*
X547513Y38561D01*
X547503Y38521D01*
X547488Y38481D01*
X547468Y38441D01*
X547453Y38406D01*
X547433Y38366D01*
X547333Y38226D01*
X547303Y38196D01*
Y36066D01*
X547293Y35941D01*
X547253Y35816D01*
X547193Y35706D01*
X547113Y35606D01*
X547013Y35526D01*
X546903Y35466D01*
X546778Y35426D01*
X546653Y35416D01*
G37*
G36*
G01X570275D02*
X570150Y35426D01*
X570025Y35466D01*
X569915Y35526D01*
X569815Y35606D01*
X569735Y35706D01*
X569675Y35816D01*
X569635Y35941D01*
X569625Y36066D01*
Y38191D01*
X569595Y38221D01*
X569570Y38256D01*
X569540Y38291D01*
X569520Y38326D01*
X569495Y38361D01*
X569455Y38441D01*
X569410Y38561D01*
X569400Y38601D01*
X569390Y38646D01*
X569385Y38686D01*
X569375Y38731D01*
Y38901D01*
X569385Y38946D01*
X569390Y38986D01*
X569400Y39031D01*
X569410Y39071D01*
X569455Y39191D01*
X569495Y39271D01*
X569520Y39306D01*
X569540Y39341D01*
X569570Y39376D01*
X569595Y39411D01*
X569625Y39441D01*
Y41866D01*
X569635Y41991D01*
X569675Y42116D01*
X569735Y42226D01*
X569815Y42326D01*
X569915Y42406D01*
X570025Y42466D01*
X570150Y42506D01*
X570275Y42516D01*
X570400Y42506D01*
X570525Y42466D01*
X570635Y42406D01*
X570735Y42326D01*
X570815Y42226D01*
X570875Y42116D01*
X570915Y41991D01*
X570925Y41866D01*
Y39436D01*
X570955Y39406D01*
X571055Y39266D01*
X571075Y39226D01*
X571090Y39191D01*
X571110Y39151D01*
X571125Y39111D01*
X571135Y39071D01*
X571150Y39026D01*
X571155Y38986D01*
X571165Y38946D01*
X571170Y38901D01*
Y38861D01*
X571175Y38816D01*
X571170Y38771D01*
Y38731D01*
X571165Y38686D01*
X571155Y38646D01*
X571150Y38606D01*
X571135Y38561D01*
X571125Y38521D01*
X571110Y38481D01*
X571090Y38441D01*
X571075Y38406D01*
X571055Y38366D01*
X570955Y38226D01*
X570925Y38196D01*
Y36066D01*
X570915Y35941D01*
X570875Y35816D01*
X570815Y35706D01*
X570735Y35606D01*
X570635Y35526D01*
X570525Y35466D01*
X570400Y35426D01*
X570275Y35416D01*
G37*
G36*
G01X565551D02*
X565426Y35426D01*
X565301Y35466D01*
X565191Y35526D01*
X565091Y35606D01*
X565011Y35706D01*
X564951Y35816D01*
X564911Y35941D01*
X564901Y36066D01*
Y38191D01*
X564871Y38221D01*
X564846Y38256D01*
X564816Y38291D01*
X564796Y38326D01*
X564771Y38361D01*
X564731Y38441D01*
X564686Y38561D01*
X564676Y38601D01*
X564666Y38646D01*
X564661Y38686D01*
X564651Y38731D01*
Y38901D01*
X564661Y38946D01*
X564666Y38986D01*
X564676Y39031D01*
X564686Y39071D01*
X564731Y39191D01*
X564771Y39271D01*
X564796Y39306D01*
X564816Y39341D01*
X564846Y39376D01*
X564871Y39411D01*
X564901Y39441D01*
Y41866D01*
X564911Y41991D01*
X564951Y42116D01*
X565011Y42226D01*
X565091Y42326D01*
X565191Y42406D01*
X565301Y42466D01*
X565426Y42506D01*
X565551Y42516D01*
X565676Y42506D01*
X565801Y42466D01*
X565911Y42406D01*
X566011Y42326D01*
X566091Y42226D01*
X566151Y42116D01*
X566191Y41991D01*
X566201Y41866D01*
Y39436D01*
X566231Y39406D01*
X566331Y39266D01*
X566351Y39226D01*
X566366Y39191D01*
X566386Y39151D01*
X566401Y39111D01*
X566411Y39071D01*
X566426Y39026D01*
X566431Y38986D01*
X566441Y38946D01*
X566446Y38901D01*
Y38861D01*
X566451Y38816D01*
X566446Y38771D01*
Y38731D01*
X566441Y38686D01*
X566431Y38646D01*
X566426Y38606D01*
X566411Y38561D01*
X566401Y38521D01*
X566386Y38481D01*
X566366Y38441D01*
X566351Y38406D01*
X566331Y38366D01*
X566231Y38226D01*
X566201Y38196D01*
Y36066D01*
X566191Y35941D01*
X566151Y35816D01*
X566091Y35706D01*
X566011Y35606D01*
X565911Y35526D01*
X565801Y35466D01*
X565676Y35426D01*
X565551Y35416D01*
G37*
G36*
G01X560827D02*
X560702Y35426D01*
X560577Y35466D01*
X560467Y35526D01*
X560367Y35606D01*
X560287Y35706D01*
X560227Y35816D01*
X560187Y35941D01*
X560177Y36066D01*
Y38191D01*
X560147Y38221D01*
X560122Y38256D01*
X560092Y38291D01*
X560072Y38326D01*
X560047Y38361D01*
X560007Y38441D01*
X559962Y38561D01*
X559952Y38601D01*
X559942Y38646D01*
X559937Y38686D01*
X559927Y38731D01*
Y38901D01*
X559937Y38946D01*
X559942Y38986D01*
X559952Y39031D01*
X559962Y39071D01*
X560007Y39191D01*
X560047Y39271D01*
X560072Y39306D01*
X560092Y39341D01*
X560122Y39376D01*
X560147Y39411D01*
X560177Y39441D01*
Y41866D01*
X560187Y41991D01*
X560227Y42116D01*
X560287Y42226D01*
X560367Y42326D01*
X560467Y42406D01*
X560577Y42466D01*
X560702Y42506D01*
X560827Y42516D01*
X560952Y42506D01*
X561077Y42466D01*
X561187Y42406D01*
X561287Y42326D01*
X561367Y42226D01*
X561427Y42116D01*
X561467Y41991D01*
X561477Y41866D01*
Y39436D01*
X561507Y39406D01*
X561607Y39266D01*
X561627Y39226D01*
X561642Y39191D01*
X561662Y39151D01*
X561677Y39111D01*
X561687Y39071D01*
X561702Y39026D01*
X561707Y38986D01*
X561717Y38946D01*
X561722Y38901D01*
Y38861D01*
X561727Y38816D01*
X561722Y38771D01*
Y38731D01*
X561717Y38686D01*
X561707Y38646D01*
X561702Y38606D01*
X561687Y38561D01*
X561677Y38521D01*
X561662Y38481D01*
X561642Y38441D01*
X561627Y38406D01*
X561607Y38366D01*
X561507Y38226D01*
X561477Y38196D01*
Y36066D01*
X561467Y35941D01*
X561427Y35816D01*
X561367Y35706D01*
X561287Y35606D01*
X561187Y35526D01*
X561077Y35466D01*
X560952Y35426D01*
X560827Y35416D01*
G37*
G36*
G01X584449D02*
X584324Y35426D01*
X584199Y35466D01*
X584089Y35526D01*
X583989Y35606D01*
X583909Y35706D01*
X583849Y35816D01*
X583809Y35941D01*
X583799Y36066D01*
Y38191D01*
X583769Y38221D01*
X583744Y38256D01*
X583714Y38291D01*
X583694Y38326D01*
X583669Y38361D01*
X583629Y38441D01*
X583584Y38561D01*
X583574Y38601D01*
X583564Y38646D01*
X583559Y38686D01*
X583549Y38731D01*
Y38901D01*
X583559Y38946D01*
X583564Y38986D01*
X583574Y39031D01*
X583584Y39071D01*
X583629Y39191D01*
X583669Y39271D01*
X583694Y39306D01*
X583714Y39341D01*
X583744Y39376D01*
X583769Y39411D01*
X583799Y39441D01*
Y41866D01*
X583809Y41991D01*
X583849Y42116D01*
X583909Y42226D01*
X583989Y42326D01*
X584089Y42406D01*
X584199Y42466D01*
X584324Y42506D01*
X584449Y42516D01*
X584574Y42506D01*
X584699Y42466D01*
X584809Y42406D01*
X584909Y42326D01*
X584989Y42226D01*
X585049Y42116D01*
X585089Y41991D01*
X585099Y41866D01*
Y39436D01*
X585129Y39406D01*
X585229Y39266D01*
X585249Y39226D01*
X585264Y39191D01*
X585284Y39151D01*
X585299Y39111D01*
X585309Y39071D01*
X585324Y39026D01*
X585329Y38986D01*
X585339Y38946D01*
X585344Y38901D01*
Y38861D01*
X585349Y38816D01*
X585344Y38771D01*
Y38731D01*
X585339Y38686D01*
X585329Y38646D01*
X585324Y38606D01*
X585309Y38561D01*
X585299Y38521D01*
X585284Y38481D01*
X585264Y38441D01*
X585249Y38406D01*
X585229Y38366D01*
X585129Y38226D01*
X585099Y38196D01*
Y36066D01*
X585089Y35941D01*
X585049Y35816D01*
X584989Y35706D01*
X584909Y35606D01*
X584809Y35526D01*
X584699Y35466D01*
X584574Y35426D01*
X584449Y35416D01*
G37*
G36*
G01X579724D02*
X579599Y35426D01*
X579474Y35466D01*
X579364Y35526D01*
X579264Y35606D01*
X579184Y35706D01*
X579124Y35816D01*
X579084Y35941D01*
X579074Y36066D01*
Y38191D01*
X579044Y38221D01*
X579019Y38256D01*
X578989Y38291D01*
X578969Y38326D01*
X578944Y38361D01*
X578904Y38441D01*
X578859Y38561D01*
X578849Y38601D01*
X578839Y38646D01*
X578834Y38686D01*
X578824Y38731D01*
Y38901D01*
X578834Y38946D01*
X578839Y38986D01*
X578849Y39031D01*
X578859Y39071D01*
X578904Y39191D01*
X578944Y39271D01*
X578969Y39306D01*
X578989Y39341D01*
X579019Y39376D01*
X579044Y39411D01*
X579074Y39441D01*
Y41866D01*
X579084Y41991D01*
X579124Y42116D01*
X579184Y42226D01*
X579264Y42326D01*
X579364Y42406D01*
X579474Y42466D01*
X579599Y42506D01*
X579724Y42516D01*
X579849Y42506D01*
X579974Y42466D01*
X580084Y42406D01*
X580184Y42326D01*
X580264Y42226D01*
X580324Y42116D01*
X580364Y41991D01*
X580374Y41866D01*
Y39436D01*
X580404Y39406D01*
X580504Y39266D01*
X580524Y39226D01*
X580539Y39191D01*
X580559Y39151D01*
X580574Y39111D01*
X580584Y39071D01*
X580599Y39026D01*
X580604Y38986D01*
X580614Y38946D01*
X580619Y38901D01*
Y38861D01*
X580624Y38816D01*
X580619Y38771D01*
Y38731D01*
X580614Y38686D01*
X580604Y38646D01*
X580599Y38606D01*
X580584Y38561D01*
X580574Y38521D01*
X580559Y38481D01*
X580539Y38441D01*
X580524Y38406D01*
X580504Y38366D01*
X580404Y38226D01*
X580374Y38196D01*
Y36066D01*
X580364Y35941D01*
X580324Y35816D01*
X580264Y35706D01*
X580184Y35606D01*
X580084Y35526D01*
X579974Y35466D01*
X579849Y35426D01*
X579724Y35416D01*
G37*
G36*
G01X575000D02*
X574875Y35426D01*
X574750Y35466D01*
X574640Y35526D01*
X574540Y35606D01*
X574460Y35706D01*
X574400Y35816D01*
X574360Y35941D01*
X574350Y36066D01*
Y38191D01*
X574320Y38221D01*
X574295Y38256D01*
X574265Y38291D01*
X574245Y38326D01*
X574220Y38361D01*
X574180Y38441D01*
X574135Y38561D01*
X574125Y38601D01*
X574115Y38646D01*
X574110Y38686D01*
X574100Y38731D01*
Y38901D01*
X574110Y38946D01*
X574115Y38986D01*
X574125Y39031D01*
X574135Y39071D01*
X574180Y39191D01*
X574220Y39271D01*
X574245Y39306D01*
X574265Y39341D01*
X574295Y39376D01*
X574320Y39411D01*
X574350Y39441D01*
Y41866D01*
X574360Y41991D01*
X574400Y42116D01*
X574460Y42226D01*
X574540Y42326D01*
X574640Y42406D01*
X574750Y42466D01*
X574875Y42506D01*
X575000Y42516D01*
X575125Y42506D01*
X575250Y42466D01*
X575360Y42406D01*
X575460Y42326D01*
X575540Y42226D01*
X575600Y42116D01*
X575640Y41991D01*
X575650Y41866D01*
Y39436D01*
X575680Y39406D01*
X575780Y39266D01*
X575800Y39226D01*
X575815Y39191D01*
X575835Y39151D01*
X575850Y39111D01*
X575860Y39071D01*
X575875Y39026D01*
X575880Y38986D01*
X575890Y38946D01*
X575895Y38901D01*
Y38861D01*
X575900Y38816D01*
X575895Y38771D01*
Y38731D01*
X575890Y38686D01*
X575880Y38646D01*
X575875Y38606D01*
X575860Y38561D01*
X575850Y38521D01*
X575835Y38481D01*
X575815Y38441D01*
X575800Y38406D01*
X575780Y38366D01*
X575680Y38226D01*
X575650Y38196D01*
Y36066D01*
X575640Y35941D01*
X575600Y35816D01*
X575540Y35706D01*
X575460Y35606D01*
X575360Y35526D01*
X575250Y35466D01*
X575125Y35426D01*
X575000Y35416D01*
G37*
G36*
G01X603346D02*
X603221Y35426D01*
X603096Y35466D01*
X602986Y35526D01*
X602886Y35606D01*
X602806Y35706D01*
X602746Y35816D01*
X602706Y35941D01*
X602696Y36066D01*
Y38191D01*
X602666Y38221D01*
X602641Y38256D01*
X602611Y38291D01*
X602591Y38326D01*
X602566Y38361D01*
X602526Y38441D01*
X602481Y38561D01*
X602471Y38601D01*
X602461Y38646D01*
X602456Y38686D01*
X602446Y38731D01*
Y38901D01*
X602456Y38946D01*
X602461Y38986D01*
X602471Y39031D01*
X602481Y39071D01*
X602526Y39191D01*
X602566Y39271D01*
X602591Y39306D01*
X602611Y39341D01*
X602641Y39376D01*
X602666Y39411D01*
X602696Y39441D01*
Y41866D01*
X602706Y41991D01*
X602746Y42116D01*
X602806Y42226D01*
X602886Y42326D01*
X602986Y42406D01*
X603096Y42466D01*
X603221Y42506D01*
X603346Y42516D01*
X603471Y42506D01*
X603596Y42466D01*
X603706Y42406D01*
X603806Y42326D01*
X603886Y42226D01*
X603946Y42116D01*
X603986Y41991D01*
X603996Y41866D01*
Y39436D01*
X604026Y39406D01*
X604126Y39266D01*
X604146Y39226D01*
X604161Y39191D01*
X604181Y39151D01*
X604196Y39111D01*
X604206Y39071D01*
X604221Y39026D01*
X604226Y38986D01*
X604236Y38946D01*
X604241Y38901D01*
Y38861D01*
X604246Y38816D01*
X604241Y38771D01*
Y38731D01*
X604236Y38686D01*
X604226Y38646D01*
X604221Y38606D01*
X604206Y38561D01*
X604196Y38521D01*
X604181Y38481D01*
X604161Y38441D01*
X604146Y38406D01*
X604126Y38366D01*
X604026Y38226D01*
X603996Y38196D01*
Y36066D01*
X603986Y35941D01*
X603946Y35816D01*
X603886Y35706D01*
X603806Y35606D01*
X603706Y35526D01*
X603596Y35466D01*
X603471Y35426D01*
X603346Y35416D01*
G37*
G36*
G01X589173D02*
X589048Y35426D01*
X588923Y35466D01*
X588813Y35526D01*
X588713Y35606D01*
X588633Y35706D01*
X588573Y35816D01*
X588533Y35941D01*
X588523Y36066D01*
Y38191D01*
X588493Y38221D01*
X588468Y38256D01*
X588438Y38291D01*
X588418Y38326D01*
X588393Y38361D01*
X588353Y38441D01*
X588308Y38561D01*
X588298Y38601D01*
X588288Y38646D01*
X588283Y38686D01*
X588273Y38731D01*
Y38901D01*
X588283Y38946D01*
X588288Y38986D01*
X588298Y39031D01*
X588308Y39071D01*
X588353Y39191D01*
X588393Y39271D01*
X588418Y39306D01*
X588438Y39341D01*
X588468Y39376D01*
X588493Y39411D01*
X588523Y39441D01*
Y41866D01*
X588533Y41991D01*
X588573Y42116D01*
X588633Y42226D01*
X588713Y42326D01*
X588813Y42406D01*
X588923Y42466D01*
X589048Y42506D01*
X589173Y42516D01*
X589298Y42506D01*
X589423Y42466D01*
X589533Y42406D01*
X589633Y42326D01*
X589713Y42226D01*
X589773Y42116D01*
X589813Y41991D01*
X589823Y41866D01*
Y39436D01*
X589853Y39406D01*
X589953Y39266D01*
X589973Y39226D01*
X589988Y39191D01*
X590008Y39151D01*
X590023Y39111D01*
X590033Y39071D01*
X590048Y39026D01*
X590053Y38986D01*
X590063Y38946D01*
X590068Y38901D01*
Y38861D01*
X590073Y38816D01*
X590068Y38771D01*
Y38731D01*
X590063Y38686D01*
X590053Y38646D01*
X590048Y38606D01*
X590033Y38561D01*
X590023Y38521D01*
X590008Y38481D01*
X589988Y38441D01*
X589973Y38406D01*
X589953Y38366D01*
X589853Y38226D01*
X589823Y38196D01*
Y36066D01*
X589813Y35941D01*
X589773Y35816D01*
X589713Y35706D01*
X589633Y35606D01*
X589533Y35526D01*
X589423Y35466D01*
X589298Y35426D01*
X589173Y35416D01*
G37*
G36*
G01X617519D02*
X617394Y35426D01*
X617269Y35466D01*
X617159Y35526D01*
X617059Y35606D01*
X616979Y35706D01*
X616919Y35816D01*
X616879Y35941D01*
X616869Y36066D01*
Y38191D01*
X616839Y38221D01*
X616814Y38256D01*
X616784Y38291D01*
X616764Y38326D01*
X616739Y38361D01*
X616699Y38441D01*
X616654Y38561D01*
X616644Y38601D01*
X616634Y38646D01*
X616629Y38686D01*
X616619Y38731D01*
Y38901D01*
X616629Y38946D01*
X616634Y38986D01*
X616644Y39031D01*
X616654Y39071D01*
X616699Y39191D01*
X616739Y39271D01*
X616764Y39306D01*
X616784Y39341D01*
X616814Y39376D01*
X616839Y39411D01*
X616869Y39441D01*
Y41866D01*
X616879Y41991D01*
X616919Y42116D01*
X616979Y42226D01*
X617059Y42326D01*
X617159Y42406D01*
X617269Y42466D01*
X617394Y42506D01*
X617519Y42516D01*
X617644Y42506D01*
X617769Y42466D01*
X617879Y42406D01*
X617979Y42326D01*
X618059Y42226D01*
X618119Y42116D01*
X618159Y41991D01*
X618169Y41866D01*
Y39436D01*
X618199Y39406D01*
X618299Y39266D01*
X618319Y39226D01*
X618334Y39191D01*
X618354Y39151D01*
X618369Y39111D01*
X618379Y39071D01*
X618394Y39026D01*
X618399Y38986D01*
X618409Y38946D01*
X618414Y38901D01*
Y38861D01*
X618419Y38816D01*
X618414Y38771D01*
Y38731D01*
X618409Y38686D01*
X618399Y38646D01*
X618394Y38606D01*
X618379Y38561D01*
X618369Y38521D01*
X618354Y38481D01*
X618334Y38441D01*
X618319Y38406D01*
X618299Y38366D01*
X618199Y38226D01*
X618169Y38196D01*
Y36066D01*
X618159Y35941D01*
X618119Y35816D01*
X618059Y35706D01*
X617979Y35606D01*
X617879Y35526D01*
X617769Y35466D01*
X617644Y35426D01*
X617519Y35416D01*
G37*
G36*
G01X612795D02*
X612670Y35426D01*
X612545Y35466D01*
X612435Y35526D01*
X612335Y35606D01*
X612255Y35706D01*
X612195Y35816D01*
X612155Y35941D01*
X612145Y36066D01*
Y38191D01*
X612115Y38221D01*
X612090Y38256D01*
X612060Y38291D01*
X612040Y38326D01*
X612015Y38361D01*
X611975Y38441D01*
X611930Y38561D01*
X611920Y38601D01*
X611910Y38646D01*
X611905Y38686D01*
X611895Y38731D01*
Y38901D01*
X611905Y38946D01*
X611910Y38986D01*
X611920Y39031D01*
X611930Y39071D01*
X611975Y39191D01*
X612015Y39271D01*
X612040Y39306D01*
X612060Y39341D01*
X612090Y39376D01*
X612115Y39411D01*
X612145Y39441D01*
Y41866D01*
X612155Y41991D01*
X612195Y42116D01*
X612255Y42226D01*
X612335Y42326D01*
X612435Y42406D01*
X612545Y42466D01*
X612670Y42506D01*
X612795Y42516D01*
X612920Y42506D01*
X613045Y42466D01*
X613155Y42406D01*
X613255Y42326D01*
X613335Y42226D01*
X613395Y42116D01*
X613435Y41991D01*
X613445Y41866D01*
Y39436D01*
X613475Y39406D01*
X613575Y39266D01*
X613595Y39226D01*
X613610Y39191D01*
X613630Y39151D01*
X613645Y39111D01*
X613655Y39071D01*
X613670Y39026D01*
X613675Y38986D01*
X613685Y38946D01*
X613690Y38901D01*
Y38861D01*
X613695Y38816D01*
X613690Y38771D01*
Y38731D01*
X613685Y38686D01*
X613675Y38646D01*
X613670Y38606D01*
X613655Y38561D01*
X613645Y38521D01*
X613630Y38481D01*
X613610Y38441D01*
X613595Y38406D01*
X613575Y38366D01*
X613475Y38226D01*
X613445Y38196D01*
Y36066D01*
X613435Y35941D01*
X613395Y35816D01*
X613335Y35706D01*
X613255Y35606D01*
X613155Y35526D01*
X613045Y35466D01*
X612920Y35426D01*
X612795Y35416D01*
G37*
G36*
G01X608071D02*
X607946Y35426D01*
X607821Y35466D01*
X607711Y35526D01*
X607611Y35606D01*
X607531Y35706D01*
X607471Y35816D01*
X607431Y35941D01*
X607421Y36066D01*
Y38191D01*
X607391Y38221D01*
X607366Y38256D01*
X607336Y38291D01*
X607316Y38326D01*
X607291Y38361D01*
X607251Y38441D01*
X607206Y38561D01*
X607196Y38601D01*
X607186Y38646D01*
X607181Y38686D01*
X607171Y38731D01*
Y38901D01*
X607181Y38946D01*
X607186Y38986D01*
X607196Y39031D01*
X607206Y39071D01*
X607251Y39191D01*
X607291Y39271D01*
X607316Y39306D01*
X607336Y39341D01*
X607366Y39376D01*
X607391Y39411D01*
X607421Y39441D01*
Y41866D01*
X607431Y41991D01*
X607471Y42116D01*
X607531Y42226D01*
X607611Y42326D01*
X607711Y42406D01*
X607821Y42466D01*
X607946Y42506D01*
X608071Y42516D01*
X608196Y42506D01*
X608321Y42466D01*
X608431Y42406D01*
X608531Y42326D01*
X608611Y42226D01*
X608671Y42116D01*
X608711Y41991D01*
X608721Y41866D01*
Y39436D01*
X608751Y39406D01*
X608851Y39266D01*
X608871Y39226D01*
X608886Y39191D01*
X608906Y39151D01*
X608921Y39111D01*
X608931Y39071D01*
X608946Y39026D01*
X608951Y38986D01*
X608961Y38946D01*
X608966Y38901D01*
Y38861D01*
X608971Y38816D01*
X608966Y38771D01*
Y38731D01*
X608961Y38686D01*
X608951Y38646D01*
X608946Y38606D01*
X608931Y38561D01*
X608921Y38521D01*
X608906Y38481D01*
X608886Y38441D01*
X608871Y38406D01*
X608851Y38366D01*
X608751Y38226D01*
X608721Y38196D01*
Y36066D01*
X608711Y35941D01*
X608671Y35816D01*
X608611Y35706D01*
X608531Y35606D01*
X608431Y35526D01*
X608321Y35466D01*
X608196Y35426D01*
X608071Y35416D01*
G37*
G36*
G01X631693D02*
X631568Y35426D01*
X631443Y35466D01*
X631333Y35526D01*
X631233Y35606D01*
X631153Y35706D01*
X631093Y35816D01*
X631053Y35941D01*
X631043Y36066D01*
Y38191D01*
X631013Y38221D01*
X630988Y38256D01*
X630958Y38291D01*
X630938Y38326D01*
X630913Y38361D01*
X630873Y38441D01*
X630828Y38561D01*
X630818Y38601D01*
X630808Y38646D01*
X630803Y38686D01*
X630793Y38731D01*
Y38901D01*
X630803Y38946D01*
X630808Y38986D01*
X630818Y39031D01*
X630828Y39071D01*
X630873Y39191D01*
X630913Y39271D01*
X630938Y39306D01*
X630958Y39341D01*
X630988Y39376D01*
X631013Y39411D01*
X631043Y39441D01*
Y41866D01*
X631053Y41991D01*
X631093Y42116D01*
X631153Y42226D01*
X631233Y42326D01*
X631333Y42406D01*
X631443Y42466D01*
X631568Y42506D01*
X631693Y42516D01*
X631818Y42506D01*
X631943Y42466D01*
X632053Y42406D01*
X632153Y42326D01*
X632233Y42226D01*
X632293Y42116D01*
X632333Y41991D01*
X632343Y41866D01*
Y39436D01*
X632373Y39406D01*
X632473Y39266D01*
X632493Y39226D01*
X632508Y39191D01*
X632528Y39151D01*
X632543Y39111D01*
X632553Y39071D01*
X632568Y39026D01*
X632573Y38986D01*
X632583Y38946D01*
X632588Y38901D01*
Y38861D01*
X632593Y38816D01*
X632588Y38771D01*
Y38731D01*
X632583Y38686D01*
X632573Y38646D01*
X632568Y38606D01*
X632553Y38561D01*
X632543Y38521D01*
X632528Y38481D01*
X632508Y38441D01*
X632493Y38406D01*
X632473Y38366D01*
X632373Y38226D01*
X632343Y38196D01*
Y36066D01*
X632333Y35941D01*
X632293Y35816D01*
X632233Y35706D01*
X632153Y35606D01*
X632053Y35526D01*
X631943Y35466D01*
X631818Y35426D01*
X631693Y35416D01*
G37*
G36*
G01X626968D02*
X626843Y35426D01*
X626718Y35466D01*
X626608Y35526D01*
X626508Y35606D01*
X626428Y35706D01*
X626368Y35816D01*
X626328Y35941D01*
X626318Y36066D01*
Y38191D01*
X626288Y38221D01*
X626263Y38256D01*
X626233Y38291D01*
X626213Y38326D01*
X626188Y38361D01*
X626148Y38441D01*
X626103Y38561D01*
X626093Y38601D01*
X626083Y38646D01*
X626078Y38686D01*
X626068Y38731D01*
Y38901D01*
X626078Y38946D01*
X626083Y38986D01*
X626093Y39031D01*
X626103Y39071D01*
X626148Y39191D01*
X626188Y39271D01*
X626213Y39306D01*
X626233Y39341D01*
X626263Y39376D01*
X626288Y39411D01*
X626318Y39441D01*
Y41866D01*
X626328Y41991D01*
X626368Y42116D01*
X626428Y42226D01*
X626508Y42326D01*
X626608Y42406D01*
X626718Y42466D01*
X626843Y42506D01*
X626968Y42516D01*
X627093Y42506D01*
X627218Y42466D01*
X627328Y42406D01*
X627428Y42326D01*
X627508Y42226D01*
X627568Y42116D01*
X627608Y41991D01*
X627618Y41866D01*
Y39436D01*
X627648Y39406D01*
X627748Y39266D01*
X627768Y39226D01*
X627783Y39191D01*
X627803Y39151D01*
X627818Y39111D01*
X627828Y39071D01*
X627843Y39026D01*
X627848Y38986D01*
X627858Y38946D01*
X627863Y38901D01*
Y38861D01*
X627868Y38816D01*
X627863Y38771D01*
Y38731D01*
X627858Y38686D01*
X627848Y38646D01*
X627843Y38606D01*
X627828Y38561D01*
X627818Y38521D01*
X627803Y38481D01*
X627783Y38441D01*
X627768Y38406D01*
X627748Y38366D01*
X627648Y38226D01*
X627618Y38196D01*
Y36066D01*
X627608Y35941D01*
X627568Y35816D01*
X627508Y35706D01*
X627428Y35606D01*
X627328Y35526D01*
X627218Y35466D01*
X627093Y35426D01*
X626968Y35416D01*
G37*
G36*
G01X622244D02*
X622119Y35426D01*
X621994Y35466D01*
X621884Y35526D01*
X621784Y35606D01*
X621704Y35706D01*
X621644Y35816D01*
X621604Y35941D01*
X621594Y36066D01*
Y38191D01*
X621564Y38221D01*
X621539Y38256D01*
X621509Y38291D01*
X621489Y38326D01*
X621464Y38361D01*
X621424Y38441D01*
X621379Y38561D01*
X621369Y38601D01*
X621359Y38646D01*
X621354Y38686D01*
X621344Y38731D01*
Y38901D01*
X621354Y38946D01*
X621359Y38986D01*
X621369Y39031D01*
X621379Y39071D01*
X621424Y39191D01*
X621464Y39271D01*
X621489Y39306D01*
X621509Y39341D01*
X621539Y39376D01*
X621564Y39411D01*
X621594Y39441D01*
Y41866D01*
X621604Y41991D01*
X621644Y42116D01*
X621704Y42226D01*
X621784Y42326D01*
X621884Y42406D01*
X621994Y42466D01*
X622119Y42506D01*
X622244Y42516D01*
X622369Y42506D01*
X622494Y42466D01*
X622604Y42406D01*
X622704Y42326D01*
X622784Y42226D01*
X622844Y42116D01*
X622884Y41991D01*
X622894Y41866D01*
Y39436D01*
X622924Y39406D01*
X623024Y39266D01*
X623044Y39226D01*
X623059Y39191D01*
X623079Y39151D01*
X623094Y39111D01*
X623104Y39071D01*
X623119Y39026D01*
X623124Y38986D01*
X623134Y38946D01*
X623139Y38901D01*
Y38861D01*
X623144Y38816D01*
X623139Y38771D01*
Y38731D01*
X623134Y38686D01*
X623124Y38646D01*
X623119Y38606D01*
X623104Y38561D01*
X623094Y38521D01*
X623079Y38481D01*
X623059Y38441D01*
X623044Y38406D01*
X623024Y38366D01*
X622924Y38226D01*
X622894Y38196D01*
Y36066D01*
X622884Y35941D01*
X622844Y35816D01*
X622784Y35706D01*
X622704Y35606D01*
X622604Y35526D01*
X622494Y35466D01*
X622369Y35426D01*
X622244Y35416D01*
G37*
G36*
G01X645866D02*
X645741Y35426D01*
X645616Y35466D01*
X645506Y35526D01*
X645406Y35606D01*
X645326Y35706D01*
X645266Y35816D01*
X645226Y35941D01*
X645216Y36066D01*
Y38191D01*
X645186Y38221D01*
X645161Y38256D01*
X645131Y38291D01*
X645111Y38326D01*
X645086Y38361D01*
X645046Y38441D01*
X645001Y38561D01*
X644991Y38601D01*
X644981Y38646D01*
X644976Y38686D01*
X644966Y38731D01*
Y38901D01*
X644976Y38946D01*
X644981Y38986D01*
X644991Y39031D01*
X645001Y39071D01*
X645046Y39191D01*
X645086Y39271D01*
X645111Y39306D01*
X645131Y39341D01*
X645161Y39376D01*
X645186Y39411D01*
X645216Y39441D01*
Y41866D01*
X645226Y41991D01*
X645266Y42116D01*
X645326Y42226D01*
X645406Y42326D01*
X645506Y42406D01*
X645616Y42466D01*
X645741Y42506D01*
X645866Y42516D01*
X645991Y42506D01*
X646116Y42466D01*
X646226Y42406D01*
X646326Y42326D01*
X646406Y42226D01*
X646466Y42116D01*
X646506Y41991D01*
X646516Y41866D01*
Y39436D01*
X646546Y39406D01*
X646646Y39266D01*
X646666Y39226D01*
X646681Y39191D01*
X646701Y39151D01*
X646716Y39111D01*
X646726Y39071D01*
X646741Y39026D01*
X646746Y38986D01*
X646756Y38946D01*
X646761Y38901D01*
Y38861D01*
X646766Y38816D01*
X646761Y38771D01*
Y38731D01*
X646756Y38686D01*
X646746Y38646D01*
X646741Y38606D01*
X646726Y38561D01*
X646716Y38521D01*
X646701Y38481D01*
X646681Y38441D01*
X646666Y38406D01*
X646646Y38366D01*
X646546Y38226D01*
X646516Y38196D01*
Y36066D01*
X646506Y35941D01*
X646466Y35816D01*
X646406Y35706D01*
X646326Y35606D01*
X646226Y35526D01*
X646116Y35466D01*
X645991Y35426D01*
X645866Y35416D01*
G37*
G36*
G01X641141D02*
X641016Y35426D01*
X640891Y35466D01*
X640781Y35526D01*
X640681Y35606D01*
X640601Y35706D01*
X640541Y35816D01*
X640501Y35941D01*
X640491Y36066D01*
Y38191D01*
X640461Y38221D01*
X640436Y38256D01*
X640406Y38291D01*
X640386Y38326D01*
X640361Y38361D01*
X640321Y38441D01*
X640276Y38561D01*
X640266Y38601D01*
X640256Y38646D01*
X640251Y38686D01*
X640241Y38731D01*
Y38901D01*
X640251Y38946D01*
X640256Y38986D01*
X640266Y39031D01*
X640276Y39071D01*
X640321Y39191D01*
X640361Y39271D01*
X640386Y39306D01*
X640406Y39341D01*
X640436Y39376D01*
X640461Y39411D01*
X640491Y39441D01*
Y41866D01*
X640501Y41991D01*
X640541Y42116D01*
X640601Y42226D01*
X640681Y42326D01*
X640781Y42406D01*
X640891Y42466D01*
X641016Y42506D01*
X641141Y42516D01*
X641266Y42506D01*
X641391Y42466D01*
X641501Y42406D01*
X641601Y42326D01*
X641681Y42226D01*
X641741Y42116D01*
X641781Y41991D01*
X641791Y41866D01*
Y39436D01*
X641821Y39406D01*
X641921Y39266D01*
X641941Y39226D01*
X641956Y39191D01*
X641976Y39151D01*
X641991Y39111D01*
X642001Y39071D01*
X642016Y39026D01*
X642021Y38986D01*
X642031Y38946D01*
X642036Y38901D01*
Y38861D01*
X642041Y38816D01*
X642036Y38771D01*
Y38731D01*
X642031Y38686D01*
X642021Y38646D01*
X642016Y38606D01*
X642001Y38561D01*
X641991Y38521D01*
X641976Y38481D01*
X641956Y38441D01*
X641941Y38406D01*
X641921Y38366D01*
X641821Y38226D01*
X641791Y38196D01*
Y36066D01*
X641781Y35941D01*
X641741Y35816D01*
X641681Y35706D01*
X641601Y35606D01*
X641501Y35526D01*
X641391Y35466D01*
X641266Y35426D01*
X641141Y35416D01*
G37*
G36*
G01X636417D02*
X636292Y35426D01*
X636167Y35466D01*
X636057Y35526D01*
X635957Y35606D01*
X635877Y35706D01*
X635817Y35816D01*
X635777Y35941D01*
X635767Y36066D01*
Y38191D01*
X635737Y38221D01*
X635712Y38256D01*
X635682Y38291D01*
X635662Y38326D01*
X635637Y38361D01*
X635597Y38441D01*
X635552Y38561D01*
X635542Y38601D01*
X635532Y38646D01*
X635527Y38686D01*
X635517Y38731D01*
Y38901D01*
X635527Y38946D01*
X635532Y38986D01*
X635542Y39031D01*
X635552Y39071D01*
X635597Y39191D01*
X635637Y39271D01*
X635662Y39306D01*
X635682Y39341D01*
X635712Y39376D01*
X635737Y39411D01*
X635767Y39441D01*
Y41866D01*
X635777Y41991D01*
X635817Y42116D01*
X635877Y42226D01*
X635957Y42326D01*
X636057Y42406D01*
X636167Y42466D01*
X636292Y42506D01*
X636417Y42516D01*
X636542Y42506D01*
X636667Y42466D01*
X636777Y42406D01*
X636877Y42326D01*
X636957Y42226D01*
X637017Y42116D01*
X637057Y41991D01*
X637067Y41866D01*
Y39436D01*
X637097Y39406D01*
X637197Y39266D01*
X637217Y39226D01*
X637232Y39191D01*
X637252Y39151D01*
X637267Y39111D01*
X637277Y39071D01*
X637292Y39026D01*
X637297Y38986D01*
X637307Y38946D01*
X637312Y38901D01*
Y38861D01*
X637317Y38816D01*
X637312Y38771D01*
Y38731D01*
X637307Y38686D01*
X637297Y38646D01*
X637292Y38606D01*
X637277Y38561D01*
X637267Y38521D01*
X637252Y38481D01*
X637232Y38441D01*
X637217Y38406D01*
X637197Y38366D01*
X637097Y38226D01*
X637067Y38196D01*
Y36066D01*
X637057Y35941D01*
X637017Y35816D01*
X636957Y35706D01*
X636877Y35606D01*
X636777Y35526D01*
X636667Y35466D01*
X636542Y35426D01*
X636417Y35416D01*
G37*
G36*
G01X664764D02*
X664639Y35426D01*
X664514Y35466D01*
X664404Y35526D01*
X664304Y35606D01*
X664224Y35706D01*
X664164Y35816D01*
X664124Y35941D01*
X664114Y36066D01*
Y38191D01*
X664084Y38221D01*
X664059Y38256D01*
X664029Y38291D01*
X664009Y38326D01*
X663984Y38361D01*
X663944Y38441D01*
X663899Y38561D01*
X663889Y38601D01*
X663879Y38646D01*
X663874Y38686D01*
X663864Y38731D01*
Y38901D01*
X663874Y38946D01*
X663879Y38986D01*
X663889Y39031D01*
X663899Y39071D01*
X663944Y39191D01*
X663984Y39271D01*
X664009Y39306D01*
X664029Y39341D01*
X664059Y39376D01*
X664084Y39411D01*
X664114Y39441D01*
Y41866D01*
X664124Y41991D01*
X664164Y42116D01*
X664224Y42226D01*
X664304Y42326D01*
X664404Y42406D01*
X664514Y42466D01*
X664639Y42506D01*
X664764Y42516D01*
X664889Y42506D01*
X665014Y42466D01*
X665124Y42406D01*
X665224Y42326D01*
X665304Y42226D01*
X665364Y42116D01*
X665404Y41991D01*
X665414Y41866D01*
Y39436D01*
X665444Y39406D01*
X665544Y39266D01*
X665564Y39226D01*
X665579Y39191D01*
X665599Y39151D01*
X665614Y39111D01*
X665624Y39071D01*
X665639Y39026D01*
X665644Y38986D01*
X665654Y38946D01*
X665659Y38901D01*
Y38861D01*
X665664Y38816D01*
X665659Y38771D01*
Y38731D01*
X665654Y38686D01*
X665644Y38646D01*
X665639Y38606D01*
X665624Y38561D01*
X665614Y38521D01*
X665599Y38481D01*
X665579Y38441D01*
X665564Y38406D01*
X665544Y38366D01*
X665444Y38226D01*
X665414Y38196D01*
Y36066D01*
X665404Y35941D01*
X665364Y35816D01*
X665304Y35706D01*
X665224Y35606D01*
X665124Y35526D01*
X665014Y35466D01*
X664889Y35426D01*
X664764Y35416D01*
G37*
G36*
G01X660039D02*
X659914Y35426D01*
X659789Y35466D01*
X659679Y35526D01*
X659579Y35606D01*
X659499Y35706D01*
X659439Y35816D01*
X659399Y35941D01*
X659389Y36066D01*
Y38191D01*
X659359Y38221D01*
X659334Y38256D01*
X659304Y38291D01*
X659284Y38326D01*
X659259Y38361D01*
X659219Y38441D01*
X659174Y38561D01*
X659164Y38601D01*
X659154Y38646D01*
X659149Y38686D01*
X659139Y38731D01*
Y38901D01*
X659149Y38946D01*
X659154Y38986D01*
X659164Y39031D01*
X659174Y39071D01*
X659219Y39191D01*
X659259Y39271D01*
X659284Y39306D01*
X659304Y39341D01*
X659334Y39376D01*
X659359Y39411D01*
X659389Y39441D01*
Y41866D01*
X659399Y41991D01*
X659439Y42116D01*
X659499Y42226D01*
X659579Y42326D01*
X659679Y42406D01*
X659789Y42466D01*
X659914Y42506D01*
X660039Y42516D01*
X660164Y42506D01*
X660289Y42466D01*
X660399Y42406D01*
X660499Y42326D01*
X660579Y42226D01*
X660639Y42116D01*
X660679Y41991D01*
X660689Y41866D01*
Y39436D01*
X660719Y39406D01*
X660819Y39266D01*
X660839Y39226D01*
X660854Y39191D01*
X660874Y39151D01*
X660889Y39111D01*
X660899Y39071D01*
X660914Y39026D01*
X660919Y38986D01*
X660929Y38946D01*
X660934Y38901D01*
Y38861D01*
X660939Y38816D01*
X660934Y38771D01*
Y38731D01*
X660929Y38686D01*
X660919Y38646D01*
X660914Y38606D01*
X660899Y38561D01*
X660889Y38521D01*
X660874Y38481D01*
X660854Y38441D01*
X660839Y38406D01*
X660819Y38366D01*
X660719Y38226D01*
X660689Y38196D01*
Y36066D01*
X660679Y35941D01*
X660639Y35816D01*
X660579Y35706D01*
X660499Y35606D01*
X660399Y35526D01*
X660289Y35466D01*
X660164Y35426D01*
X660039Y35416D01*
G37*
G36*
G01X655315D02*
X655190Y35426D01*
X655065Y35466D01*
X654955Y35526D01*
X654855Y35606D01*
X654775Y35706D01*
X654715Y35816D01*
X654675Y35941D01*
X654665Y36066D01*
Y38191D01*
X654635Y38221D01*
X654610Y38256D01*
X654580Y38291D01*
X654560Y38326D01*
X654535Y38361D01*
X654495Y38441D01*
X654450Y38561D01*
X654440Y38601D01*
X654430Y38646D01*
X654425Y38686D01*
X654415Y38731D01*
Y38901D01*
X654425Y38946D01*
X654430Y38986D01*
X654440Y39031D01*
X654450Y39071D01*
X654495Y39191D01*
X654535Y39271D01*
X654560Y39306D01*
X654580Y39341D01*
X654610Y39376D01*
X654635Y39411D01*
X654665Y39441D01*
Y41866D01*
X654675Y41991D01*
X654715Y42116D01*
X654775Y42226D01*
X654855Y42326D01*
X654955Y42406D01*
X655065Y42466D01*
X655190Y42506D01*
X655315Y42516D01*
X655440Y42506D01*
X655565Y42466D01*
X655675Y42406D01*
X655775Y42326D01*
X655855Y42226D01*
X655915Y42116D01*
X655955Y41991D01*
X655965Y41866D01*
Y39436D01*
X655995Y39406D01*
X656095Y39266D01*
X656115Y39226D01*
X656130Y39191D01*
X656150Y39151D01*
X656165Y39111D01*
X656175Y39071D01*
X656190Y39026D01*
X656195Y38986D01*
X656205Y38946D01*
X656210Y38901D01*
Y38861D01*
X656215Y38816D01*
X656210Y38771D01*
Y38731D01*
X656205Y38686D01*
X656195Y38646D01*
X656190Y38606D01*
X656175Y38561D01*
X656165Y38521D01*
X656150Y38481D01*
X656130Y38441D01*
X656115Y38406D01*
X656095Y38366D01*
X655995Y38226D01*
X655965Y38196D01*
Y36066D01*
X655955Y35941D01*
X655915Y35816D01*
X655855Y35706D01*
X655775Y35606D01*
X655675Y35526D01*
X655565Y35466D01*
X655440Y35426D01*
X655315Y35416D01*
G37*
G36*
G01X650590D02*
X650465Y35426D01*
X650340Y35466D01*
X650230Y35526D01*
X650130Y35606D01*
X650050Y35706D01*
X649990Y35816D01*
X649950Y35941D01*
X649940Y36066D01*
Y38191D01*
X649910Y38221D01*
X649885Y38256D01*
X649855Y38291D01*
X649835Y38326D01*
X649810Y38361D01*
X649770Y38441D01*
X649725Y38561D01*
X649715Y38601D01*
X649705Y38646D01*
X649700Y38686D01*
X649690Y38731D01*
Y38901D01*
X649700Y38946D01*
X649705Y38986D01*
X649715Y39031D01*
X649725Y39071D01*
X649770Y39191D01*
X649810Y39271D01*
X649835Y39306D01*
X649855Y39341D01*
X649885Y39376D01*
X649910Y39411D01*
X649940Y39441D01*
Y41866D01*
X649950Y41991D01*
X649990Y42116D01*
X650050Y42226D01*
X650130Y42326D01*
X650230Y42406D01*
X650340Y42466D01*
X650465Y42506D01*
X650590Y42516D01*
X650715Y42506D01*
X650840Y42466D01*
X650950Y42406D01*
X651050Y42326D01*
X651130Y42226D01*
X651190Y42116D01*
X651230Y41991D01*
X651240Y41866D01*
Y39436D01*
X651270Y39406D01*
X651370Y39266D01*
X651390Y39226D01*
X651405Y39191D01*
X651425Y39151D01*
X651440Y39111D01*
X651450Y39071D01*
X651465Y39026D01*
X651470Y38986D01*
X651480Y38946D01*
X651485Y38901D01*
Y38861D01*
X651490Y38816D01*
X651485Y38771D01*
Y38731D01*
X651480Y38686D01*
X651470Y38646D01*
X651465Y38606D01*
X651450Y38561D01*
X651440Y38521D01*
X651425Y38481D01*
X651405Y38441D01*
X651390Y38406D01*
X651370Y38366D01*
X651270Y38226D01*
X651240Y38196D01*
Y36066D01*
X651230Y35941D01*
X651190Y35816D01*
X651130Y35706D01*
X651050Y35606D01*
X650950Y35526D01*
X650840Y35466D01*
X650715Y35426D01*
X650590Y35416D01*
G37*
G36*
G01X678937D02*
X678812Y35426D01*
X678687Y35466D01*
X678577Y35526D01*
X678477Y35606D01*
X678397Y35706D01*
X678337Y35816D01*
X678297Y35941D01*
X678287Y36066D01*
Y38191D01*
X678257Y38221D01*
X678232Y38256D01*
X678202Y38291D01*
X678182Y38326D01*
X678157Y38361D01*
X678117Y38441D01*
X678072Y38561D01*
X678062Y38601D01*
X678052Y38646D01*
X678047Y38686D01*
X678037Y38731D01*
Y38901D01*
X678047Y38946D01*
X678052Y38986D01*
X678062Y39031D01*
X678072Y39071D01*
X678117Y39191D01*
X678157Y39271D01*
X678182Y39306D01*
X678202Y39341D01*
X678232Y39376D01*
X678257Y39411D01*
X678287Y39441D01*
Y41866D01*
X678297Y41991D01*
X678337Y42116D01*
X678397Y42226D01*
X678477Y42326D01*
X678577Y42406D01*
X678687Y42466D01*
X678812Y42506D01*
X678937Y42516D01*
X679062Y42506D01*
X679187Y42466D01*
X679297Y42406D01*
X679397Y42326D01*
X679477Y42226D01*
X679537Y42116D01*
X679577Y41991D01*
X679587Y41866D01*
Y39436D01*
X679617Y39406D01*
X679717Y39266D01*
X679737Y39226D01*
X679752Y39191D01*
X679772Y39151D01*
X679787Y39111D01*
X679797Y39071D01*
X679812Y39026D01*
X679817Y38986D01*
X679827Y38946D01*
X679832Y38901D01*
Y38861D01*
X679837Y38816D01*
X679832Y38771D01*
Y38731D01*
X679827Y38686D01*
X679817Y38646D01*
X679812Y38606D01*
X679797Y38561D01*
X679787Y38521D01*
X679772Y38481D01*
X679752Y38441D01*
X679737Y38406D01*
X679717Y38366D01*
X679617Y38226D01*
X679587Y38196D01*
Y36066D01*
X679577Y35941D01*
X679537Y35816D01*
X679477Y35706D01*
X679397Y35606D01*
X679297Y35526D01*
X679187Y35466D01*
X679062Y35426D01*
X678937Y35416D01*
G37*
G36*
G01X674212D02*
X674087Y35426D01*
X673962Y35466D01*
X673852Y35526D01*
X673752Y35606D01*
X673672Y35706D01*
X673612Y35816D01*
X673572Y35941D01*
X673562Y36066D01*
Y38191D01*
X673532Y38221D01*
X673507Y38256D01*
X673477Y38291D01*
X673457Y38326D01*
X673432Y38361D01*
X673392Y38441D01*
X673347Y38561D01*
X673337Y38601D01*
X673327Y38646D01*
X673322Y38686D01*
X673312Y38731D01*
Y38901D01*
X673322Y38946D01*
X673327Y38986D01*
X673337Y39031D01*
X673347Y39071D01*
X673392Y39191D01*
X673432Y39271D01*
X673457Y39306D01*
X673477Y39341D01*
X673507Y39376D01*
X673532Y39411D01*
X673562Y39441D01*
Y41866D01*
X673572Y41991D01*
X673612Y42116D01*
X673672Y42226D01*
X673752Y42326D01*
X673852Y42406D01*
X673962Y42466D01*
X674087Y42506D01*
X674212Y42516D01*
X674337Y42506D01*
X674462Y42466D01*
X674572Y42406D01*
X674672Y42326D01*
X674752Y42226D01*
X674812Y42116D01*
X674852Y41991D01*
X674862Y41866D01*
Y39436D01*
X674892Y39406D01*
X674992Y39266D01*
X675012Y39226D01*
X675027Y39191D01*
X675047Y39151D01*
X675062Y39111D01*
X675072Y39071D01*
X675087Y39026D01*
X675092Y38986D01*
X675102Y38946D01*
X675107Y38901D01*
Y38861D01*
X675112Y38816D01*
X675107Y38771D01*
Y38731D01*
X675102Y38686D01*
X675092Y38646D01*
X675087Y38606D01*
X675072Y38561D01*
X675062Y38521D01*
X675047Y38481D01*
X675027Y38441D01*
X675012Y38406D01*
X674992Y38366D01*
X674892Y38226D01*
X674862Y38196D01*
Y36066D01*
X674852Y35941D01*
X674812Y35816D01*
X674752Y35706D01*
X674672Y35606D01*
X674572Y35526D01*
X674462Y35466D01*
X674337Y35426D01*
X674212Y35416D01*
G37*
G36*
G01X669488D02*
X669363Y35426D01*
X669238Y35466D01*
X669128Y35526D01*
X669028Y35606D01*
X668948Y35706D01*
X668888Y35816D01*
X668848Y35941D01*
X668838Y36066D01*
Y38191D01*
X668808Y38221D01*
X668783Y38256D01*
X668753Y38291D01*
X668733Y38326D01*
X668708Y38361D01*
X668668Y38441D01*
X668623Y38561D01*
X668613Y38601D01*
X668603Y38646D01*
X668598Y38686D01*
X668588Y38731D01*
Y38901D01*
X668598Y38946D01*
X668603Y38986D01*
X668613Y39031D01*
X668623Y39071D01*
X668668Y39191D01*
X668708Y39271D01*
X668733Y39306D01*
X668753Y39341D01*
X668783Y39376D01*
X668808Y39411D01*
X668838Y39441D01*
Y41866D01*
X668848Y41991D01*
X668888Y42116D01*
X668948Y42226D01*
X669028Y42326D01*
X669128Y42406D01*
X669238Y42466D01*
X669363Y42506D01*
X669488Y42516D01*
X669613Y42506D01*
X669738Y42466D01*
X669848Y42406D01*
X669948Y42326D01*
X670028Y42226D01*
X670088Y42116D01*
X670128Y41991D01*
X670138Y41866D01*
Y39436D01*
X670168Y39406D01*
X670268Y39266D01*
X670288Y39226D01*
X670303Y39191D01*
X670323Y39151D01*
X670338Y39111D01*
X670348Y39071D01*
X670363Y39026D01*
X670368Y38986D01*
X670378Y38946D01*
X670383Y38901D01*
Y38861D01*
X670388Y38816D01*
X670383Y38771D01*
Y38731D01*
X670378Y38686D01*
X670368Y38646D01*
X670363Y38606D01*
X670348Y38561D01*
X670338Y38521D01*
X670323Y38481D01*
X670303Y38441D01*
X670288Y38406D01*
X670268Y38366D01*
X670168Y38226D01*
X670138Y38196D01*
Y36066D01*
X670128Y35941D01*
X670088Y35816D01*
X670028Y35706D01*
X669948Y35606D01*
X669848Y35526D01*
X669738Y35466D01*
X669613Y35426D01*
X669488Y35416D01*
G37*
G36*
G01X693110D02*
X692985Y35426D01*
X692860Y35466D01*
X692750Y35526D01*
X692650Y35606D01*
X692570Y35706D01*
X692510Y35816D01*
X692470Y35941D01*
X692460Y36066D01*
Y38191D01*
X692430Y38221D01*
X692405Y38256D01*
X692375Y38291D01*
X692355Y38326D01*
X692330Y38361D01*
X692290Y38441D01*
X692245Y38561D01*
X692235Y38601D01*
X692225Y38646D01*
X692220Y38686D01*
X692210Y38731D01*
Y38901D01*
X692220Y38946D01*
X692225Y38986D01*
X692235Y39031D01*
X692245Y39071D01*
X692290Y39191D01*
X692330Y39271D01*
X692355Y39306D01*
X692375Y39341D01*
X692405Y39376D01*
X692430Y39411D01*
X692460Y39441D01*
Y41866D01*
X692470Y41991D01*
X692510Y42116D01*
X692570Y42226D01*
X692650Y42326D01*
X692750Y42406D01*
X692860Y42466D01*
X692985Y42506D01*
X693110Y42516D01*
X693235Y42506D01*
X693360Y42466D01*
X693470Y42406D01*
X693570Y42326D01*
X693650Y42226D01*
X693710Y42116D01*
X693750Y41991D01*
X693760Y41866D01*
Y39436D01*
X693790Y39406D01*
X693890Y39266D01*
X693910Y39226D01*
X693925Y39191D01*
X693945Y39151D01*
X693960Y39111D01*
X693970Y39071D01*
X693985Y39026D01*
X693990Y38986D01*
X694000Y38946D01*
X694005Y38901D01*
Y38861D01*
X694010Y38816D01*
X694005Y38771D01*
Y38731D01*
X694000Y38686D01*
X693990Y38646D01*
X693985Y38606D01*
X693970Y38561D01*
X693960Y38521D01*
X693945Y38481D01*
X693925Y38441D01*
X693910Y38406D01*
X693890Y38366D01*
X693790Y38226D01*
X693760Y38196D01*
Y36066D01*
X693750Y35941D01*
X693710Y35816D01*
X693650Y35706D01*
X693570Y35606D01*
X693470Y35526D01*
X693360Y35466D01*
X693235Y35426D01*
X693110Y35416D01*
G37*
G36*
G01X688386D02*
X688261Y35426D01*
X688136Y35466D01*
X688026Y35526D01*
X687926Y35606D01*
X687846Y35706D01*
X687786Y35816D01*
X687746Y35941D01*
X687736Y36066D01*
Y38191D01*
X687706Y38221D01*
X687681Y38256D01*
X687651Y38291D01*
X687631Y38326D01*
X687606Y38361D01*
X687566Y38441D01*
X687521Y38561D01*
X687511Y38601D01*
X687501Y38646D01*
X687496Y38686D01*
X687486Y38731D01*
Y38901D01*
X687496Y38946D01*
X687501Y38986D01*
X687511Y39031D01*
X687521Y39071D01*
X687566Y39191D01*
X687606Y39271D01*
X687631Y39306D01*
X687651Y39341D01*
X687681Y39376D01*
X687706Y39411D01*
X687736Y39441D01*
Y41866D01*
X687746Y41991D01*
X687786Y42116D01*
X687846Y42226D01*
X687926Y42326D01*
X688026Y42406D01*
X688136Y42466D01*
X688261Y42506D01*
X688386Y42516D01*
X688511Y42506D01*
X688636Y42466D01*
X688746Y42406D01*
X688846Y42326D01*
X688926Y42226D01*
X688986Y42116D01*
X689026Y41991D01*
X689036Y41866D01*
Y39436D01*
X689066Y39406D01*
X689166Y39266D01*
X689186Y39226D01*
X689201Y39191D01*
X689221Y39151D01*
X689236Y39111D01*
X689246Y39071D01*
X689261Y39026D01*
X689266Y38986D01*
X689276Y38946D01*
X689281Y38901D01*
Y38861D01*
X689286Y38816D01*
X689281Y38771D01*
Y38731D01*
X689276Y38686D01*
X689266Y38646D01*
X689261Y38606D01*
X689246Y38561D01*
X689236Y38521D01*
X689221Y38481D01*
X689201Y38441D01*
X689186Y38406D01*
X689166Y38366D01*
X689066Y38226D01*
X689036Y38196D01*
Y36066D01*
X689026Y35941D01*
X688986Y35816D01*
X688926Y35706D01*
X688846Y35606D01*
X688746Y35526D01*
X688636Y35466D01*
X688511Y35426D01*
X688386Y35416D01*
G37*
G36*
G01X683661D02*
X683536Y35426D01*
X683411Y35466D01*
X683301Y35526D01*
X683201Y35606D01*
X683121Y35706D01*
X683061Y35816D01*
X683021Y35941D01*
X683011Y36066D01*
Y38191D01*
X682981Y38221D01*
X682956Y38256D01*
X682926Y38291D01*
X682906Y38326D01*
X682881Y38361D01*
X682841Y38441D01*
X682796Y38561D01*
X682786Y38601D01*
X682776Y38646D01*
X682771Y38686D01*
X682761Y38731D01*
Y38901D01*
X682771Y38946D01*
X682776Y38986D01*
X682786Y39031D01*
X682796Y39071D01*
X682841Y39191D01*
X682881Y39271D01*
X682906Y39306D01*
X682926Y39341D01*
X682956Y39376D01*
X682981Y39411D01*
X683011Y39441D01*
Y41866D01*
X683021Y41991D01*
X683061Y42116D01*
X683121Y42226D01*
X683201Y42326D01*
X683301Y42406D01*
X683411Y42466D01*
X683536Y42506D01*
X683661Y42516D01*
X683786Y42506D01*
X683911Y42466D01*
X684021Y42406D01*
X684121Y42326D01*
X684201Y42226D01*
X684261Y42116D01*
X684301Y41991D01*
X684311Y41866D01*
Y39436D01*
X684341Y39406D01*
X684441Y39266D01*
X684461Y39226D01*
X684476Y39191D01*
X684496Y39151D01*
X684511Y39111D01*
X684521Y39071D01*
X684536Y39026D01*
X684541Y38986D01*
X684551Y38946D01*
X684556Y38901D01*
Y38861D01*
X684561Y38816D01*
X684556Y38771D01*
Y38731D01*
X684551Y38686D01*
X684541Y38646D01*
X684536Y38606D01*
X684521Y38561D01*
X684511Y38521D01*
X684496Y38481D01*
X684476Y38441D01*
X684461Y38406D01*
X684441Y38366D01*
X684341Y38226D01*
X684311Y38196D01*
Y36066D01*
X684301Y35941D01*
X684261Y35816D01*
X684201Y35706D01*
X684121Y35606D01*
X684021Y35526D01*
X683911Y35466D01*
X683786Y35426D01*
X683661Y35416D01*
G37*
G36*
G01X707283D02*
X707158Y35426D01*
X707033Y35466D01*
X706923Y35526D01*
X706823Y35606D01*
X706743Y35706D01*
X706683Y35816D01*
X706643Y35941D01*
X706633Y36066D01*
Y38191D01*
X706603Y38221D01*
X706578Y38256D01*
X706548Y38291D01*
X706528Y38326D01*
X706503Y38361D01*
X706463Y38441D01*
X706418Y38561D01*
X706408Y38601D01*
X706398Y38646D01*
X706393Y38686D01*
X706383Y38731D01*
Y38901D01*
X706393Y38946D01*
X706398Y38986D01*
X706408Y39031D01*
X706418Y39071D01*
X706463Y39191D01*
X706503Y39271D01*
X706528Y39306D01*
X706548Y39341D01*
X706578Y39376D01*
X706603Y39411D01*
X706633Y39441D01*
Y41866D01*
X706643Y41991D01*
X706683Y42116D01*
X706743Y42226D01*
X706823Y42326D01*
X706923Y42406D01*
X707033Y42466D01*
X707158Y42506D01*
X707283Y42516D01*
X707408Y42506D01*
X707533Y42466D01*
X707643Y42406D01*
X707743Y42326D01*
X707823Y42226D01*
X707883Y42116D01*
X707923Y41991D01*
X707933Y41866D01*
Y39436D01*
X707963Y39406D01*
X708063Y39266D01*
X708083Y39226D01*
X708098Y39191D01*
X708118Y39151D01*
X708133Y39111D01*
X708143Y39071D01*
X708158Y39026D01*
X708163Y38986D01*
X708173Y38946D01*
X708178Y38901D01*
Y38861D01*
X708183Y38816D01*
X708178Y38771D01*
Y38731D01*
X708173Y38686D01*
X708163Y38646D01*
X708158Y38606D01*
X708143Y38561D01*
X708133Y38521D01*
X708118Y38481D01*
X708098Y38441D01*
X708083Y38406D01*
X708063Y38366D01*
X707963Y38226D01*
X707933Y38196D01*
Y36066D01*
X707923Y35941D01*
X707883Y35816D01*
X707823Y35706D01*
X707743Y35606D01*
X707643Y35526D01*
X707533Y35466D01*
X707408Y35426D01*
X707283Y35416D01*
G37*
G36*
G01X702559D02*
X702434Y35426D01*
X702309Y35466D01*
X702199Y35526D01*
X702099Y35606D01*
X702019Y35706D01*
X701959Y35816D01*
X701919Y35941D01*
X701909Y36066D01*
Y38191D01*
X701879Y38221D01*
X701854Y38256D01*
X701824Y38291D01*
X701804Y38326D01*
X701779Y38361D01*
X701739Y38441D01*
X701694Y38561D01*
X701684Y38601D01*
X701674Y38646D01*
X701669Y38686D01*
X701659Y38731D01*
Y38901D01*
X701669Y38946D01*
X701674Y38986D01*
X701684Y39031D01*
X701694Y39071D01*
X701739Y39191D01*
X701779Y39271D01*
X701804Y39306D01*
X701824Y39341D01*
X701854Y39376D01*
X701879Y39411D01*
X701909Y39441D01*
Y41866D01*
X701919Y41991D01*
X701959Y42116D01*
X702019Y42226D01*
X702099Y42326D01*
X702199Y42406D01*
X702309Y42466D01*
X702434Y42506D01*
X702559Y42516D01*
X702684Y42506D01*
X702809Y42466D01*
X702919Y42406D01*
X703019Y42326D01*
X703099Y42226D01*
X703159Y42116D01*
X703199Y41991D01*
X703209Y41866D01*
Y39436D01*
X703239Y39406D01*
X703339Y39266D01*
X703359Y39226D01*
X703374Y39191D01*
X703394Y39151D01*
X703409Y39111D01*
X703419Y39071D01*
X703434Y39026D01*
X703439Y38986D01*
X703449Y38946D01*
X703454Y38901D01*
Y38861D01*
X703459Y38816D01*
X703454Y38771D01*
Y38731D01*
X703449Y38686D01*
X703439Y38646D01*
X703434Y38606D01*
X703419Y38561D01*
X703409Y38521D01*
X703394Y38481D01*
X703374Y38441D01*
X703359Y38406D01*
X703339Y38366D01*
X703239Y38226D01*
X703209Y38196D01*
Y36066D01*
X703199Y35941D01*
X703159Y35816D01*
X703099Y35706D01*
X703019Y35606D01*
X702919Y35526D01*
X702809Y35466D01*
X702684Y35426D01*
X702559Y35416D01*
G37*
G36*
G01X697834D02*
X697709Y35426D01*
X697584Y35466D01*
X697474Y35526D01*
X697374Y35606D01*
X697294Y35706D01*
X697234Y35816D01*
X697194Y35941D01*
X697184Y36066D01*
Y38191D01*
X697154Y38221D01*
X697129Y38256D01*
X697099Y38291D01*
X697079Y38326D01*
X697054Y38361D01*
X697014Y38441D01*
X696969Y38561D01*
X696959Y38601D01*
X696949Y38646D01*
X696944Y38686D01*
X696934Y38731D01*
Y38901D01*
X696944Y38946D01*
X696949Y38986D01*
X696959Y39031D01*
X696969Y39071D01*
X697014Y39191D01*
X697054Y39271D01*
X697079Y39306D01*
X697099Y39341D01*
X697129Y39376D01*
X697154Y39411D01*
X697184Y39441D01*
Y41866D01*
X697194Y41991D01*
X697234Y42116D01*
X697294Y42226D01*
X697374Y42326D01*
X697474Y42406D01*
X697584Y42466D01*
X697709Y42506D01*
X697834Y42516D01*
X697959Y42506D01*
X698084Y42466D01*
X698194Y42406D01*
X698294Y42326D01*
X698374Y42226D01*
X698434Y42116D01*
X698474Y41991D01*
X698484Y41866D01*
Y39436D01*
X698514Y39406D01*
X698614Y39266D01*
X698634Y39226D01*
X698649Y39191D01*
X698669Y39151D01*
X698684Y39111D01*
X698694Y39071D01*
X698709Y39026D01*
X698714Y38986D01*
X698724Y38946D01*
X698729Y38901D01*
Y38861D01*
X698734Y38816D01*
X698729Y38771D01*
Y38731D01*
X698724Y38686D01*
X698714Y38646D01*
X698709Y38606D01*
X698694Y38561D01*
X698684Y38521D01*
X698669Y38481D01*
X698649Y38441D01*
X698634Y38406D01*
X698614Y38366D01*
X698514Y38226D01*
X698484Y38196D01*
Y36066D01*
X698474Y35941D01*
X698434Y35816D01*
X698374Y35706D01*
X698294Y35606D01*
X698194Y35526D01*
X698084Y35466D01*
X697959Y35426D01*
X697834Y35416D01*
G37*
G36*
G01X726181D02*
X726056Y35426D01*
X725931Y35466D01*
X725821Y35526D01*
X725721Y35606D01*
X725641Y35706D01*
X725581Y35816D01*
X725541Y35941D01*
X725531Y36066D01*
Y38191D01*
X725501Y38221D01*
X725476Y38256D01*
X725446Y38291D01*
X725426Y38326D01*
X725401Y38361D01*
X725361Y38441D01*
X725316Y38561D01*
X725306Y38601D01*
X725296Y38646D01*
X725291Y38686D01*
X725281Y38731D01*
Y38901D01*
X725291Y38946D01*
X725296Y38986D01*
X725306Y39031D01*
X725316Y39071D01*
X725361Y39191D01*
X725401Y39271D01*
X725426Y39306D01*
X725446Y39341D01*
X725476Y39376D01*
X725501Y39411D01*
X725531Y39441D01*
Y41866D01*
X725541Y41991D01*
X725581Y42116D01*
X725641Y42226D01*
X725721Y42326D01*
X725821Y42406D01*
X725931Y42466D01*
X726056Y42506D01*
X726181Y42516D01*
X726306Y42506D01*
X726431Y42466D01*
X726541Y42406D01*
X726641Y42326D01*
X726721Y42226D01*
X726781Y42116D01*
X726821Y41991D01*
X726831Y41866D01*
Y39436D01*
X726861Y39406D01*
X726961Y39266D01*
X726981Y39226D01*
X726996Y39191D01*
X727016Y39151D01*
X727031Y39111D01*
X727041Y39071D01*
X727056Y39026D01*
X727061Y38986D01*
X727071Y38946D01*
X727076Y38901D01*
Y38861D01*
X727081Y38816D01*
X727076Y38771D01*
Y38731D01*
X727071Y38686D01*
X727061Y38646D01*
X727056Y38606D01*
X727041Y38561D01*
X727031Y38521D01*
X727016Y38481D01*
X726996Y38441D01*
X726981Y38406D01*
X726961Y38366D01*
X726861Y38226D01*
X726831Y38196D01*
Y36066D01*
X726821Y35941D01*
X726781Y35816D01*
X726721Y35706D01*
X726641Y35606D01*
X726541Y35526D01*
X726431Y35466D01*
X726306Y35426D01*
X726181Y35416D01*
G37*
G36*
G01X721456D02*
X721331Y35426D01*
X721206Y35466D01*
X721096Y35526D01*
X720996Y35606D01*
X720916Y35706D01*
X720856Y35816D01*
X720816Y35941D01*
X720806Y36066D01*
Y38191D01*
X720776Y38221D01*
X720751Y38256D01*
X720721Y38291D01*
X720701Y38326D01*
X720676Y38361D01*
X720636Y38441D01*
X720591Y38561D01*
X720581Y38601D01*
X720571Y38646D01*
X720566Y38686D01*
X720556Y38731D01*
Y38901D01*
X720566Y38946D01*
X720571Y38986D01*
X720581Y39031D01*
X720591Y39071D01*
X720636Y39191D01*
X720676Y39271D01*
X720701Y39306D01*
X720721Y39341D01*
X720751Y39376D01*
X720776Y39411D01*
X720806Y39441D01*
Y41866D01*
X720816Y41991D01*
X720856Y42116D01*
X720916Y42226D01*
X720996Y42326D01*
X721096Y42406D01*
X721206Y42466D01*
X721331Y42506D01*
X721456Y42516D01*
X721581Y42506D01*
X721706Y42466D01*
X721816Y42406D01*
X721916Y42326D01*
X721996Y42226D01*
X722056Y42116D01*
X722096Y41991D01*
X722106Y41866D01*
Y39436D01*
X722136Y39406D01*
X722236Y39266D01*
X722256Y39226D01*
X722271Y39191D01*
X722291Y39151D01*
X722306Y39111D01*
X722316Y39071D01*
X722331Y39026D01*
X722336Y38986D01*
X722346Y38946D01*
X722351Y38901D01*
Y38861D01*
X722356Y38816D01*
X722351Y38771D01*
Y38731D01*
X722346Y38686D01*
X722336Y38646D01*
X722331Y38606D01*
X722316Y38561D01*
X722306Y38521D01*
X722291Y38481D01*
X722271Y38441D01*
X722256Y38406D01*
X722236Y38366D01*
X722136Y38226D01*
X722106Y38196D01*
Y36066D01*
X722096Y35941D01*
X722056Y35816D01*
X721996Y35706D01*
X721916Y35606D01*
X721816Y35526D01*
X721706Y35466D01*
X721581Y35426D01*
X721456Y35416D01*
G37*
G36*
G01X716732D02*
X716607Y35426D01*
X716482Y35466D01*
X716372Y35526D01*
X716272Y35606D01*
X716192Y35706D01*
X716132Y35816D01*
X716092Y35941D01*
X716082Y36066D01*
Y38191D01*
X716052Y38221D01*
X716027Y38256D01*
X715997Y38291D01*
X715977Y38326D01*
X715952Y38361D01*
X715912Y38441D01*
X715867Y38561D01*
X715857Y38601D01*
X715847Y38646D01*
X715842Y38686D01*
X715832Y38731D01*
Y38901D01*
X715842Y38946D01*
X715847Y38986D01*
X715857Y39031D01*
X715867Y39071D01*
X715912Y39191D01*
X715952Y39271D01*
X715977Y39306D01*
X715997Y39341D01*
X716027Y39376D01*
X716052Y39411D01*
X716082Y39441D01*
Y41866D01*
X716092Y41991D01*
X716132Y42116D01*
X716192Y42226D01*
X716272Y42326D01*
X716372Y42406D01*
X716482Y42466D01*
X716607Y42506D01*
X716732Y42516D01*
X716857Y42506D01*
X716982Y42466D01*
X717092Y42406D01*
X717192Y42326D01*
X717272Y42226D01*
X717332Y42116D01*
X717372Y41991D01*
X717382Y41866D01*
Y39436D01*
X717412Y39406D01*
X717512Y39266D01*
X717532Y39226D01*
X717547Y39191D01*
X717567Y39151D01*
X717582Y39111D01*
X717592Y39071D01*
X717607Y39026D01*
X717612Y38986D01*
X717622Y38946D01*
X717627Y38901D01*
Y38861D01*
X717632Y38816D01*
X717627Y38771D01*
Y38731D01*
X717622Y38686D01*
X717612Y38646D01*
X717607Y38606D01*
X717592Y38561D01*
X717582Y38521D01*
X717567Y38481D01*
X717547Y38441D01*
X717532Y38406D01*
X717512Y38366D01*
X717412Y38226D01*
X717382Y38196D01*
Y36066D01*
X717372Y35941D01*
X717332Y35816D01*
X717272Y35706D01*
X717192Y35606D01*
X717092Y35526D01*
X716982Y35466D01*
X716857Y35426D01*
X716732Y35416D01*
G37*
G36*
G01X712008D02*
X711883Y35426D01*
X711758Y35466D01*
X711648Y35526D01*
X711548Y35606D01*
X711468Y35706D01*
X711408Y35816D01*
X711368Y35941D01*
X711358Y36066D01*
Y38191D01*
X711328Y38221D01*
X711303Y38256D01*
X711273Y38291D01*
X711253Y38326D01*
X711228Y38361D01*
X711188Y38441D01*
X711143Y38561D01*
X711133Y38601D01*
X711123Y38646D01*
X711118Y38686D01*
X711108Y38731D01*
Y38901D01*
X711118Y38946D01*
X711123Y38986D01*
X711133Y39031D01*
X711143Y39071D01*
X711188Y39191D01*
X711228Y39271D01*
X711253Y39306D01*
X711273Y39341D01*
X711303Y39376D01*
X711328Y39411D01*
X711358Y39441D01*
Y41866D01*
X711368Y41991D01*
X711408Y42116D01*
X711468Y42226D01*
X711548Y42326D01*
X711648Y42406D01*
X711758Y42466D01*
X711883Y42506D01*
X712008Y42516D01*
X712133Y42506D01*
X712258Y42466D01*
X712368Y42406D01*
X712468Y42326D01*
X712548Y42226D01*
X712608Y42116D01*
X712648Y41991D01*
X712658Y41866D01*
Y39436D01*
X712688Y39406D01*
X712788Y39266D01*
X712808Y39226D01*
X712823Y39191D01*
X712843Y39151D01*
X712858Y39111D01*
X712868Y39071D01*
X712883Y39026D01*
X712888Y38986D01*
X712898Y38946D01*
X712903Y38901D01*
Y38861D01*
X712908Y38816D01*
X712903Y38771D01*
Y38731D01*
X712898Y38686D01*
X712888Y38646D01*
X712883Y38606D01*
X712868Y38561D01*
X712858Y38521D01*
X712843Y38481D01*
X712823Y38441D01*
X712808Y38406D01*
X712788Y38366D01*
X712688Y38226D01*
X712658Y38196D01*
Y36066D01*
X712648Y35941D01*
X712608Y35816D01*
X712548Y35706D01*
X712468Y35606D01*
X712368Y35526D01*
X712258Y35466D01*
X712133Y35426D01*
X712008Y35416D01*
G37*
G36*
G01X740354D02*
X740229Y35426D01*
X740104Y35466D01*
X739994Y35526D01*
X739894Y35606D01*
X739814Y35706D01*
X739754Y35816D01*
X739714Y35941D01*
X739704Y36066D01*
Y38191D01*
X739674Y38221D01*
X739649Y38256D01*
X739619Y38291D01*
X739599Y38326D01*
X739574Y38361D01*
X739534Y38441D01*
X739489Y38561D01*
X739479Y38601D01*
X739469Y38646D01*
X739464Y38686D01*
X739454Y38731D01*
Y38901D01*
X739464Y38946D01*
X739469Y38986D01*
X739479Y39031D01*
X739489Y39071D01*
X739534Y39191D01*
X739574Y39271D01*
X739599Y39306D01*
X739619Y39341D01*
X739649Y39376D01*
X739674Y39411D01*
X739704Y39441D01*
Y41866D01*
X739714Y41991D01*
X739754Y42116D01*
X739814Y42226D01*
X739894Y42326D01*
X739994Y42406D01*
X740104Y42466D01*
X740229Y42506D01*
X740354Y42516D01*
X740479Y42506D01*
X740604Y42466D01*
X740714Y42406D01*
X740814Y42326D01*
X740894Y42226D01*
X740954Y42116D01*
X740994Y41991D01*
X741004Y41866D01*
Y39436D01*
X741034Y39406D01*
X741134Y39266D01*
X741154Y39226D01*
X741169Y39191D01*
X741189Y39151D01*
X741204Y39111D01*
X741214Y39071D01*
X741229Y39026D01*
X741234Y38986D01*
X741244Y38946D01*
X741249Y38901D01*
Y38861D01*
X741254Y38816D01*
X741249Y38771D01*
Y38731D01*
X741244Y38686D01*
X741234Y38646D01*
X741229Y38606D01*
X741214Y38561D01*
X741204Y38521D01*
X741189Y38481D01*
X741169Y38441D01*
X741154Y38406D01*
X741134Y38366D01*
X741034Y38226D01*
X741004Y38196D01*
Y36066D01*
X740994Y35941D01*
X740954Y35816D01*
X740894Y35706D01*
X740814Y35606D01*
X740714Y35526D01*
X740604Y35466D01*
X740479Y35426D01*
X740354Y35416D01*
G37*
G36*
G01X735630D02*
X735505Y35426D01*
X735380Y35466D01*
X735270Y35526D01*
X735170Y35606D01*
X735090Y35706D01*
X735030Y35816D01*
X734990Y35941D01*
X734980Y36066D01*
Y38191D01*
X734950Y38221D01*
X734925Y38256D01*
X734895Y38291D01*
X734875Y38326D01*
X734850Y38361D01*
X734810Y38441D01*
X734765Y38561D01*
X734755Y38601D01*
X734745Y38646D01*
X734740Y38686D01*
X734730Y38731D01*
Y38901D01*
X734740Y38946D01*
X734745Y38986D01*
X734755Y39031D01*
X734765Y39071D01*
X734810Y39191D01*
X734850Y39271D01*
X734875Y39306D01*
X734895Y39341D01*
X734925Y39376D01*
X734950Y39411D01*
X734980Y39441D01*
Y41866D01*
X734990Y41991D01*
X735030Y42116D01*
X735090Y42226D01*
X735170Y42326D01*
X735270Y42406D01*
X735380Y42466D01*
X735505Y42506D01*
X735630Y42516D01*
X735755Y42506D01*
X735880Y42466D01*
X735990Y42406D01*
X736090Y42326D01*
X736170Y42226D01*
X736230Y42116D01*
X736270Y41991D01*
X736280Y41866D01*
Y39436D01*
X736310Y39406D01*
X736410Y39266D01*
X736430Y39226D01*
X736445Y39191D01*
X736465Y39151D01*
X736480Y39111D01*
X736490Y39071D01*
X736505Y39026D01*
X736510Y38986D01*
X736520Y38946D01*
X736525Y38901D01*
Y38861D01*
X736530Y38816D01*
X736525Y38771D01*
Y38731D01*
X736520Y38686D01*
X736510Y38646D01*
X736505Y38606D01*
X736490Y38561D01*
X736480Y38521D01*
X736465Y38481D01*
X736445Y38441D01*
X736430Y38406D01*
X736410Y38366D01*
X736310Y38226D01*
X736280Y38196D01*
Y36066D01*
X736270Y35941D01*
X736230Y35816D01*
X736170Y35706D01*
X736090Y35606D01*
X735990Y35526D01*
X735880Y35466D01*
X735755Y35426D01*
X735630Y35416D01*
G37*
G36*
G01X730905D02*
X730780Y35426D01*
X730655Y35466D01*
X730545Y35526D01*
X730445Y35606D01*
X730365Y35706D01*
X730305Y35816D01*
X730265Y35941D01*
X730255Y36066D01*
Y38191D01*
X730225Y38221D01*
X730200Y38256D01*
X730170Y38291D01*
X730150Y38326D01*
X730125Y38361D01*
X730085Y38441D01*
X730040Y38561D01*
X730030Y38601D01*
X730020Y38646D01*
X730015Y38686D01*
X730005Y38731D01*
Y38901D01*
X730015Y38946D01*
X730020Y38986D01*
X730030Y39031D01*
X730040Y39071D01*
X730085Y39191D01*
X730125Y39271D01*
X730150Y39306D01*
X730170Y39341D01*
X730200Y39376D01*
X730225Y39411D01*
X730255Y39441D01*
Y41866D01*
X730265Y41991D01*
X730305Y42116D01*
X730365Y42226D01*
X730445Y42326D01*
X730545Y42406D01*
X730655Y42466D01*
X730780Y42506D01*
X730905Y42516D01*
X731030Y42506D01*
X731155Y42466D01*
X731265Y42406D01*
X731365Y42326D01*
X731445Y42226D01*
X731505Y42116D01*
X731545Y41991D01*
X731555Y41866D01*
Y39436D01*
X731585Y39406D01*
X731685Y39266D01*
X731705Y39226D01*
X731720Y39191D01*
X731740Y39151D01*
X731755Y39111D01*
X731765Y39071D01*
X731780Y39026D01*
X731785Y38986D01*
X731795Y38946D01*
X731800Y38901D01*
Y38861D01*
X731805Y38816D01*
X731800Y38771D01*
Y38731D01*
X731795Y38686D01*
X731785Y38646D01*
X731780Y38606D01*
X731765Y38561D01*
X731755Y38521D01*
X731740Y38481D01*
X731720Y38441D01*
X731705Y38406D01*
X731685Y38366D01*
X731585Y38226D01*
X731555Y38196D01*
Y36066D01*
X731545Y35941D01*
X731505Y35816D01*
X731445Y35706D01*
X731365Y35606D01*
X731265Y35526D01*
X731155Y35466D01*
X731030Y35426D01*
X730905Y35416D01*
G37*
G36*
G01X754527D02*
X754402Y35426D01*
X754277Y35466D01*
X754167Y35526D01*
X754067Y35606D01*
X753987Y35706D01*
X753927Y35816D01*
X753887Y35941D01*
X753877Y36066D01*
Y38191D01*
X753847Y38221D01*
X753822Y38256D01*
X753792Y38291D01*
X753772Y38326D01*
X753747Y38361D01*
X753707Y38441D01*
X753662Y38561D01*
X753652Y38601D01*
X753642Y38646D01*
X753637Y38686D01*
X753627Y38731D01*
Y38901D01*
X753637Y38946D01*
X753642Y38986D01*
X753652Y39031D01*
X753662Y39071D01*
X753707Y39191D01*
X753747Y39271D01*
X753772Y39306D01*
X753792Y39341D01*
X753822Y39376D01*
X753847Y39411D01*
X753877Y39441D01*
Y41866D01*
X753887Y41991D01*
X753927Y42116D01*
X753987Y42226D01*
X754067Y42326D01*
X754167Y42406D01*
X754277Y42466D01*
X754402Y42506D01*
X754527Y42516D01*
X754652Y42506D01*
X754777Y42466D01*
X754887Y42406D01*
X754987Y42326D01*
X755067Y42226D01*
X755127Y42116D01*
X755167Y41991D01*
X755177Y41866D01*
Y39436D01*
X755207Y39406D01*
X755307Y39266D01*
X755327Y39226D01*
X755342Y39191D01*
X755362Y39151D01*
X755377Y39111D01*
X755387Y39071D01*
X755402Y39026D01*
X755407Y38986D01*
X755417Y38946D01*
X755422Y38901D01*
Y38861D01*
X755427Y38816D01*
X755422Y38771D01*
Y38731D01*
X755417Y38686D01*
X755407Y38646D01*
X755402Y38606D01*
X755387Y38561D01*
X755377Y38521D01*
X755362Y38481D01*
X755342Y38441D01*
X755327Y38406D01*
X755307Y38366D01*
X755207Y38226D01*
X755177Y38196D01*
Y36066D01*
X755167Y35941D01*
X755127Y35816D01*
X755067Y35706D01*
X754987Y35606D01*
X754887Y35526D01*
X754777Y35466D01*
X754652Y35426D01*
X754527Y35416D01*
G37*
G36*
G01X749803D02*
X749678Y35426D01*
X749553Y35466D01*
X749443Y35526D01*
X749343Y35606D01*
X749263Y35706D01*
X749203Y35816D01*
X749163Y35941D01*
X749153Y36066D01*
Y38191D01*
X749123Y38221D01*
X749098Y38256D01*
X749068Y38291D01*
X749048Y38326D01*
X749023Y38361D01*
X748983Y38441D01*
X748938Y38561D01*
X748928Y38601D01*
X748918Y38646D01*
X748913Y38686D01*
X748903Y38731D01*
Y38901D01*
X748913Y38946D01*
X748918Y38986D01*
X748928Y39031D01*
X748938Y39071D01*
X748983Y39191D01*
X749023Y39271D01*
X749048Y39306D01*
X749068Y39341D01*
X749098Y39376D01*
X749123Y39411D01*
X749153Y39441D01*
Y41866D01*
X749163Y41991D01*
X749203Y42116D01*
X749263Y42226D01*
X749343Y42326D01*
X749443Y42406D01*
X749553Y42466D01*
X749678Y42506D01*
X749803Y42516D01*
X749928Y42506D01*
X750053Y42466D01*
X750163Y42406D01*
X750263Y42326D01*
X750343Y42226D01*
X750403Y42116D01*
X750443Y41991D01*
X750453Y41866D01*
Y39436D01*
X750483Y39406D01*
X750583Y39266D01*
X750603Y39226D01*
X750618Y39191D01*
X750638Y39151D01*
X750653Y39111D01*
X750663Y39071D01*
X750678Y39026D01*
X750683Y38986D01*
X750693Y38946D01*
X750698Y38901D01*
Y38861D01*
X750703Y38816D01*
X750698Y38771D01*
Y38731D01*
X750693Y38686D01*
X750683Y38646D01*
X750678Y38606D01*
X750663Y38561D01*
X750653Y38521D01*
X750638Y38481D01*
X750618Y38441D01*
X750603Y38406D01*
X750583Y38366D01*
X750483Y38226D01*
X750453Y38196D01*
Y36066D01*
X750443Y35941D01*
X750403Y35816D01*
X750343Y35706D01*
X750263Y35606D01*
X750163Y35526D01*
X750053Y35466D01*
X749928Y35426D01*
X749803Y35416D01*
G37*
G36*
G01X745078D02*
X744953Y35426D01*
X744828Y35466D01*
X744718Y35526D01*
X744618Y35606D01*
X744538Y35706D01*
X744478Y35816D01*
X744438Y35941D01*
X744428Y36066D01*
Y38191D01*
X744398Y38221D01*
X744373Y38256D01*
X744343Y38291D01*
X744323Y38326D01*
X744298Y38361D01*
X744258Y38441D01*
X744213Y38561D01*
X744203Y38601D01*
X744193Y38646D01*
X744188Y38686D01*
X744178Y38731D01*
Y38901D01*
X744188Y38946D01*
X744193Y38986D01*
X744203Y39031D01*
X744213Y39071D01*
X744258Y39191D01*
X744298Y39271D01*
X744323Y39306D01*
X744343Y39341D01*
X744373Y39376D01*
X744398Y39411D01*
X744428Y39441D01*
Y41866D01*
X744438Y41991D01*
X744478Y42116D01*
X744538Y42226D01*
X744618Y42326D01*
X744718Y42406D01*
X744828Y42466D01*
X744953Y42506D01*
X745078Y42516D01*
X745203Y42506D01*
X745328Y42466D01*
X745438Y42406D01*
X745538Y42326D01*
X745618Y42226D01*
X745678Y42116D01*
X745718Y41991D01*
X745728Y41866D01*
Y39436D01*
X745758Y39406D01*
X745858Y39266D01*
X745878Y39226D01*
X745893Y39191D01*
X745913Y39151D01*
X745928Y39111D01*
X745938Y39071D01*
X745953Y39026D01*
X745958Y38986D01*
X745968Y38946D01*
X745973Y38901D01*
Y38861D01*
X745978Y38816D01*
X745973Y38771D01*
Y38731D01*
X745968Y38686D01*
X745958Y38646D01*
X745953Y38606D01*
X745938Y38561D01*
X745928Y38521D01*
X745913Y38481D01*
X745893Y38441D01*
X745878Y38406D01*
X745858Y38366D01*
X745758Y38226D01*
X745728Y38196D01*
Y36066D01*
X745718Y35941D01*
X745678Y35816D01*
X745618Y35706D01*
X745538Y35606D01*
X745438Y35526D01*
X745328Y35466D01*
X745203Y35426D01*
X745078Y35416D01*
G37*
G54D78*
X248430Y164600D03*
X246465D03*
Y180400D03*
X248430D03*
X254335Y164600D03*
X252370D03*
X250400D03*
Y180400D03*
X252370D03*
X254335D03*
G54D69*
X187250Y164000D03*
Y159000D03*
Y154000D03*
Y169000D03*
X203850Y74900D03*
Y69900D03*
Y84900D03*
Y79900D03*
X194197Y105871D03*
Y120871D03*
Y115871D03*
Y110871D03*
X206750Y154000D03*
Y159000D03*
Y164000D03*
Y169000D03*
X223350Y69900D03*
Y74900D03*
Y79900D03*
Y84900D03*
X221299Y105871D03*
Y110871D03*
Y115871D03*
Y120871D03*
G36*
G01X506496Y35416D02*
X506371Y35426D01*
X506246Y35466D01*
X506136Y35526D01*
X506036Y35606D01*
X505956Y35706D01*
X505896Y35816D01*
X505856Y35941D01*
X505846Y36066D01*
Y37196D01*
X505816Y37226D01*
X505716Y37366D01*
X505696Y37406D01*
X505681Y37441D01*
X505661Y37481D01*
X505646Y37521D01*
X505636Y37561D01*
X505621Y37606D01*
X505616Y37646D01*
X505606Y37686D01*
X505601Y37731D01*
Y37771D01*
X505596Y37816D01*
X505601Y37861D01*
Y37901D01*
X505606Y37946D01*
X505616Y37986D01*
X505621Y38026D01*
X505636Y38071D01*
X505646Y38111D01*
X505661Y38151D01*
X505681Y38191D01*
X505696Y38226D01*
X505716Y38266D01*
X505816Y38406D01*
X505846Y38436D01*
Y41866D01*
X505856Y41991D01*
X505896Y42116D01*
X505956Y42226D01*
X506036Y42326D01*
X506136Y42406D01*
X506246Y42466D01*
X506371Y42506D01*
X506496Y42516D01*
X506621Y42506D01*
X506746Y42466D01*
X506856Y42406D01*
X506956Y42326D01*
X507036Y42226D01*
X507096Y42116D01*
X507136Y41991D01*
X507146Y41866D01*
Y38436D01*
X507176Y38406D01*
X507276Y38266D01*
X507296Y38226D01*
X507311Y38191D01*
X507331Y38151D01*
X507346Y38111D01*
X507356Y38071D01*
X507371Y38026D01*
X507376Y37986D01*
X507386Y37946D01*
X507391Y37901D01*
Y37861D01*
X507396Y37816D01*
X507391Y37771D01*
Y37731D01*
X507386Y37686D01*
X507376Y37646D01*
X507371Y37606D01*
X507356Y37561D01*
X507346Y37521D01*
X507331Y37481D01*
X507311Y37441D01*
X507296Y37406D01*
X507276Y37366D01*
X507176Y37226D01*
X507146Y37196D01*
Y36066D01*
X507136Y35941D01*
X507096Y35816D01*
X507036Y35706D01*
X506956Y35606D01*
X506856Y35526D01*
X506746Y35466D01*
X506621Y35426D01*
X506496Y35416D01*
G37*
G36*
G01X525393D02*
X525268Y35426D01*
X525143Y35466D01*
X525033Y35526D01*
X524933Y35606D01*
X524853Y35706D01*
X524793Y35816D01*
X524753Y35941D01*
X524743Y36066D01*
Y37196D01*
X524713Y37226D01*
X524613Y37366D01*
X524593Y37406D01*
X524578Y37441D01*
X524558Y37481D01*
X524543Y37521D01*
X524533Y37561D01*
X524518Y37606D01*
X524513Y37646D01*
X524503Y37686D01*
X524498Y37731D01*
Y37771D01*
X524493Y37816D01*
X524498Y37861D01*
Y37901D01*
X524503Y37946D01*
X524513Y37986D01*
X524518Y38026D01*
X524533Y38071D01*
X524543Y38111D01*
X524558Y38151D01*
X524578Y38191D01*
X524593Y38226D01*
X524613Y38266D01*
X524713Y38406D01*
X524743Y38436D01*
Y41866D01*
X524753Y41991D01*
X524793Y42116D01*
X524853Y42226D01*
X524933Y42326D01*
X525033Y42406D01*
X525143Y42466D01*
X525268Y42506D01*
X525393Y42516D01*
X525518Y42506D01*
X525643Y42466D01*
X525753Y42406D01*
X525853Y42326D01*
X525933Y42226D01*
X525993Y42116D01*
X526033Y41991D01*
X526043Y41866D01*
Y38436D01*
X526073Y38406D01*
X526173Y38266D01*
X526193Y38226D01*
X526208Y38191D01*
X526228Y38151D01*
X526243Y38111D01*
X526253Y38071D01*
X526268Y38026D01*
X526273Y37986D01*
X526283Y37946D01*
X526288Y37901D01*
Y37861D01*
X526293Y37816D01*
X526288Y37771D01*
Y37731D01*
X526283Y37686D01*
X526273Y37646D01*
X526268Y37606D01*
X526253Y37561D01*
X526243Y37521D01*
X526228Y37481D01*
X526208Y37441D01*
X526193Y37406D01*
X526173Y37366D01*
X526073Y37226D01*
X526043Y37196D01*
Y36066D01*
X526033Y35941D01*
X525993Y35816D01*
X525933Y35706D01*
X525853Y35606D01*
X525753Y35526D01*
X525643Y35466D01*
X525518Y35426D01*
X525393Y35416D01*
G37*
G36*
G01X520669D02*
X520544Y35426D01*
X520419Y35466D01*
X520309Y35526D01*
X520209Y35606D01*
X520129Y35706D01*
X520069Y35816D01*
X520029Y35941D01*
X520019Y36066D01*
Y37196D01*
X519989Y37226D01*
X519889Y37366D01*
X519869Y37406D01*
X519854Y37441D01*
X519834Y37481D01*
X519819Y37521D01*
X519809Y37561D01*
X519794Y37606D01*
X519789Y37646D01*
X519779Y37686D01*
X519774Y37731D01*
Y37771D01*
X519769Y37816D01*
X519774Y37861D01*
Y37901D01*
X519779Y37946D01*
X519789Y37986D01*
X519794Y38026D01*
X519809Y38071D01*
X519819Y38111D01*
X519834Y38151D01*
X519854Y38191D01*
X519869Y38226D01*
X519889Y38266D01*
X519989Y38406D01*
X520019Y38436D01*
Y41866D01*
X520029Y41991D01*
X520069Y42116D01*
X520129Y42226D01*
X520209Y42326D01*
X520309Y42406D01*
X520419Y42466D01*
X520544Y42506D01*
X520669Y42516D01*
X520794Y42506D01*
X520919Y42466D01*
X521029Y42406D01*
X521129Y42326D01*
X521209Y42226D01*
X521269Y42116D01*
X521309Y41991D01*
X521319Y41866D01*
Y38436D01*
X521349Y38406D01*
X521449Y38266D01*
X521469Y38226D01*
X521484Y38191D01*
X521504Y38151D01*
X521519Y38111D01*
X521529Y38071D01*
X521544Y38026D01*
X521549Y37986D01*
X521559Y37946D01*
X521564Y37901D01*
Y37861D01*
X521569Y37816D01*
X521564Y37771D01*
Y37731D01*
X521559Y37686D01*
X521549Y37646D01*
X521544Y37606D01*
X521529Y37561D01*
X521519Y37521D01*
X521504Y37481D01*
X521484Y37441D01*
X521469Y37406D01*
X521449Y37366D01*
X521349Y37226D01*
X521319Y37196D01*
Y36066D01*
X521309Y35941D01*
X521269Y35816D01*
X521209Y35706D01*
X521129Y35606D01*
X521029Y35526D01*
X520919Y35466D01*
X520794Y35426D01*
X520669Y35416D01*
G37*
G36*
G01X515945D02*
X515820Y35426D01*
X515695Y35466D01*
X515585Y35526D01*
X515485Y35606D01*
X515405Y35706D01*
X515345Y35816D01*
X515305Y35941D01*
X515295Y36066D01*
Y37196D01*
X515265Y37226D01*
X515165Y37366D01*
X515145Y37406D01*
X515130Y37441D01*
X515110Y37481D01*
X515095Y37521D01*
X515085Y37561D01*
X515070Y37606D01*
X515065Y37646D01*
X515055Y37686D01*
X515050Y37731D01*
Y37771D01*
X515045Y37816D01*
X515050Y37861D01*
Y37901D01*
X515055Y37946D01*
X515065Y37986D01*
X515070Y38026D01*
X515085Y38071D01*
X515095Y38111D01*
X515110Y38151D01*
X515130Y38191D01*
X515145Y38226D01*
X515165Y38266D01*
X515265Y38406D01*
X515295Y38436D01*
Y41866D01*
X515305Y41991D01*
X515345Y42116D01*
X515405Y42226D01*
X515485Y42326D01*
X515585Y42406D01*
X515695Y42466D01*
X515820Y42506D01*
X515945Y42516D01*
X516070Y42506D01*
X516195Y42466D01*
X516305Y42406D01*
X516405Y42326D01*
X516485Y42226D01*
X516545Y42116D01*
X516585Y41991D01*
X516595Y41866D01*
Y38436D01*
X516625Y38406D01*
X516725Y38266D01*
X516745Y38226D01*
X516760Y38191D01*
X516780Y38151D01*
X516795Y38111D01*
X516805Y38071D01*
X516820Y38026D01*
X516825Y37986D01*
X516835Y37946D01*
X516840Y37901D01*
Y37861D01*
X516845Y37816D01*
X516840Y37771D01*
Y37731D01*
X516835Y37686D01*
X516825Y37646D01*
X516820Y37606D01*
X516805Y37561D01*
X516795Y37521D01*
X516780Y37481D01*
X516760Y37441D01*
X516745Y37406D01*
X516725Y37366D01*
X516625Y37226D01*
X516595Y37196D01*
Y36066D01*
X516585Y35941D01*
X516545Y35816D01*
X516485Y35706D01*
X516405Y35606D01*
X516305Y35526D01*
X516195Y35466D01*
X516070Y35426D01*
X515945Y35416D01*
G37*
G36*
G01X511220D02*
X511095Y35426D01*
X510970Y35466D01*
X510860Y35526D01*
X510760Y35606D01*
X510680Y35706D01*
X510620Y35816D01*
X510580Y35941D01*
X510570Y36066D01*
Y37196D01*
X510540Y37226D01*
X510440Y37366D01*
X510420Y37406D01*
X510405Y37441D01*
X510385Y37481D01*
X510370Y37521D01*
X510360Y37561D01*
X510345Y37606D01*
X510340Y37646D01*
X510330Y37686D01*
X510325Y37731D01*
Y37771D01*
X510320Y37816D01*
X510325Y37861D01*
Y37901D01*
X510330Y37946D01*
X510340Y37986D01*
X510345Y38026D01*
X510360Y38071D01*
X510370Y38111D01*
X510385Y38151D01*
X510405Y38191D01*
X510420Y38226D01*
X510440Y38266D01*
X510540Y38406D01*
X510570Y38436D01*
Y41866D01*
X510580Y41991D01*
X510620Y42116D01*
X510680Y42226D01*
X510760Y42326D01*
X510860Y42406D01*
X510970Y42466D01*
X511095Y42506D01*
X511220Y42516D01*
X511345Y42506D01*
X511470Y42466D01*
X511580Y42406D01*
X511680Y42326D01*
X511760Y42226D01*
X511820Y42116D01*
X511860Y41991D01*
X511870Y41866D01*
Y38436D01*
X511900Y38406D01*
X512000Y38266D01*
X512020Y38226D01*
X512035Y38191D01*
X512055Y38151D01*
X512070Y38111D01*
X512080Y38071D01*
X512095Y38026D01*
X512100Y37986D01*
X512110Y37946D01*
X512115Y37901D01*
Y37861D01*
X512120Y37816D01*
X512115Y37771D01*
Y37731D01*
X512110Y37686D01*
X512100Y37646D01*
X512095Y37606D01*
X512080Y37561D01*
X512070Y37521D01*
X512055Y37481D01*
X512035Y37441D01*
X512020Y37406D01*
X512000Y37366D01*
X511900Y37226D01*
X511870Y37196D01*
Y36066D01*
X511860Y35941D01*
X511820Y35816D01*
X511760Y35706D01*
X511680Y35606D01*
X511580Y35526D01*
X511470Y35466D01*
X511345Y35426D01*
X511220Y35416D01*
G37*
G36*
G01X539567D02*
X539442Y35426D01*
X539317Y35466D01*
X539207Y35526D01*
X539107Y35606D01*
X539027Y35706D01*
X538967Y35816D01*
X538927Y35941D01*
X538917Y36066D01*
Y37196D01*
X538887Y37226D01*
X538787Y37366D01*
X538767Y37406D01*
X538752Y37441D01*
X538732Y37481D01*
X538717Y37521D01*
X538707Y37561D01*
X538692Y37606D01*
X538687Y37646D01*
X538677Y37686D01*
X538672Y37731D01*
Y37771D01*
X538667Y37816D01*
X538672Y37861D01*
Y37901D01*
X538677Y37946D01*
X538687Y37986D01*
X538692Y38026D01*
X538707Y38071D01*
X538717Y38111D01*
X538732Y38151D01*
X538752Y38191D01*
X538767Y38226D01*
X538787Y38266D01*
X538887Y38406D01*
X538917Y38436D01*
Y41866D01*
X538927Y41991D01*
X538967Y42116D01*
X539027Y42226D01*
X539107Y42326D01*
X539207Y42406D01*
X539317Y42466D01*
X539442Y42506D01*
X539567Y42516D01*
X539692Y42506D01*
X539817Y42466D01*
X539927Y42406D01*
X540027Y42326D01*
X540107Y42226D01*
X540167Y42116D01*
X540207Y41991D01*
X540217Y41866D01*
Y38436D01*
X540247Y38406D01*
X540347Y38266D01*
X540367Y38226D01*
X540382Y38191D01*
X540402Y38151D01*
X540417Y38111D01*
X540427Y38071D01*
X540442Y38026D01*
X540447Y37986D01*
X540457Y37946D01*
X540462Y37901D01*
Y37861D01*
X540467Y37816D01*
X540462Y37771D01*
Y37731D01*
X540457Y37686D01*
X540447Y37646D01*
X540442Y37606D01*
X540427Y37561D01*
X540417Y37521D01*
X540402Y37481D01*
X540382Y37441D01*
X540367Y37406D01*
X540347Y37366D01*
X540247Y37226D01*
X540217Y37196D01*
Y36066D01*
X540207Y35941D01*
X540167Y35816D01*
X540107Y35706D01*
X540027Y35606D01*
X539927Y35526D01*
X539817Y35466D01*
X539692Y35426D01*
X539567Y35416D01*
G37*
G36*
G01X534842D02*
X534717Y35426D01*
X534592Y35466D01*
X534482Y35526D01*
X534382Y35606D01*
X534302Y35706D01*
X534242Y35816D01*
X534202Y35941D01*
X534192Y36066D01*
Y37196D01*
X534162Y37226D01*
X534062Y37366D01*
X534042Y37406D01*
X534027Y37441D01*
X534007Y37481D01*
X533992Y37521D01*
X533982Y37561D01*
X533967Y37606D01*
X533962Y37646D01*
X533952Y37686D01*
X533947Y37731D01*
Y37771D01*
X533942Y37816D01*
X533947Y37861D01*
Y37901D01*
X533952Y37946D01*
X533962Y37986D01*
X533967Y38026D01*
X533982Y38071D01*
X533992Y38111D01*
X534007Y38151D01*
X534027Y38191D01*
X534042Y38226D01*
X534062Y38266D01*
X534162Y38406D01*
X534192Y38436D01*
Y41866D01*
X534202Y41991D01*
X534242Y42116D01*
X534302Y42226D01*
X534382Y42326D01*
X534482Y42406D01*
X534592Y42466D01*
X534717Y42506D01*
X534842Y42516D01*
X534967Y42506D01*
X535092Y42466D01*
X535202Y42406D01*
X535302Y42326D01*
X535382Y42226D01*
X535442Y42116D01*
X535482Y41991D01*
X535492Y41866D01*
Y38436D01*
X535522Y38406D01*
X535622Y38266D01*
X535642Y38226D01*
X535657Y38191D01*
X535677Y38151D01*
X535692Y38111D01*
X535702Y38071D01*
X535717Y38026D01*
X535722Y37986D01*
X535732Y37946D01*
X535737Y37901D01*
Y37861D01*
X535742Y37816D01*
X535737Y37771D01*
Y37731D01*
X535732Y37686D01*
X535722Y37646D01*
X535717Y37606D01*
X535702Y37561D01*
X535692Y37521D01*
X535677Y37481D01*
X535657Y37441D01*
X535642Y37406D01*
X535622Y37366D01*
X535522Y37226D01*
X535492Y37196D01*
Y36066D01*
X535482Y35941D01*
X535442Y35816D01*
X535382Y35706D01*
X535302Y35606D01*
X535202Y35526D01*
X535092Y35466D01*
X534967Y35426D01*
X534842Y35416D01*
G37*
G36*
G01X530118D02*
X529993Y35426D01*
X529868Y35466D01*
X529758Y35526D01*
X529658Y35606D01*
X529578Y35706D01*
X529518Y35816D01*
X529478Y35941D01*
X529468Y36066D01*
Y37196D01*
X529438Y37226D01*
X529338Y37366D01*
X529318Y37406D01*
X529303Y37441D01*
X529283Y37481D01*
X529268Y37521D01*
X529258Y37561D01*
X529243Y37606D01*
X529238Y37646D01*
X529228Y37686D01*
X529223Y37731D01*
Y37771D01*
X529218Y37816D01*
X529223Y37861D01*
Y37901D01*
X529228Y37946D01*
X529238Y37986D01*
X529243Y38026D01*
X529258Y38071D01*
X529268Y38111D01*
X529283Y38151D01*
X529303Y38191D01*
X529318Y38226D01*
X529338Y38266D01*
X529438Y38406D01*
X529468Y38436D01*
Y41866D01*
X529478Y41991D01*
X529518Y42116D01*
X529578Y42226D01*
X529658Y42326D01*
X529758Y42406D01*
X529868Y42466D01*
X529993Y42506D01*
X530118Y42516D01*
X530243Y42506D01*
X530368Y42466D01*
X530478Y42406D01*
X530578Y42326D01*
X530658Y42226D01*
X530718Y42116D01*
X530758Y41991D01*
X530768Y41866D01*
Y38436D01*
X530798Y38406D01*
X530898Y38266D01*
X530918Y38226D01*
X530933Y38191D01*
X530953Y38151D01*
X530968Y38111D01*
X530978Y38071D01*
X530993Y38026D01*
X530998Y37986D01*
X531008Y37946D01*
X531013Y37901D01*
Y37861D01*
X531018Y37816D01*
X531013Y37771D01*
Y37731D01*
X531008Y37686D01*
X530998Y37646D01*
X530993Y37606D01*
X530978Y37561D01*
X530968Y37521D01*
X530953Y37481D01*
X530933Y37441D01*
X530918Y37406D01*
X530898Y37366D01*
X530798Y37226D01*
X530768Y37196D01*
Y36066D01*
X530758Y35941D01*
X530718Y35816D01*
X530658Y35706D01*
X530578Y35606D01*
X530478Y35526D01*
X530368Y35466D01*
X530243Y35426D01*
X530118Y35416D01*
G37*
G36*
G01X553740D02*
X553615Y35426D01*
X553490Y35466D01*
X553380Y35526D01*
X553280Y35606D01*
X553200Y35706D01*
X553140Y35816D01*
X553100Y35941D01*
X553090Y36066D01*
Y37196D01*
X553060Y37226D01*
X552960Y37366D01*
X552940Y37406D01*
X552925Y37441D01*
X552905Y37481D01*
X552890Y37521D01*
X552880Y37561D01*
X552865Y37606D01*
X552860Y37646D01*
X552850Y37686D01*
X552845Y37731D01*
Y37771D01*
X552840Y37816D01*
X552845Y37861D01*
Y37901D01*
X552850Y37946D01*
X552860Y37986D01*
X552865Y38026D01*
X552880Y38071D01*
X552890Y38111D01*
X552905Y38151D01*
X552925Y38191D01*
X552940Y38226D01*
X552960Y38266D01*
X553060Y38406D01*
X553090Y38436D01*
Y41866D01*
X553100Y41991D01*
X553140Y42116D01*
X553200Y42226D01*
X553280Y42326D01*
X553380Y42406D01*
X553490Y42466D01*
X553615Y42506D01*
X553740Y42516D01*
X553865Y42506D01*
X553990Y42466D01*
X554100Y42406D01*
X554200Y42326D01*
X554280Y42226D01*
X554340Y42116D01*
X554380Y41991D01*
X554390Y41866D01*
Y38436D01*
X554420Y38406D01*
X554520Y38266D01*
X554540Y38226D01*
X554555Y38191D01*
X554575Y38151D01*
X554590Y38111D01*
X554600Y38071D01*
X554615Y38026D01*
X554620Y37986D01*
X554630Y37946D01*
X554635Y37901D01*
Y37861D01*
X554640Y37816D01*
X554635Y37771D01*
Y37731D01*
X554630Y37686D01*
X554620Y37646D01*
X554615Y37606D01*
X554600Y37561D01*
X554590Y37521D01*
X554575Y37481D01*
X554555Y37441D01*
X554540Y37406D01*
X554520Y37366D01*
X554420Y37226D01*
X554390Y37196D01*
Y36066D01*
X554380Y35941D01*
X554340Y35816D01*
X554280Y35706D01*
X554200Y35606D01*
X554100Y35526D01*
X553990Y35466D01*
X553865Y35426D01*
X553740Y35416D01*
G37*
G36*
G01X549015D02*
X548890Y35426D01*
X548765Y35466D01*
X548655Y35526D01*
X548555Y35606D01*
X548475Y35706D01*
X548415Y35816D01*
X548375Y35941D01*
X548365Y36066D01*
Y37196D01*
X548335Y37226D01*
X548235Y37366D01*
X548215Y37406D01*
X548200Y37441D01*
X548180Y37481D01*
X548165Y37521D01*
X548155Y37561D01*
X548140Y37606D01*
X548135Y37646D01*
X548125Y37686D01*
X548120Y37731D01*
Y37771D01*
X548115Y37816D01*
X548120Y37861D01*
Y37901D01*
X548125Y37946D01*
X548135Y37986D01*
X548140Y38026D01*
X548155Y38071D01*
X548165Y38111D01*
X548180Y38151D01*
X548200Y38191D01*
X548215Y38226D01*
X548235Y38266D01*
X548335Y38406D01*
X548365Y38436D01*
Y41866D01*
X548375Y41991D01*
X548415Y42116D01*
X548475Y42226D01*
X548555Y42326D01*
X548655Y42406D01*
X548765Y42466D01*
X548890Y42506D01*
X549015Y42516D01*
X549140Y42506D01*
X549265Y42466D01*
X549375Y42406D01*
X549475Y42326D01*
X549555Y42226D01*
X549615Y42116D01*
X549655Y41991D01*
X549665Y41866D01*
Y38436D01*
X549695Y38406D01*
X549795Y38266D01*
X549815Y38226D01*
X549830Y38191D01*
X549850Y38151D01*
X549865Y38111D01*
X549875Y38071D01*
X549890Y38026D01*
X549895Y37986D01*
X549905Y37946D01*
X549910Y37901D01*
Y37861D01*
X549915Y37816D01*
X549910Y37771D01*
Y37731D01*
X549905Y37686D01*
X549895Y37646D01*
X549890Y37606D01*
X549875Y37561D01*
X549865Y37521D01*
X549850Y37481D01*
X549830Y37441D01*
X549815Y37406D01*
X549795Y37366D01*
X549695Y37226D01*
X549665Y37196D01*
Y36066D01*
X549655Y35941D01*
X549615Y35816D01*
X549555Y35706D01*
X549475Y35606D01*
X549375Y35526D01*
X549265Y35466D01*
X549140Y35426D01*
X549015Y35416D01*
G37*
G36*
G01X544291D02*
X544166Y35426D01*
X544041Y35466D01*
X543931Y35526D01*
X543831Y35606D01*
X543751Y35706D01*
X543691Y35816D01*
X543651Y35941D01*
X543641Y36066D01*
Y37196D01*
X543611Y37226D01*
X543511Y37366D01*
X543491Y37406D01*
X543476Y37441D01*
X543456Y37481D01*
X543441Y37521D01*
X543431Y37561D01*
X543416Y37606D01*
X543411Y37646D01*
X543401Y37686D01*
X543396Y37731D01*
Y37771D01*
X543391Y37816D01*
X543396Y37861D01*
Y37901D01*
X543401Y37946D01*
X543411Y37986D01*
X543416Y38026D01*
X543431Y38071D01*
X543441Y38111D01*
X543456Y38151D01*
X543476Y38191D01*
X543491Y38226D01*
X543511Y38266D01*
X543611Y38406D01*
X543641Y38436D01*
Y41866D01*
X543651Y41991D01*
X543691Y42116D01*
X543751Y42226D01*
X543831Y42326D01*
X543931Y42406D01*
X544041Y42466D01*
X544166Y42506D01*
X544291Y42516D01*
X544416Y42506D01*
X544541Y42466D01*
X544651Y42406D01*
X544751Y42326D01*
X544831Y42226D01*
X544891Y42116D01*
X544931Y41991D01*
X544941Y41866D01*
Y38436D01*
X544971Y38406D01*
X545071Y38266D01*
X545091Y38226D01*
X545106Y38191D01*
X545126Y38151D01*
X545141Y38111D01*
X545151Y38071D01*
X545166Y38026D01*
X545171Y37986D01*
X545181Y37946D01*
X545186Y37901D01*
Y37861D01*
X545191Y37816D01*
X545186Y37771D01*
Y37731D01*
X545181Y37686D01*
X545171Y37646D01*
X545166Y37606D01*
X545151Y37561D01*
X545141Y37521D01*
X545126Y37481D01*
X545106Y37441D01*
X545091Y37406D01*
X545071Y37366D01*
X544971Y37226D01*
X544941Y37196D01*
Y36066D01*
X544931Y35941D01*
X544891Y35816D01*
X544831Y35706D01*
X544751Y35606D01*
X544651Y35526D01*
X544541Y35466D01*
X544416Y35426D01*
X544291Y35416D01*
G37*
G36*
G01X572638D02*
X572513Y35426D01*
X572388Y35466D01*
X572278Y35526D01*
X572178Y35606D01*
X572098Y35706D01*
X572038Y35816D01*
X571998Y35941D01*
X571988Y36066D01*
Y37196D01*
X571958Y37226D01*
X571858Y37366D01*
X571838Y37406D01*
X571823Y37441D01*
X571803Y37481D01*
X571788Y37521D01*
X571778Y37561D01*
X571763Y37606D01*
X571758Y37646D01*
X571748Y37686D01*
X571743Y37731D01*
Y37771D01*
X571738Y37816D01*
X571743Y37861D01*
Y37901D01*
X571748Y37946D01*
X571758Y37986D01*
X571763Y38026D01*
X571778Y38071D01*
X571788Y38111D01*
X571803Y38151D01*
X571823Y38191D01*
X571838Y38226D01*
X571858Y38266D01*
X571958Y38406D01*
X571988Y38436D01*
Y41866D01*
X571998Y41991D01*
X572038Y42116D01*
X572098Y42226D01*
X572178Y42326D01*
X572278Y42406D01*
X572388Y42466D01*
X572513Y42506D01*
X572638Y42516D01*
X572763Y42506D01*
X572888Y42466D01*
X572998Y42406D01*
X573098Y42326D01*
X573178Y42226D01*
X573238Y42116D01*
X573278Y41991D01*
X573288Y41866D01*
Y38436D01*
X573318Y38406D01*
X573418Y38266D01*
X573438Y38226D01*
X573453Y38191D01*
X573473Y38151D01*
X573488Y38111D01*
X573498Y38071D01*
X573513Y38026D01*
X573518Y37986D01*
X573528Y37946D01*
X573533Y37901D01*
Y37861D01*
X573538Y37816D01*
X573533Y37771D01*
Y37731D01*
X573528Y37686D01*
X573518Y37646D01*
X573513Y37606D01*
X573498Y37561D01*
X573488Y37521D01*
X573473Y37481D01*
X573453Y37441D01*
X573438Y37406D01*
X573418Y37366D01*
X573318Y37226D01*
X573288Y37196D01*
Y36066D01*
X573278Y35941D01*
X573238Y35816D01*
X573178Y35706D01*
X573098Y35606D01*
X572998Y35526D01*
X572888Y35466D01*
X572763Y35426D01*
X572638Y35416D01*
G37*
G36*
G01X567913D02*
X567788Y35426D01*
X567663Y35466D01*
X567553Y35526D01*
X567453Y35606D01*
X567373Y35706D01*
X567313Y35816D01*
X567273Y35941D01*
X567263Y36066D01*
Y37196D01*
X567233Y37226D01*
X567133Y37366D01*
X567113Y37406D01*
X567098Y37441D01*
X567078Y37481D01*
X567063Y37521D01*
X567053Y37561D01*
X567038Y37606D01*
X567033Y37646D01*
X567023Y37686D01*
X567018Y37731D01*
Y37771D01*
X567013Y37816D01*
X567018Y37861D01*
Y37901D01*
X567023Y37946D01*
X567033Y37986D01*
X567038Y38026D01*
X567053Y38071D01*
X567063Y38111D01*
X567078Y38151D01*
X567098Y38191D01*
X567113Y38226D01*
X567133Y38266D01*
X567233Y38406D01*
X567263Y38436D01*
Y41866D01*
X567273Y41991D01*
X567313Y42116D01*
X567373Y42226D01*
X567453Y42326D01*
X567553Y42406D01*
X567663Y42466D01*
X567788Y42506D01*
X567913Y42516D01*
X568038Y42506D01*
X568163Y42466D01*
X568273Y42406D01*
X568373Y42326D01*
X568453Y42226D01*
X568513Y42116D01*
X568553Y41991D01*
X568563Y41866D01*
Y38436D01*
X568593Y38406D01*
X568693Y38266D01*
X568713Y38226D01*
X568728Y38191D01*
X568748Y38151D01*
X568763Y38111D01*
X568773Y38071D01*
X568788Y38026D01*
X568793Y37986D01*
X568803Y37946D01*
X568808Y37901D01*
Y37861D01*
X568813Y37816D01*
X568808Y37771D01*
Y37731D01*
X568803Y37686D01*
X568793Y37646D01*
X568788Y37606D01*
X568773Y37561D01*
X568763Y37521D01*
X568748Y37481D01*
X568728Y37441D01*
X568713Y37406D01*
X568693Y37366D01*
X568593Y37226D01*
X568563Y37196D01*
Y36066D01*
X568553Y35941D01*
X568513Y35816D01*
X568453Y35706D01*
X568373Y35606D01*
X568273Y35526D01*
X568163Y35466D01*
X568038Y35426D01*
X567913Y35416D01*
G37*
G36*
G01X563189D02*
X563064Y35426D01*
X562939Y35466D01*
X562829Y35526D01*
X562729Y35606D01*
X562649Y35706D01*
X562589Y35816D01*
X562549Y35941D01*
X562539Y36066D01*
Y37196D01*
X562509Y37226D01*
X562409Y37366D01*
X562389Y37406D01*
X562374Y37441D01*
X562354Y37481D01*
X562339Y37521D01*
X562329Y37561D01*
X562314Y37606D01*
X562309Y37646D01*
X562299Y37686D01*
X562294Y37731D01*
Y37771D01*
X562289Y37816D01*
X562294Y37861D01*
Y37901D01*
X562299Y37946D01*
X562309Y37986D01*
X562314Y38026D01*
X562329Y38071D01*
X562339Y38111D01*
X562354Y38151D01*
X562374Y38191D01*
X562389Y38226D01*
X562409Y38266D01*
X562509Y38406D01*
X562539Y38436D01*
Y41866D01*
X562549Y41991D01*
X562589Y42116D01*
X562649Y42226D01*
X562729Y42326D01*
X562829Y42406D01*
X562939Y42466D01*
X563064Y42506D01*
X563189Y42516D01*
X563314Y42506D01*
X563439Y42466D01*
X563549Y42406D01*
X563649Y42326D01*
X563729Y42226D01*
X563789Y42116D01*
X563829Y41991D01*
X563839Y41866D01*
Y38436D01*
X563869Y38406D01*
X563969Y38266D01*
X563989Y38226D01*
X564004Y38191D01*
X564024Y38151D01*
X564039Y38111D01*
X564049Y38071D01*
X564064Y38026D01*
X564069Y37986D01*
X564079Y37946D01*
X564084Y37901D01*
Y37861D01*
X564089Y37816D01*
X564084Y37771D01*
Y37731D01*
X564079Y37686D01*
X564069Y37646D01*
X564064Y37606D01*
X564049Y37561D01*
X564039Y37521D01*
X564024Y37481D01*
X564004Y37441D01*
X563989Y37406D01*
X563969Y37366D01*
X563869Y37226D01*
X563839Y37196D01*
Y36066D01*
X563829Y35941D01*
X563789Y35816D01*
X563729Y35706D01*
X563649Y35606D01*
X563549Y35526D01*
X563439Y35466D01*
X563314Y35426D01*
X563189Y35416D01*
G37*
G36*
G01X558464D02*
X558339Y35426D01*
X558214Y35466D01*
X558104Y35526D01*
X558004Y35606D01*
X557924Y35706D01*
X557864Y35816D01*
X557824Y35941D01*
X557814Y36066D01*
Y37196D01*
X557784Y37226D01*
X557684Y37366D01*
X557664Y37406D01*
X557649Y37441D01*
X557629Y37481D01*
X557614Y37521D01*
X557604Y37561D01*
X557589Y37606D01*
X557584Y37646D01*
X557574Y37686D01*
X557569Y37731D01*
Y37771D01*
X557564Y37816D01*
X557569Y37861D01*
Y37901D01*
X557574Y37946D01*
X557584Y37986D01*
X557589Y38026D01*
X557604Y38071D01*
X557614Y38111D01*
X557629Y38151D01*
X557649Y38191D01*
X557664Y38226D01*
X557684Y38266D01*
X557784Y38406D01*
X557814Y38436D01*
Y41866D01*
X557824Y41991D01*
X557864Y42116D01*
X557924Y42226D01*
X558004Y42326D01*
X558104Y42406D01*
X558214Y42466D01*
X558339Y42506D01*
X558464Y42516D01*
X558589Y42506D01*
X558714Y42466D01*
X558824Y42406D01*
X558924Y42326D01*
X559004Y42226D01*
X559064Y42116D01*
X559104Y41991D01*
X559114Y41866D01*
Y38436D01*
X559144Y38406D01*
X559244Y38266D01*
X559264Y38226D01*
X559279Y38191D01*
X559299Y38151D01*
X559314Y38111D01*
X559324Y38071D01*
X559339Y38026D01*
X559344Y37986D01*
X559354Y37946D01*
X559359Y37901D01*
Y37861D01*
X559364Y37816D01*
X559359Y37771D01*
Y37731D01*
X559354Y37686D01*
X559344Y37646D01*
X559339Y37606D01*
X559324Y37561D01*
X559314Y37521D01*
X559299Y37481D01*
X559279Y37441D01*
X559264Y37406D01*
X559244Y37366D01*
X559144Y37226D01*
X559114Y37196D01*
Y36066D01*
X559104Y35941D01*
X559064Y35816D01*
X559004Y35706D01*
X558924Y35606D01*
X558824Y35526D01*
X558714Y35466D01*
X558589Y35426D01*
X558464Y35416D01*
G37*
G36*
G01X586811D02*
X586686Y35426D01*
X586561Y35466D01*
X586451Y35526D01*
X586351Y35606D01*
X586271Y35706D01*
X586211Y35816D01*
X586171Y35941D01*
X586161Y36066D01*
Y37196D01*
X586131Y37226D01*
X586031Y37366D01*
X586011Y37406D01*
X585996Y37441D01*
X585976Y37481D01*
X585961Y37521D01*
X585951Y37561D01*
X585936Y37606D01*
X585931Y37646D01*
X585921Y37686D01*
X585916Y37731D01*
Y37771D01*
X585911Y37816D01*
X585916Y37861D01*
Y37901D01*
X585921Y37946D01*
X585931Y37986D01*
X585936Y38026D01*
X585951Y38071D01*
X585961Y38111D01*
X585976Y38151D01*
X585996Y38191D01*
X586011Y38226D01*
X586031Y38266D01*
X586131Y38406D01*
X586161Y38436D01*
Y41866D01*
X586171Y41991D01*
X586211Y42116D01*
X586271Y42226D01*
X586351Y42326D01*
X586451Y42406D01*
X586561Y42466D01*
X586686Y42506D01*
X586811Y42516D01*
X586936Y42506D01*
X587061Y42466D01*
X587171Y42406D01*
X587271Y42326D01*
X587351Y42226D01*
X587411Y42116D01*
X587451Y41991D01*
X587461Y41866D01*
Y38436D01*
X587491Y38406D01*
X587591Y38266D01*
X587611Y38226D01*
X587626Y38191D01*
X587646Y38151D01*
X587661Y38111D01*
X587671Y38071D01*
X587686Y38026D01*
X587691Y37986D01*
X587701Y37946D01*
X587706Y37901D01*
Y37861D01*
X587711Y37816D01*
X587706Y37771D01*
Y37731D01*
X587701Y37686D01*
X587691Y37646D01*
X587686Y37606D01*
X587671Y37561D01*
X587661Y37521D01*
X587646Y37481D01*
X587626Y37441D01*
X587611Y37406D01*
X587591Y37366D01*
X587491Y37226D01*
X587461Y37196D01*
Y36066D01*
X587451Y35941D01*
X587411Y35816D01*
X587351Y35706D01*
X587271Y35606D01*
X587171Y35526D01*
X587061Y35466D01*
X586936Y35426D01*
X586811Y35416D01*
G37*
G36*
G01X582086D02*
X581961Y35426D01*
X581836Y35466D01*
X581726Y35526D01*
X581626Y35606D01*
X581546Y35706D01*
X581486Y35816D01*
X581446Y35941D01*
X581436Y36066D01*
Y37196D01*
X581406Y37226D01*
X581306Y37366D01*
X581286Y37406D01*
X581271Y37441D01*
X581251Y37481D01*
X581236Y37521D01*
X581226Y37561D01*
X581211Y37606D01*
X581206Y37646D01*
X581196Y37686D01*
X581191Y37731D01*
Y37771D01*
X581186Y37816D01*
X581191Y37861D01*
Y37901D01*
X581196Y37946D01*
X581206Y37986D01*
X581211Y38026D01*
X581226Y38071D01*
X581236Y38111D01*
X581251Y38151D01*
X581271Y38191D01*
X581286Y38226D01*
X581306Y38266D01*
X581406Y38406D01*
X581436Y38436D01*
Y41866D01*
X581446Y41991D01*
X581486Y42116D01*
X581546Y42226D01*
X581626Y42326D01*
X581726Y42406D01*
X581836Y42466D01*
X581961Y42506D01*
X582086Y42516D01*
X582211Y42506D01*
X582336Y42466D01*
X582446Y42406D01*
X582546Y42326D01*
X582626Y42226D01*
X582686Y42116D01*
X582726Y41991D01*
X582736Y41866D01*
Y38436D01*
X582766Y38406D01*
X582866Y38266D01*
X582886Y38226D01*
X582901Y38191D01*
X582921Y38151D01*
X582936Y38111D01*
X582946Y38071D01*
X582961Y38026D01*
X582966Y37986D01*
X582976Y37946D01*
X582981Y37901D01*
Y37861D01*
X582986Y37816D01*
X582981Y37771D01*
Y37731D01*
X582976Y37686D01*
X582966Y37646D01*
X582961Y37606D01*
X582946Y37561D01*
X582936Y37521D01*
X582921Y37481D01*
X582901Y37441D01*
X582886Y37406D01*
X582866Y37366D01*
X582766Y37226D01*
X582736Y37196D01*
Y36066D01*
X582726Y35941D01*
X582686Y35816D01*
X582626Y35706D01*
X582546Y35606D01*
X582446Y35526D01*
X582336Y35466D01*
X582211Y35426D01*
X582086Y35416D01*
G37*
G36*
G01X577362D02*
X577237Y35426D01*
X577112Y35466D01*
X577002Y35526D01*
X576902Y35606D01*
X576822Y35706D01*
X576762Y35816D01*
X576722Y35941D01*
X576712Y36066D01*
Y37196D01*
X576682Y37226D01*
X576582Y37366D01*
X576562Y37406D01*
X576547Y37441D01*
X576527Y37481D01*
X576512Y37521D01*
X576502Y37561D01*
X576487Y37606D01*
X576482Y37646D01*
X576472Y37686D01*
X576467Y37731D01*
Y37771D01*
X576462Y37816D01*
X576467Y37861D01*
Y37901D01*
X576472Y37946D01*
X576482Y37986D01*
X576487Y38026D01*
X576502Y38071D01*
X576512Y38111D01*
X576527Y38151D01*
X576547Y38191D01*
X576562Y38226D01*
X576582Y38266D01*
X576682Y38406D01*
X576712Y38436D01*
Y41866D01*
X576722Y41991D01*
X576762Y42116D01*
X576822Y42226D01*
X576902Y42326D01*
X577002Y42406D01*
X577112Y42466D01*
X577237Y42506D01*
X577362Y42516D01*
X577487Y42506D01*
X577612Y42466D01*
X577722Y42406D01*
X577822Y42326D01*
X577902Y42226D01*
X577962Y42116D01*
X578002Y41991D01*
X578012Y41866D01*
Y38436D01*
X578042Y38406D01*
X578142Y38266D01*
X578162Y38226D01*
X578177Y38191D01*
X578197Y38151D01*
X578212Y38111D01*
X578222Y38071D01*
X578237Y38026D01*
X578242Y37986D01*
X578252Y37946D01*
X578257Y37901D01*
Y37861D01*
X578262Y37816D01*
X578257Y37771D01*
Y37731D01*
X578252Y37686D01*
X578242Y37646D01*
X578237Y37606D01*
X578222Y37561D01*
X578212Y37521D01*
X578197Y37481D01*
X578177Y37441D01*
X578162Y37406D01*
X578142Y37366D01*
X578042Y37226D01*
X578012Y37196D01*
Y36066D01*
X578002Y35941D01*
X577962Y35816D01*
X577902Y35706D01*
X577822Y35606D01*
X577722Y35526D01*
X577612Y35466D01*
X577487Y35426D01*
X577362Y35416D01*
G37*
G36*
G01X600984D02*
X600859Y35426D01*
X600734Y35466D01*
X600624Y35526D01*
X600524Y35606D01*
X600444Y35706D01*
X600384Y35816D01*
X600344Y35941D01*
X600334Y36066D01*
Y37196D01*
X600304Y37226D01*
X600204Y37366D01*
X600184Y37406D01*
X600169Y37441D01*
X600149Y37481D01*
X600134Y37521D01*
X600124Y37561D01*
X600109Y37606D01*
X600104Y37646D01*
X600094Y37686D01*
X600089Y37731D01*
Y37771D01*
X600084Y37816D01*
X600089Y37861D01*
Y37901D01*
X600094Y37946D01*
X600104Y37986D01*
X600109Y38026D01*
X600124Y38071D01*
X600134Y38111D01*
X600149Y38151D01*
X600169Y38191D01*
X600184Y38226D01*
X600204Y38266D01*
X600304Y38406D01*
X600334Y38436D01*
Y41866D01*
X600344Y41991D01*
X600384Y42116D01*
X600444Y42226D01*
X600524Y42326D01*
X600624Y42406D01*
X600734Y42466D01*
X600859Y42506D01*
X600984Y42516D01*
X601109Y42506D01*
X601234Y42466D01*
X601344Y42406D01*
X601444Y42326D01*
X601524Y42226D01*
X601584Y42116D01*
X601624Y41991D01*
X601634Y41866D01*
Y38436D01*
X601664Y38406D01*
X601764Y38266D01*
X601784Y38226D01*
X601799Y38191D01*
X601819Y38151D01*
X601834Y38111D01*
X601844Y38071D01*
X601859Y38026D01*
X601864Y37986D01*
X601874Y37946D01*
X601879Y37901D01*
Y37861D01*
X601884Y37816D01*
X601879Y37771D01*
Y37731D01*
X601874Y37686D01*
X601864Y37646D01*
X601859Y37606D01*
X601844Y37561D01*
X601834Y37521D01*
X601819Y37481D01*
X601799Y37441D01*
X601784Y37406D01*
X601764Y37366D01*
X601664Y37226D01*
X601634Y37196D01*
Y36066D01*
X601624Y35941D01*
X601584Y35816D01*
X601524Y35706D01*
X601444Y35606D01*
X601344Y35526D01*
X601234Y35466D01*
X601109Y35426D01*
X600984Y35416D01*
G37*
G36*
G01X615157D02*
X615032Y35426D01*
X614907Y35466D01*
X614797Y35526D01*
X614697Y35606D01*
X614617Y35706D01*
X614557Y35816D01*
X614517Y35941D01*
X614507Y36066D01*
Y37196D01*
X614477Y37226D01*
X614377Y37366D01*
X614357Y37406D01*
X614342Y37441D01*
X614322Y37481D01*
X614307Y37521D01*
X614297Y37561D01*
X614282Y37606D01*
X614277Y37646D01*
X614267Y37686D01*
X614262Y37731D01*
Y37771D01*
X614257Y37816D01*
X614262Y37861D01*
Y37901D01*
X614267Y37946D01*
X614277Y37986D01*
X614282Y38026D01*
X614297Y38071D01*
X614307Y38111D01*
X614322Y38151D01*
X614342Y38191D01*
X614357Y38226D01*
X614377Y38266D01*
X614477Y38406D01*
X614507Y38436D01*
Y41866D01*
X614517Y41991D01*
X614557Y42116D01*
X614617Y42226D01*
X614697Y42326D01*
X614797Y42406D01*
X614907Y42466D01*
X615032Y42506D01*
X615157Y42516D01*
X615282Y42506D01*
X615407Y42466D01*
X615517Y42406D01*
X615617Y42326D01*
X615697Y42226D01*
X615757Y42116D01*
X615797Y41991D01*
X615807Y41866D01*
Y38436D01*
X615837Y38406D01*
X615937Y38266D01*
X615957Y38226D01*
X615972Y38191D01*
X615992Y38151D01*
X616007Y38111D01*
X616017Y38071D01*
X616032Y38026D01*
X616037Y37986D01*
X616047Y37946D01*
X616052Y37901D01*
Y37861D01*
X616057Y37816D01*
X616052Y37771D01*
Y37731D01*
X616047Y37686D01*
X616037Y37646D01*
X616032Y37606D01*
X616017Y37561D01*
X616007Y37521D01*
X615992Y37481D01*
X615972Y37441D01*
X615957Y37406D01*
X615937Y37366D01*
X615837Y37226D01*
X615807Y37196D01*
Y36066D01*
X615797Y35941D01*
X615757Y35816D01*
X615697Y35706D01*
X615617Y35606D01*
X615517Y35526D01*
X615407Y35466D01*
X615282Y35426D01*
X615157Y35416D01*
G37*
G36*
G01X610433D02*
X610308Y35426D01*
X610183Y35466D01*
X610073Y35526D01*
X609973Y35606D01*
X609893Y35706D01*
X609833Y35816D01*
X609793Y35941D01*
X609783Y36066D01*
Y37196D01*
X609753Y37226D01*
X609653Y37366D01*
X609633Y37406D01*
X609618Y37441D01*
X609598Y37481D01*
X609583Y37521D01*
X609573Y37561D01*
X609558Y37606D01*
X609553Y37646D01*
X609543Y37686D01*
X609538Y37731D01*
Y37771D01*
X609533Y37816D01*
X609538Y37861D01*
Y37901D01*
X609543Y37946D01*
X609553Y37986D01*
X609558Y38026D01*
X609573Y38071D01*
X609583Y38111D01*
X609598Y38151D01*
X609618Y38191D01*
X609633Y38226D01*
X609653Y38266D01*
X609753Y38406D01*
X609783Y38436D01*
Y41866D01*
X609793Y41991D01*
X609833Y42116D01*
X609893Y42226D01*
X609973Y42326D01*
X610073Y42406D01*
X610183Y42466D01*
X610308Y42506D01*
X610433Y42516D01*
X610558Y42506D01*
X610683Y42466D01*
X610793Y42406D01*
X610893Y42326D01*
X610973Y42226D01*
X611033Y42116D01*
X611073Y41991D01*
X611083Y41866D01*
Y38436D01*
X611113Y38406D01*
X611213Y38266D01*
X611233Y38226D01*
X611248Y38191D01*
X611268Y38151D01*
X611283Y38111D01*
X611293Y38071D01*
X611308Y38026D01*
X611313Y37986D01*
X611323Y37946D01*
X611328Y37901D01*
Y37861D01*
X611333Y37816D01*
X611328Y37771D01*
Y37731D01*
X611323Y37686D01*
X611313Y37646D01*
X611308Y37606D01*
X611293Y37561D01*
X611283Y37521D01*
X611268Y37481D01*
X611248Y37441D01*
X611233Y37406D01*
X611213Y37366D01*
X611113Y37226D01*
X611083Y37196D01*
Y36066D01*
X611073Y35941D01*
X611033Y35816D01*
X610973Y35706D01*
X610893Y35606D01*
X610793Y35526D01*
X610683Y35466D01*
X610558Y35426D01*
X610433Y35416D01*
G37*
G36*
G01X605708D02*
X605583Y35426D01*
X605458Y35466D01*
X605348Y35526D01*
X605248Y35606D01*
X605168Y35706D01*
X605108Y35816D01*
X605068Y35941D01*
X605058Y36066D01*
Y37196D01*
X605028Y37226D01*
X604928Y37366D01*
X604908Y37406D01*
X604893Y37441D01*
X604873Y37481D01*
X604858Y37521D01*
X604848Y37561D01*
X604833Y37606D01*
X604828Y37646D01*
X604818Y37686D01*
X604813Y37731D01*
Y37771D01*
X604808Y37816D01*
X604813Y37861D01*
Y37901D01*
X604818Y37946D01*
X604828Y37986D01*
X604833Y38026D01*
X604848Y38071D01*
X604858Y38111D01*
X604873Y38151D01*
X604893Y38191D01*
X604908Y38226D01*
X604928Y38266D01*
X605028Y38406D01*
X605058Y38436D01*
Y41866D01*
X605068Y41991D01*
X605108Y42116D01*
X605168Y42226D01*
X605248Y42326D01*
X605348Y42406D01*
X605458Y42466D01*
X605583Y42506D01*
X605708Y42516D01*
X605833Y42506D01*
X605958Y42466D01*
X606068Y42406D01*
X606168Y42326D01*
X606248Y42226D01*
X606308Y42116D01*
X606348Y41991D01*
X606358Y41866D01*
Y38436D01*
X606388Y38406D01*
X606488Y38266D01*
X606508Y38226D01*
X606523Y38191D01*
X606543Y38151D01*
X606558Y38111D01*
X606568Y38071D01*
X606583Y38026D01*
X606588Y37986D01*
X606598Y37946D01*
X606603Y37901D01*
Y37861D01*
X606608Y37816D01*
X606603Y37771D01*
Y37731D01*
X606598Y37686D01*
X606588Y37646D01*
X606583Y37606D01*
X606568Y37561D01*
X606558Y37521D01*
X606543Y37481D01*
X606523Y37441D01*
X606508Y37406D01*
X606488Y37366D01*
X606388Y37226D01*
X606358Y37196D01*
Y36066D01*
X606348Y35941D01*
X606308Y35816D01*
X606248Y35706D01*
X606168Y35606D01*
X606068Y35526D01*
X605958Y35466D01*
X605833Y35426D01*
X605708Y35416D01*
G37*
G36*
G01X634055D02*
X633930Y35426D01*
X633805Y35466D01*
X633695Y35526D01*
X633595Y35606D01*
X633515Y35706D01*
X633455Y35816D01*
X633415Y35941D01*
X633405Y36066D01*
Y37196D01*
X633375Y37226D01*
X633275Y37366D01*
X633255Y37406D01*
X633240Y37441D01*
X633220Y37481D01*
X633205Y37521D01*
X633195Y37561D01*
X633180Y37606D01*
X633175Y37646D01*
X633165Y37686D01*
X633160Y37731D01*
Y37771D01*
X633155Y37816D01*
X633160Y37861D01*
Y37901D01*
X633165Y37946D01*
X633175Y37986D01*
X633180Y38026D01*
X633195Y38071D01*
X633205Y38111D01*
X633220Y38151D01*
X633240Y38191D01*
X633255Y38226D01*
X633275Y38266D01*
X633375Y38406D01*
X633405Y38436D01*
Y41866D01*
X633415Y41991D01*
X633455Y42116D01*
X633515Y42226D01*
X633595Y42326D01*
X633695Y42406D01*
X633805Y42466D01*
X633930Y42506D01*
X634055Y42516D01*
X634180Y42506D01*
X634305Y42466D01*
X634415Y42406D01*
X634515Y42326D01*
X634595Y42226D01*
X634655Y42116D01*
X634695Y41991D01*
X634705Y41866D01*
Y38436D01*
X634735Y38406D01*
X634835Y38266D01*
X634855Y38226D01*
X634870Y38191D01*
X634890Y38151D01*
X634905Y38111D01*
X634915Y38071D01*
X634930Y38026D01*
X634935Y37986D01*
X634945Y37946D01*
X634950Y37901D01*
Y37861D01*
X634955Y37816D01*
X634950Y37771D01*
Y37731D01*
X634945Y37686D01*
X634935Y37646D01*
X634930Y37606D01*
X634915Y37561D01*
X634905Y37521D01*
X634890Y37481D01*
X634870Y37441D01*
X634855Y37406D01*
X634835Y37366D01*
X634735Y37226D01*
X634705Y37196D01*
Y36066D01*
X634695Y35941D01*
X634655Y35816D01*
X634595Y35706D01*
X634515Y35606D01*
X634415Y35526D01*
X634305Y35466D01*
X634180Y35426D01*
X634055Y35416D01*
G37*
G36*
G01X629330D02*
X629205Y35426D01*
X629080Y35466D01*
X628970Y35526D01*
X628870Y35606D01*
X628790Y35706D01*
X628730Y35816D01*
X628690Y35941D01*
X628680Y36066D01*
Y37196D01*
X628650Y37226D01*
X628550Y37366D01*
X628530Y37406D01*
X628515Y37441D01*
X628495Y37481D01*
X628480Y37521D01*
X628470Y37561D01*
X628455Y37606D01*
X628450Y37646D01*
X628440Y37686D01*
X628435Y37731D01*
Y37771D01*
X628430Y37816D01*
X628435Y37861D01*
Y37901D01*
X628440Y37946D01*
X628450Y37986D01*
X628455Y38026D01*
X628470Y38071D01*
X628480Y38111D01*
X628495Y38151D01*
X628515Y38191D01*
X628530Y38226D01*
X628550Y38266D01*
X628650Y38406D01*
X628680Y38436D01*
Y41866D01*
X628690Y41991D01*
X628730Y42116D01*
X628790Y42226D01*
X628870Y42326D01*
X628970Y42406D01*
X629080Y42466D01*
X629205Y42506D01*
X629330Y42516D01*
X629455Y42506D01*
X629580Y42466D01*
X629690Y42406D01*
X629790Y42326D01*
X629870Y42226D01*
X629930Y42116D01*
X629970Y41991D01*
X629980Y41866D01*
Y38436D01*
X630010Y38406D01*
X630110Y38266D01*
X630130Y38226D01*
X630145Y38191D01*
X630165Y38151D01*
X630180Y38111D01*
X630190Y38071D01*
X630205Y38026D01*
X630210Y37986D01*
X630220Y37946D01*
X630225Y37901D01*
Y37861D01*
X630230Y37816D01*
X630225Y37771D01*
Y37731D01*
X630220Y37686D01*
X630210Y37646D01*
X630205Y37606D01*
X630190Y37561D01*
X630180Y37521D01*
X630165Y37481D01*
X630145Y37441D01*
X630130Y37406D01*
X630110Y37366D01*
X630010Y37226D01*
X629980Y37196D01*
Y36066D01*
X629970Y35941D01*
X629930Y35816D01*
X629870Y35706D01*
X629790Y35606D01*
X629690Y35526D01*
X629580Y35466D01*
X629455Y35426D01*
X629330Y35416D01*
G37*
G36*
G01X624606D02*
X624481Y35426D01*
X624356Y35466D01*
X624246Y35526D01*
X624146Y35606D01*
X624066Y35706D01*
X624006Y35816D01*
X623966Y35941D01*
X623956Y36066D01*
Y37196D01*
X623926Y37226D01*
X623826Y37366D01*
X623806Y37406D01*
X623791Y37441D01*
X623771Y37481D01*
X623756Y37521D01*
X623746Y37561D01*
X623731Y37606D01*
X623726Y37646D01*
X623716Y37686D01*
X623711Y37731D01*
Y37771D01*
X623706Y37816D01*
X623711Y37861D01*
Y37901D01*
X623716Y37946D01*
X623726Y37986D01*
X623731Y38026D01*
X623746Y38071D01*
X623756Y38111D01*
X623771Y38151D01*
X623791Y38191D01*
X623806Y38226D01*
X623826Y38266D01*
X623926Y38406D01*
X623956Y38436D01*
Y41866D01*
X623966Y41991D01*
X624006Y42116D01*
X624066Y42226D01*
X624146Y42326D01*
X624246Y42406D01*
X624356Y42466D01*
X624481Y42506D01*
X624606Y42516D01*
X624731Y42506D01*
X624856Y42466D01*
X624966Y42406D01*
X625066Y42326D01*
X625146Y42226D01*
X625206Y42116D01*
X625246Y41991D01*
X625256Y41866D01*
Y38436D01*
X625286Y38406D01*
X625386Y38266D01*
X625406Y38226D01*
X625421Y38191D01*
X625441Y38151D01*
X625456Y38111D01*
X625466Y38071D01*
X625481Y38026D01*
X625486Y37986D01*
X625496Y37946D01*
X625501Y37901D01*
Y37861D01*
X625506Y37816D01*
X625501Y37771D01*
Y37731D01*
X625496Y37686D01*
X625486Y37646D01*
X625481Y37606D01*
X625466Y37561D01*
X625456Y37521D01*
X625441Y37481D01*
X625421Y37441D01*
X625406Y37406D01*
X625386Y37366D01*
X625286Y37226D01*
X625256Y37196D01*
Y36066D01*
X625246Y35941D01*
X625206Y35816D01*
X625146Y35706D01*
X625066Y35606D01*
X624966Y35526D01*
X624856Y35466D01*
X624731Y35426D01*
X624606Y35416D01*
G37*
G36*
G01X619882D02*
X619757Y35426D01*
X619632Y35466D01*
X619522Y35526D01*
X619422Y35606D01*
X619342Y35706D01*
X619282Y35816D01*
X619242Y35941D01*
X619232Y36066D01*
Y37196D01*
X619202Y37226D01*
X619102Y37366D01*
X619082Y37406D01*
X619067Y37441D01*
X619047Y37481D01*
X619032Y37521D01*
X619022Y37561D01*
X619007Y37606D01*
X619002Y37646D01*
X618992Y37686D01*
X618987Y37731D01*
Y37771D01*
X618982Y37816D01*
X618987Y37861D01*
Y37901D01*
X618992Y37946D01*
X619002Y37986D01*
X619007Y38026D01*
X619022Y38071D01*
X619032Y38111D01*
X619047Y38151D01*
X619067Y38191D01*
X619082Y38226D01*
X619102Y38266D01*
X619202Y38406D01*
X619232Y38436D01*
Y41866D01*
X619242Y41991D01*
X619282Y42116D01*
X619342Y42226D01*
X619422Y42326D01*
X619522Y42406D01*
X619632Y42466D01*
X619757Y42506D01*
X619882Y42516D01*
X620007Y42506D01*
X620132Y42466D01*
X620242Y42406D01*
X620342Y42326D01*
X620422Y42226D01*
X620482Y42116D01*
X620522Y41991D01*
X620532Y41866D01*
Y38436D01*
X620562Y38406D01*
X620662Y38266D01*
X620682Y38226D01*
X620697Y38191D01*
X620717Y38151D01*
X620732Y38111D01*
X620742Y38071D01*
X620757Y38026D01*
X620762Y37986D01*
X620772Y37946D01*
X620777Y37901D01*
Y37861D01*
X620782Y37816D01*
X620777Y37771D01*
Y37731D01*
X620772Y37686D01*
X620762Y37646D01*
X620757Y37606D01*
X620742Y37561D01*
X620732Y37521D01*
X620717Y37481D01*
X620697Y37441D01*
X620682Y37406D01*
X620662Y37366D01*
X620562Y37226D01*
X620532Y37196D01*
Y36066D01*
X620522Y35941D01*
X620482Y35816D01*
X620422Y35706D01*
X620342Y35606D01*
X620242Y35526D01*
X620132Y35466D01*
X620007Y35426D01*
X619882Y35416D01*
G37*
G36*
G01X648228D02*
X648103Y35426D01*
X647978Y35466D01*
X647868Y35526D01*
X647768Y35606D01*
X647688Y35706D01*
X647628Y35816D01*
X647588Y35941D01*
X647578Y36066D01*
Y37196D01*
X647548Y37226D01*
X647448Y37366D01*
X647428Y37406D01*
X647413Y37441D01*
X647393Y37481D01*
X647378Y37521D01*
X647368Y37561D01*
X647353Y37606D01*
X647348Y37646D01*
X647338Y37686D01*
X647333Y37731D01*
Y37771D01*
X647328Y37816D01*
X647333Y37861D01*
Y37901D01*
X647338Y37946D01*
X647348Y37986D01*
X647353Y38026D01*
X647368Y38071D01*
X647378Y38111D01*
X647393Y38151D01*
X647413Y38191D01*
X647428Y38226D01*
X647448Y38266D01*
X647548Y38406D01*
X647578Y38436D01*
Y41866D01*
X647588Y41991D01*
X647628Y42116D01*
X647688Y42226D01*
X647768Y42326D01*
X647868Y42406D01*
X647978Y42466D01*
X648103Y42506D01*
X648228Y42516D01*
X648353Y42506D01*
X648478Y42466D01*
X648588Y42406D01*
X648688Y42326D01*
X648768Y42226D01*
X648828Y42116D01*
X648868Y41991D01*
X648878Y41866D01*
Y38436D01*
X648908Y38406D01*
X649008Y38266D01*
X649028Y38226D01*
X649043Y38191D01*
X649063Y38151D01*
X649078Y38111D01*
X649088Y38071D01*
X649103Y38026D01*
X649108Y37986D01*
X649118Y37946D01*
X649123Y37901D01*
Y37861D01*
X649128Y37816D01*
X649123Y37771D01*
Y37731D01*
X649118Y37686D01*
X649108Y37646D01*
X649103Y37606D01*
X649088Y37561D01*
X649078Y37521D01*
X649063Y37481D01*
X649043Y37441D01*
X649028Y37406D01*
X649008Y37366D01*
X648908Y37226D01*
X648878Y37196D01*
Y36066D01*
X648868Y35941D01*
X648828Y35816D01*
X648768Y35706D01*
X648688Y35606D01*
X648588Y35526D01*
X648478Y35466D01*
X648353Y35426D01*
X648228Y35416D01*
G37*
G36*
G01X643504D02*
X643379Y35426D01*
X643254Y35466D01*
X643144Y35526D01*
X643044Y35606D01*
X642964Y35706D01*
X642904Y35816D01*
X642864Y35941D01*
X642854Y36066D01*
Y37196D01*
X642824Y37226D01*
X642724Y37366D01*
X642704Y37406D01*
X642689Y37441D01*
X642669Y37481D01*
X642654Y37521D01*
X642644Y37561D01*
X642629Y37606D01*
X642624Y37646D01*
X642614Y37686D01*
X642609Y37731D01*
Y37771D01*
X642604Y37816D01*
X642609Y37861D01*
Y37901D01*
X642614Y37946D01*
X642624Y37986D01*
X642629Y38026D01*
X642644Y38071D01*
X642654Y38111D01*
X642669Y38151D01*
X642689Y38191D01*
X642704Y38226D01*
X642724Y38266D01*
X642824Y38406D01*
X642854Y38436D01*
Y41866D01*
X642864Y41991D01*
X642904Y42116D01*
X642964Y42226D01*
X643044Y42326D01*
X643144Y42406D01*
X643254Y42466D01*
X643379Y42506D01*
X643504Y42516D01*
X643629Y42506D01*
X643754Y42466D01*
X643864Y42406D01*
X643964Y42326D01*
X644044Y42226D01*
X644104Y42116D01*
X644144Y41991D01*
X644154Y41866D01*
Y38436D01*
X644184Y38406D01*
X644284Y38266D01*
X644304Y38226D01*
X644319Y38191D01*
X644339Y38151D01*
X644354Y38111D01*
X644364Y38071D01*
X644379Y38026D01*
X644384Y37986D01*
X644394Y37946D01*
X644399Y37901D01*
Y37861D01*
X644404Y37816D01*
X644399Y37771D01*
Y37731D01*
X644394Y37686D01*
X644384Y37646D01*
X644379Y37606D01*
X644364Y37561D01*
X644354Y37521D01*
X644339Y37481D01*
X644319Y37441D01*
X644304Y37406D01*
X644284Y37366D01*
X644184Y37226D01*
X644154Y37196D01*
Y36066D01*
X644144Y35941D01*
X644104Y35816D01*
X644044Y35706D01*
X643964Y35606D01*
X643864Y35526D01*
X643754Y35466D01*
X643629Y35426D01*
X643504Y35416D01*
G37*
G36*
G01X638779D02*
X638654Y35426D01*
X638529Y35466D01*
X638419Y35526D01*
X638319Y35606D01*
X638239Y35706D01*
X638179Y35816D01*
X638139Y35941D01*
X638129Y36066D01*
Y37196D01*
X638099Y37226D01*
X637999Y37366D01*
X637979Y37406D01*
X637964Y37441D01*
X637944Y37481D01*
X637929Y37521D01*
X637919Y37561D01*
X637904Y37606D01*
X637899Y37646D01*
X637889Y37686D01*
X637884Y37731D01*
Y37771D01*
X637879Y37816D01*
X637884Y37861D01*
Y37901D01*
X637889Y37946D01*
X637899Y37986D01*
X637904Y38026D01*
X637919Y38071D01*
X637929Y38111D01*
X637944Y38151D01*
X637964Y38191D01*
X637979Y38226D01*
X637999Y38266D01*
X638099Y38406D01*
X638129Y38436D01*
Y41866D01*
X638139Y41991D01*
X638179Y42116D01*
X638239Y42226D01*
X638319Y42326D01*
X638419Y42406D01*
X638529Y42466D01*
X638654Y42506D01*
X638779Y42516D01*
X638904Y42506D01*
X639029Y42466D01*
X639139Y42406D01*
X639239Y42326D01*
X639319Y42226D01*
X639379Y42116D01*
X639419Y41991D01*
X639429Y41866D01*
Y38436D01*
X639459Y38406D01*
X639559Y38266D01*
X639579Y38226D01*
X639594Y38191D01*
X639614Y38151D01*
X639629Y38111D01*
X639639Y38071D01*
X639654Y38026D01*
X639659Y37986D01*
X639669Y37946D01*
X639674Y37901D01*
Y37861D01*
X639679Y37816D01*
X639674Y37771D01*
Y37731D01*
X639669Y37686D01*
X639659Y37646D01*
X639654Y37606D01*
X639639Y37561D01*
X639629Y37521D01*
X639614Y37481D01*
X639594Y37441D01*
X639579Y37406D01*
X639559Y37366D01*
X639459Y37226D01*
X639429Y37196D01*
Y36066D01*
X639419Y35941D01*
X639379Y35816D01*
X639319Y35706D01*
X639239Y35606D01*
X639139Y35526D01*
X639029Y35466D01*
X638904Y35426D01*
X638779Y35416D01*
G37*
G36*
G01X662401D02*
X662276Y35426D01*
X662151Y35466D01*
X662041Y35526D01*
X661941Y35606D01*
X661861Y35706D01*
X661801Y35816D01*
X661761Y35941D01*
X661751Y36066D01*
Y37196D01*
X661721Y37226D01*
X661621Y37366D01*
X661601Y37406D01*
X661586Y37441D01*
X661566Y37481D01*
X661551Y37521D01*
X661541Y37561D01*
X661526Y37606D01*
X661521Y37646D01*
X661511Y37686D01*
X661506Y37731D01*
Y37771D01*
X661501Y37816D01*
X661506Y37861D01*
Y37901D01*
X661511Y37946D01*
X661521Y37986D01*
X661526Y38026D01*
X661541Y38071D01*
X661551Y38111D01*
X661566Y38151D01*
X661586Y38191D01*
X661601Y38226D01*
X661621Y38266D01*
X661721Y38406D01*
X661751Y38436D01*
Y41866D01*
X661761Y41991D01*
X661801Y42116D01*
X661861Y42226D01*
X661941Y42326D01*
X662041Y42406D01*
X662151Y42466D01*
X662276Y42506D01*
X662401Y42516D01*
X662526Y42506D01*
X662651Y42466D01*
X662761Y42406D01*
X662861Y42326D01*
X662941Y42226D01*
X663001Y42116D01*
X663041Y41991D01*
X663051Y41866D01*
Y38436D01*
X663081Y38406D01*
X663181Y38266D01*
X663201Y38226D01*
X663216Y38191D01*
X663236Y38151D01*
X663251Y38111D01*
X663261Y38071D01*
X663276Y38026D01*
X663281Y37986D01*
X663291Y37946D01*
X663296Y37901D01*
Y37861D01*
X663301Y37816D01*
X663296Y37771D01*
Y37731D01*
X663291Y37686D01*
X663281Y37646D01*
X663276Y37606D01*
X663261Y37561D01*
X663251Y37521D01*
X663236Y37481D01*
X663216Y37441D01*
X663201Y37406D01*
X663181Y37366D01*
X663081Y37226D01*
X663051Y37196D01*
Y36066D01*
X663041Y35941D01*
X663001Y35816D01*
X662941Y35706D01*
X662861Y35606D01*
X662761Y35526D01*
X662651Y35466D01*
X662526Y35426D01*
X662401Y35416D01*
G37*
G36*
G01X657677D02*
X657552Y35426D01*
X657427Y35466D01*
X657317Y35526D01*
X657217Y35606D01*
X657137Y35706D01*
X657077Y35816D01*
X657037Y35941D01*
X657027Y36066D01*
Y37196D01*
X656997Y37226D01*
X656897Y37366D01*
X656877Y37406D01*
X656862Y37441D01*
X656842Y37481D01*
X656827Y37521D01*
X656817Y37561D01*
X656802Y37606D01*
X656797Y37646D01*
X656787Y37686D01*
X656782Y37731D01*
Y37771D01*
X656777Y37816D01*
X656782Y37861D01*
Y37901D01*
X656787Y37946D01*
X656797Y37986D01*
X656802Y38026D01*
X656817Y38071D01*
X656827Y38111D01*
X656842Y38151D01*
X656862Y38191D01*
X656877Y38226D01*
X656897Y38266D01*
X656997Y38406D01*
X657027Y38436D01*
Y41866D01*
X657037Y41991D01*
X657077Y42116D01*
X657137Y42226D01*
X657217Y42326D01*
X657317Y42406D01*
X657427Y42466D01*
X657552Y42506D01*
X657677Y42516D01*
X657802Y42506D01*
X657927Y42466D01*
X658037Y42406D01*
X658137Y42326D01*
X658217Y42226D01*
X658277Y42116D01*
X658317Y41991D01*
X658327Y41866D01*
Y38436D01*
X658357Y38406D01*
X658457Y38266D01*
X658477Y38226D01*
X658492Y38191D01*
X658512Y38151D01*
X658527Y38111D01*
X658537Y38071D01*
X658552Y38026D01*
X658557Y37986D01*
X658567Y37946D01*
X658572Y37901D01*
Y37861D01*
X658577Y37816D01*
X658572Y37771D01*
Y37731D01*
X658567Y37686D01*
X658557Y37646D01*
X658552Y37606D01*
X658537Y37561D01*
X658527Y37521D01*
X658512Y37481D01*
X658492Y37441D01*
X658477Y37406D01*
X658457Y37366D01*
X658357Y37226D01*
X658327Y37196D01*
Y36066D01*
X658317Y35941D01*
X658277Y35816D01*
X658217Y35706D01*
X658137Y35606D01*
X658037Y35526D01*
X657927Y35466D01*
X657802Y35426D01*
X657677Y35416D01*
G37*
G36*
G01X652952D02*
X652827Y35426D01*
X652702Y35466D01*
X652592Y35526D01*
X652492Y35606D01*
X652412Y35706D01*
X652352Y35816D01*
X652312Y35941D01*
X652302Y36066D01*
Y37196D01*
X652272Y37226D01*
X652172Y37366D01*
X652152Y37406D01*
X652137Y37441D01*
X652117Y37481D01*
X652102Y37521D01*
X652092Y37561D01*
X652077Y37606D01*
X652072Y37646D01*
X652062Y37686D01*
X652057Y37731D01*
Y37771D01*
X652052Y37816D01*
X652057Y37861D01*
Y37901D01*
X652062Y37946D01*
X652072Y37986D01*
X652077Y38026D01*
X652092Y38071D01*
X652102Y38111D01*
X652117Y38151D01*
X652137Y38191D01*
X652152Y38226D01*
X652172Y38266D01*
X652272Y38406D01*
X652302Y38436D01*
Y41866D01*
X652312Y41991D01*
X652352Y42116D01*
X652412Y42226D01*
X652492Y42326D01*
X652592Y42406D01*
X652702Y42466D01*
X652827Y42506D01*
X652952Y42516D01*
X653077Y42506D01*
X653202Y42466D01*
X653312Y42406D01*
X653412Y42326D01*
X653492Y42226D01*
X653552Y42116D01*
X653592Y41991D01*
X653602Y41866D01*
Y38436D01*
X653632Y38406D01*
X653732Y38266D01*
X653752Y38226D01*
X653767Y38191D01*
X653787Y38151D01*
X653802Y38111D01*
X653812Y38071D01*
X653827Y38026D01*
X653832Y37986D01*
X653842Y37946D01*
X653847Y37901D01*
Y37861D01*
X653852Y37816D01*
X653847Y37771D01*
Y37731D01*
X653842Y37686D01*
X653832Y37646D01*
X653827Y37606D01*
X653812Y37561D01*
X653802Y37521D01*
X653787Y37481D01*
X653767Y37441D01*
X653752Y37406D01*
X653732Y37366D01*
X653632Y37226D01*
X653602Y37196D01*
Y36066D01*
X653592Y35941D01*
X653552Y35816D01*
X653492Y35706D01*
X653412Y35606D01*
X653312Y35526D01*
X653202Y35466D01*
X653077Y35426D01*
X652952Y35416D01*
G37*
G36*
G01X676575D02*
X676450Y35426D01*
X676325Y35466D01*
X676215Y35526D01*
X676115Y35606D01*
X676035Y35706D01*
X675975Y35816D01*
X675935Y35941D01*
X675925Y36066D01*
Y37196D01*
X675895Y37226D01*
X675795Y37366D01*
X675775Y37406D01*
X675760Y37441D01*
X675740Y37481D01*
X675725Y37521D01*
X675715Y37561D01*
X675700Y37606D01*
X675695Y37646D01*
X675685Y37686D01*
X675680Y37731D01*
Y37771D01*
X675675Y37816D01*
X675680Y37861D01*
Y37901D01*
X675685Y37946D01*
X675695Y37986D01*
X675700Y38026D01*
X675715Y38071D01*
X675725Y38111D01*
X675740Y38151D01*
X675760Y38191D01*
X675775Y38226D01*
X675795Y38266D01*
X675895Y38406D01*
X675925Y38436D01*
Y41866D01*
X675935Y41991D01*
X675975Y42116D01*
X676035Y42226D01*
X676115Y42326D01*
X676215Y42406D01*
X676325Y42466D01*
X676450Y42506D01*
X676575Y42516D01*
X676700Y42506D01*
X676825Y42466D01*
X676935Y42406D01*
X677035Y42326D01*
X677115Y42226D01*
X677175Y42116D01*
X677215Y41991D01*
X677225Y41866D01*
Y38436D01*
X677255Y38406D01*
X677355Y38266D01*
X677375Y38226D01*
X677390Y38191D01*
X677410Y38151D01*
X677425Y38111D01*
X677435Y38071D01*
X677450Y38026D01*
X677455Y37986D01*
X677465Y37946D01*
X677470Y37901D01*
Y37861D01*
X677475Y37816D01*
X677470Y37771D01*
Y37731D01*
X677465Y37686D01*
X677455Y37646D01*
X677450Y37606D01*
X677435Y37561D01*
X677425Y37521D01*
X677410Y37481D01*
X677390Y37441D01*
X677375Y37406D01*
X677355Y37366D01*
X677255Y37226D01*
X677225Y37196D01*
Y36066D01*
X677215Y35941D01*
X677175Y35816D01*
X677115Y35706D01*
X677035Y35606D01*
X676935Y35526D01*
X676825Y35466D01*
X676700Y35426D01*
X676575Y35416D01*
G37*
G36*
G01X671850D02*
X671725Y35426D01*
X671600Y35466D01*
X671490Y35526D01*
X671390Y35606D01*
X671310Y35706D01*
X671250Y35816D01*
X671210Y35941D01*
X671200Y36066D01*
Y37196D01*
X671170Y37226D01*
X671070Y37366D01*
X671050Y37406D01*
X671035Y37441D01*
X671015Y37481D01*
X671000Y37521D01*
X670990Y37561D01*
X670975Y37606D01*
X670970Y37646D01*
X670960Y37686D01*
X670955Y37731D01*
Y37771D01*
X670950Y37816D01*
X670955Y37861D01*
Y37901D01*
X670960Y37946D01*
X670970Y37986D01*
X670975Y38026D01*
X670990Y38071D01*
X671000Y38111D01*
X671015Y38151D01*
X671035Y38191D01*
X671050Y38226D01*
X671070Y38266D01*
X671170Y38406D01*
X671200Y38436D01*
Y41866D01*
X671210Y41991D01*
X671250Y42116D01*
X671310Y42226D01*
X671390Y42326D01*
X671490Y42406D01*
X671600Y42466D01*
X671725Y42506D01*
X671850Y42516D01*
X671975Y42506D01*
X672100Y42466D01*
X672210Y42406D01*
X672310Y42326D01*
X672390Y42226D01*
X672450Y42116D01*
X672490Y41991D01*
X672500Y41866D01*
Y38436D01*
X672530Y38406D01*
X672630Y38266D01*
X672650Y38226D01*
X672665Y38191D01*
X672685Y38151D01*
X672700Y38111D01*
X672710Y38071D01*
X672725Y38026D01*
X672730Y37986D01*
X672740Y37946D01*
X672745Y37901D01*
Y37861D01*
X672750Y37816D01*
X672745Y37771D01*
Y37731D01*
X672740Y37686D01*
X672730Y37646D01*
X672725Y37606D01*
X672710Y37561D01*
X672700Y37521D01*
X672685Y37481D01*
X672665Y37441D01*
X672650Y37406D01*
X672630Y37366D01*
X672530Y37226D01*
X672500Y37196D01*
Y36066D01*
X672490Y35941D01*
X672450Y35816D01*
X672390Y35706D01*
X672310Y35606D01*
X672210Y35526D01*
X672100Y35466D01*
X671975Y35426D01*
X671850Y35416D01*
G37*
G36*
G01X667126D02*
X667001Y35426D01*
X666876Y35466D01*
X666766Y35526D01*
X666666Y35606D01*
X666586Y35706D01*
X666526Y35816D01*
X666486Y35941D01*
X666476Y36066D01*
Y37196D01*
X666446Y37226D01*
X666346Y37366D01*
X666326Y37406D01*
X666311Y37441D01*
X666291Y37481D01*
X666276Y37521D01*
X666266Y37561D01*
X666251Y37606D01*
X666246Y37646D01*
X666236Y37686D01*
X666231Y37731D01*
Y37771D01*
X666226Y37816D01*
X666231Y37861D01*
Y37901D01*
X666236Y37946D01*
X666246Y37986D01*
X666251Y38026D01*
X666266Y38071D01*
X666276Y38111D01*
X666291Y38151D01*
X666311Y38191D01*
X666326Y38226D01*
X666346Y38266D01*
X666446Y38406D01*
X666476Y38436D01*
Y41866D01*
X666486Y41991D01*
X666526Y42116D01*
X666586Y42226D01*
X666666Y42326D01*
X666766Y42406D01*
X666876Y42466D01*
X667001Y42506D01*
X667126Y42516D01*
X667251Y42506D01*
X667376Y42466D01*
X667486Y42406D01*
X667586Y42326D01*
X667666Y42226D01*
X667726Y42116D01*
X667766Y41991D01*
X667776Y41866D01*
Y38436D01*
X667806Y38406D01*
X667906Y38266D01*
X667926Y38226D01*
X667941Y38191D01*
X667961Y38151D01*
X667976Y38111D01*
X667986Y38071D01*
X668001Y38026D01*
X668006Y37986D01*
X668016Y37946D01*
X668021Y37901D01*
Y37861D01*
X668026Y37816D01*
X668021Y37771D01*
Y37731D01*
X668016Y37686D01*
X668006Y37646D01*
X668001Y37606D01*
X667986Y37561D01*
X667976Y37521D01*
X667961Y37481D01*
X667941Y37441D01*
X667926Y37406D01*
X667906Y37366D01*
X667806Y37226D01*
X667776Y37196D01*
Y36066D01*
X667766Y35941D01*
X667726Y35816D01*
X667666Y35706D01*
X667586Y35606D01*
X667486Y35526D01*
X667376Y35466D01*
X667251Y35426D01*
X667126Y35416D01*
G37*
G36*
G01X695472D02*
X695347Y35426D01*
X695222Y35466D01*
X695112Y35526D01*
X695012Y35606D01*
X694932Y35706D01*
X694872Y35816D01*
X694832Y35941D01*
X694822Y36066D01*
Y37196D01*
X694792Y37226D01*
X694692Y37366D01*
X694672Y37406D01*
X694657Y37441D01*
X694637Y37481D01*
X694622Y37521D01*
X694612Y37561D01*
X694597Y37606D01*
X694592Y37646D01*
X694582Y37686D01*
X694577Y37731D01*
Y37771D01*
X694572Y37816D01*
X694577Y37861D01*
Y37901D01*
X694582Y37946D01*
X694592Y37986D01*
X694597Y38026D01*
X694612Y38071D01*
X694622Y38111D01*
X694637Y38151D01*
X694657Y38191D01*
X694672Y38226D01*
X694692Y38266D01*
X694792Y38406D01*
X694822Y38436D01*
Y41866D01*
X694832Y41991D01*
X694872Y42116D01*
X694932Y42226D01*
X695012Y42326D01*
X695112Y42406D01*
X695222Y42466D01*
X695347Y42506D01*
X695472Y42516D01*
X695597Y42506D01*
X695722Y42466D01*
X695832Y42406D01*
X695932Y42326D01*
X696012Y42226D01*
X696072Y42116D01*
X696112Y41991D01*
X696122Y41866D01*
Y38436D01*
X696152Y38406D01*
X696252Y38266D01*
X696272Y38226D01*
X696287Y38191D01*
X696307Y38151D01*
X696322Y38111D01*
X696332Y38071D01*
X696347Y38026D01*
X696352Y37986D01*
X696362Y37946D01*
X696367Y37901D01*
Y37861D01*
X696372Y37816D01*
X696367Y37771D01*
Y37731D01*
X696362Y37686D01*
X696352Y37646D01*
X696347Y37606D01*
X696332Y37561D01*
X696322Y37521D01*
X696307Y37481D01*
X696287Y37441D01*
X696272Y37406D01*
X696252Y37366D01*
X696152Y37226D01*
X696122Y37196D01*
Y36066D01*
X696112Y35941D01*
X696072Y35816D01*
X696012Y35706D01*
X695932Y35606D01*
X695832Y35526D01*
X695722Y35466D01*
X695597Y35426D01*
X695472Y35416D01*
G37*
G36*
G01X690748D02*
X690623Y35426D01*
X690498Y35466D01*
X690388Y35526D01*
X690288Y35606D01*
X690208Y35706D01*
X690148Y35816D01*
X690108Y35941D01*
X690098Y36066D01*
Y37196D01*
X690068Y37226D01*
X689968Y37366D01*
X689948Y37406D01*
X689933Y37441D01*
X689913Y37481D01*
X689898Y37521D01*
X689888Y37561D01*
X689873Y37606D01*
X689868Y37646D01*
X689858Y37686D01*
X689853Y37731D01*
Y37771D01*
X689848Y37816D01*
X689853Y37861D01*
Y37901D01*
X689858Y37946D01*
X689868Y37986D01*
X689873Y38026D01*
X689888Y38071D01*
X689898Y38111D01*
X689913Y38151D01*
X689933Y38191D01*
X689948Y38226D01*
X689968Y38266D01*
X690068Y38406D01*
X690098Y38436D01*
Y41866D01*
X690108Y41991D01*
X690148Y42116D01*
X690208Y42226D01*
X690288Y42326D01*
X690388Y42406D01*
X690498Y42466D01*
X690623Y42506D01*
X690748Y42516D01*
X690873Y42506D01*
X690998Y42466D01*
X691108Y42406D01*
X691208Y42326D01*
X691288Y42226D01*
X691348Y42116D01*
X691388Y41991D01*
X691398Y41866D01*
Y38436D01*
X691428Y38406D01*
X691528Y38266D01*
X691548Y38226D01*
X691563Y38191D01*
X691583Y38151D01*
X691598Y38111D01*
X691608Y38071D01*
X691623Y38026D01*
X691628Y37986D01*
X691638Y37946D01*
X691643Y37901D01*
Y37861D01*
X691648Y37816D01*
X691643Y37771D01*
Y37731D01*
X691638Y37686D01*
X691628Y37646D01*
X691623Y37606D01*
X691608Y37561D01*
X691598Y37521D01*
X691583Y37481D01*
X691563Y37441D01*
X691548Y37406D01*
X691528Y37366D01*
X691428Y37226D01*
X691398Y37196D01*
Y36066D01*
X691388Y35941D01*
X691348Y35816D01*
X691288Y35706D01*
X691208Y35606D01*
X691108Y35526D01*
X690998Y35466D01*
X690873Y35426D01*
X690748Y35416D01*
G37*
G36*
G01X686023D02*
X685898Y35426D01*
X685773Y35466D01*
X685663Y35526D01*
X685563Y35606D01*
X685483Y35706D01*
X685423Y35816D01*
X685383Y35941D01*
X685373Y36066D01*
Y37196D01*
X685343Y37226D01*
X685243Y37366D01*
X685223Y37406D01*
X685208Y37441D01*
X685188Y37481D01*
X685173Y37521D01*
X685163Y37561D01*
X685148Y37606D01*
X685143Y37646D01*
X685133Y37686D01*
X685128Y37731D01*
Y37771D01*
X685123Y37816D01*
X685128Y37861D01*
Y37901D01*
X685133Y37946D01*
X685143Y37986D01*
X685148Y38026D01*
X685163Y38071D01*
X685173Y38111D01*
X685188Y38151D01*
X685208Y38191D01*
X685223Y38226D01*
X685243Y38266D01*
X685343Y38406D01*
X685373Y38436D01*
Y41866D01*
X685383Y41991D01*
X685423Y42116D01*
X685483Y42226D01*
X685563Y42326D01*
X685663Y42406D01*
X685773Y42466D01*
X685898Y42506D01*
X686023Y42516D01*
X686148Y42506D01*
X686273Y42466D01*
X686383Y42406D01*
X686483Y42326D01*
X686563Y42226D01*
X686623Y42116D01*
X686663Y41991D01*
X686673Y41866D01*
Y38436D01*
X686703Y38406D01*
X686803Y38266D01*
X686823Y38226D01*
X686838Y38191D01*
X686858Y38151D01*
X686873Y38111D01*
X686883Y38071D01*
X686898Y38026D01*
X686903Y37986D01*
X686913Y37946D01*
X686918Y37901D01*
Y37861D01*
X686923Y37816D01*
X686918Y37771D01*
Y37731D01*
X686913Y37686D01*
X686903Y37646D01*
X686898Y37606D01*
X686883Y37561D01*
X686873Y37521D01*
X686858Y37481D01*
X686838Y37441D01*
X686823Y37406D01*
X686803Y37366D01*
X686703Y37226D01*
X686673Y37196D01*
Y36066D01*
X686663Y35941D01*
X686623Y35816D01*
X686563Y35706D01*
X686483Y35606D01*
X686383Y35526D01*
X686273Y35466D01*
X686148Y35426D01*
X686023Y35416D01*
G37*
G36*
G01X681299D02*
X681174Y35426D01*
X681049Y35466D01*
X680939Y35526D01*
X680839Y35606D01*
X680759Y35706D01*
X680699Y35816D01*
X680659Y35941D01*
X680649Y36066D01*
Y37196D01*
X680619Y37226D01*
X680519Y37366D01*
X680499Y37406D01*
X680484Y37441D01*
X680464Y37481D01*
X680449Y37521D01*
X680439Y37561D01*
X680424Y37606D01*
X680419Y37646D01*
X680409Y37686D01*
X680404Y37731D01*
Y37771D01*
X680399Y37816D01*
X680404Y37861D01*
Y37901D01*
X680409Y37946D01*
X680419Y37986D01*
X680424Y38026D01*
X680439Y38071D01*
X680449Y38111D01*
X680464Y38151D01*
X680484Y38191D01*
X680499Y38226D01*
X680519Y38266D01*
X680619Y38406D01*
X680649Y38436D01*
Y41866D01*
X680659Y41991D01*
X680699Y42116D01*
X680759Y42226D01*
X680839Y42326D01*
X680939Y42406D01*
X681049Y42466D01*
X681174Y42506D01*
X681299Y42516D01*
X681424Y42506D01*
X681549Y42466D01*
X681659Y42406D01*
X681759Y42326D01*
X681839Y42226D01*
X681899Y42116D01*
X681939Y41991D01*
X681949Y41866D01*
Y38436D01*
X681979Y38406D01*
X682079Y38266D01*
X682099Y38226D01*
X682114Y38191D01*
X682134Y38151D01*
X682149Y38111D01*
X682159Y38071D01*
X682174Y38026D01*
X682179Y37986D01*
X682189Y37946D01*
X682194Y37901D01*
Y37861D01*
X682199Y37816D01*
X682194Y37771D01*
Y37731D01*
X682189Y37686D01*
X682179Y37646D01*
X682174Y37606D01*
X682159Y37561D01*
X682149Y37521D01*
X682134Y37481D01*
X682114Y37441D01*
X682099Y37406D01*
X682079Y37366D01*
X681979Y37226D01*
X681949Y37196D01*
Y36066D01*
X681939Y35941D01*
X681899Y35816D01*
X681839Y35706D01*
X681759Y35606D01*
X681659Y35526D01*
X681549Y35466D01*
X681424Y35426D01*
X681299Y35416D01*
G37*
G36*
G01X709645D02*
X709520Y35426D01*
X709395Y35466D01*
X709285Y35526D01*
X709185Y35606D01*
X709105Y35706D01*
X709045Y35816D01*
X709005Y35941D01*
X708995Y36066D01*
Y37196D01*
X708965Y37226D01*
X708865Y37366D01*
X708845Y37406D01*
X708830Y37441D01*
X708810Y37481D01*
X708795Y37521D01*
X708785Y37561D01*
X708770Y37606D01*
X708765Y37646D01*
X708755Y37686D01*
X708750Y37731D01*
Y37771D01*
X708745Y37816D01*
X708750Y37861D01*
Y37901D01*
X708755Y37946D01*
X708765Y37986D01*
X708770Y38026D01*
X708785Y38071D01*
X708795Y38111D01*
X708810Y38151D01*
X708830Y38191D01*
X708845Y38226D01*
X708865Y38266D01*
X708965Y38406D01*
X708995Y38436D01*
Y41866D01*
X709005Y41991D01*
X709045Y42116D01*
X709105Y42226D01*
X709185Y42326D01*
X709285Y42406D01*
X709395Y42466D01*
X709520Y42506D01*
X709645Y42516D01*
X709770Y42506D01*
X709895Y42466D01*
X710005Y42406D01*
X710105Y42326D01*
X710185Y42226D01*
X710245Y42116D01*
X710285Y41991D01*
X710295Y41866D01*
Y38436D01*
X710325Y38406D01*
X710425Y38266D01*
X710445Y38226D01*
X710460Y38191D01*
X710480Y38151D01*
X710495Y38111D01*
X710505Y38071D01*
X710520Y38026D01*
X710525Y37986D01*
X710535Y37946D01*
X710540Y37901D01*
Y37861D01*
X710545Y37816D01*
X710540Y37771D01*
Y37731D01*
X710535Y37686D01*
X710525Y37646D01*
X710520Y37606D01*
X710505Y37561D01*
X710495Y37521D01*
X710480Y37481D01*
X710460Y37441D01*
X710445Y37406D01*
X710425Y37366D01*
X710325Y37226D01*
X710295Y37196D01*
Y36066D01*
X710285Y35941D01*
X710245Y35816D01*
X710185Y35706D01*
X710105Y35606D01*
X710005Y35526D01*
X709895Y35466D01*
X709770Y35426D01*
X709645Y35416D01*
G37*
G36*
G01X704921D02*
X704796Y35426D01*
X704671Y35466D01*
X704561Y35526D01*
X704461Y35606D01*
X704381Y35706D01*
X704321Y35816D01*
X704281Y35941D01*
X704271Y36066D01*
Y37196D01*
X704241Y37226D01*
X704141Y37366D01*
X704121Y37406D01*
X704106Y37441D01*
X704086Y37481D01*
X704071Y37521D01*
X704061Y37561D01*
X704046Y37606D01*
X704041Y37646D01*
X704031Y37686D01*
X704026Y37731D01*
Y37771D01*
X704021Y37816D01*
X704026Y37861D01*
Y37901D01*
X704031Y37946D01*
X704041Y37986D01*
X704046Y38026D01*
X704061Y38071D01*
X704071Y38111D01*
X704086Y38151D01*
X704106Y38191D01*
X704121Y38226D01*
X704141Y38266D01*
X704241Y38406D01*
X704271Y38436D01*
Y41866D01*
X704281Y41991D01*
X704321Y42116D01*
X704381Y42226D01*
X704461Y42326D01*
X704561Y42406D01*
X704671Y42466D01*
X704796Y42506D01*
X704921Y42516D01*
X705046Y42506D01*
X705171Y42466D01*
X705281Y42406D01*
X705381Y42326D01*
X705461Y42226D01*
X705521Y42116D01*
X705561Y41991D01*
X705571Y41866D01*
Y38436D01*
X705601Y38406D01*
X705701Y38266D01*
X705721Y38226D01*
X705736Y38191D01*
X705756Y38151D01*
X705771Y38111D01*
X705781Y38071D01*
X705796Y38026D01*
X705801Y37986D01*
X705811Y37946D01*
X705816Y37901D01*
Y37861D01*
X705821Y37816D01*
X705816Y37771D01*
Y37731D01*
X705811Y37686D01*
X705801Y37646D01*
X705796Y37606D01*
X705781Y37561D01*
X705771Y37521D01*
X705756Y37481D01*
X705736Y37441D01*
X705721Y37406D01*
X705701Y37366D01*
X705601Y37226D01*
X705571Y37196D01*
Y36066D01*
X705561Y35941D01*
X705521Y35816D01*
X705461Y35706D01*
X705381Y35606D01*
X705281Y35526D01*
X705171Y35466D01*
X705046Y35426D01*
X704921Y35416D01*
G37*
G36*
G01X700197D02*
X700072Y35426D01*
X699947Y35466D01*
X699837Y35526D01*
X699737Y35606D01*
X699657Y35706D01*
X699597Y35816D01*
X699557Y35941D01*
X699547Y36066D01*
Y37196D01*
X699517Y37226D01*
X699417Y37366D01*
X699397Y37406D01*
X699382Y37441D01*
X699362Y37481D01*
X699347Y37521D01*
X699337Y37561D01*
X699322Y37606D01*
X699317Y37646D01*
X699307Y37686D01*
X699302Y37731D01*
Y37771D01*
X699297Y37816D01*
X699302Y37861D01*
Y37901D01*
X699307Y37946D01*
X699317Y37986D01*
X699322Y38026D01*
X699337Y38071D01*
X699347Y38111D01*
X699362Y38151D01*
X699382Y38191D01*
X699397Y38226D01*
X699417Y38266D01*
X699517Y38406D01*
X699547Y38436D01*
Y41866D01*
X699557Y41991D01*
X699597Y42116D01*
X699657Y42226D01*
X699737Y42326D01*
X699837Y42406D01*
X699947Y42466D01*
X700072Y42506D01*
X700197Y42516D01*
X700322Y42506D01*
X700447Y42466D01*
X700557Y42406D01*
X700657Y42326D01*
X700737Y42226D01*
X700797Y42116D01*
X700837Y41991D01*
X700847Y41866D01*
Y38436D01*
X700877Y38406D01*
X700977Y38266D01*
X700997Y38226D01*
X701012Y38191D01*
X701032Y38151D01*
X701047Y38111D01*
X701057Y38071D01*
X701072Y38026D01*
X701077Y37986D01*
X701087Y37946D01*
X701092Y37901D01*
Y37861D01*
X701097Y37816D01*
X701092Y37771D01*
Y37731D01*
X701087Y37686D01*
X701077Y37646D01*
X701072Y37606D01*
X701057Y37561D01*
X701047Y37521D01*
X701032Y37481D01*
X701012Y37441D01*
X700997Y37406D01*
X700977Y37366D01*
X700877Y37226D01*
X700847Y37196D01*
Y36066D01*
X700837Y35941D01*
X700797Y35816D01*
X700737Y35706D01*
X700657Y35606D01*
X700557Y35526D01*
X700447Y35466D01*
X700322Y35426D01*
X700197Y35416D01*
G37*
G36*
G01X723819D02*
X723694Y35426D01*
X723569Y35466D01*
X723459Y35526D01*
X723359Y35606D01*
X723279Y35706D01*
X723219Y35816D01*
X723179Y35941D01*
X723169Y36066D01*
Y37196D01*
X723139Y37226D01*
X723039Y37366D01*
X723019Y37406D01*
X723004Y37441D01*
X722984Y37481D01*
X722969Y37521D01*
X722959Y37561D01*
X722944Y37606D01*
X722939Y37646D01*
X722929Y37686D01*
X722924Y37731D01*
Y37771D01*
X722919Y37816D01*
X722924Y37861D01*
Y37901D01*
X722929Y37946D01*
X722939Y37986D01*
X722944Y38026D01*
X722959Y38071D01*
X722969Y38111D01*
X722984Y38151D01*
X723004Y38191D01*
X723019Y38226D01*
X723039Y38266D01*
X723139Y38406D01*
X723169Y38436D01*
Y41866D01*
X723179Y41991D01*
X723219Y42116D01*
X723279Y42226D01*
X723359Y42326D01*
X723459Y42406D01*
X723569Y42466D01*
X723694Y42506D01*
X723819Y42516D01*
X723944Y42506D01*
X724069Y42466D01*
X724179Y42406D01*
X724279Y42326D01*
X724359Y42226D01*
X724419Y42116D01*
X724459Y41991D01*
X724469Y41866D01*
Y38436D01*
X724499Y38406D01*
X724599Y38266D01*
X724619Y38226D01*
X724634Y38191D01*
X724654Y38151D01*
X724669Y38111D01*
X724679Y38071D01*
X724694Y38026D01*
X724699Y37986D01*
X724709Y37946D01*
X724714Y37901D01*
Y37861D01*
X724719Y37816D01*
X724714Y37771D01*
Y37731D01*
X724709Y37686D01*
X724699Y37646D01*
X724694Y37606D01*
X724679Y37561D01*
X724669Y37521D01*
X724654Y37481D01*
X724634Y37441D01*
X724619Y37406D01*
X724599Y37366D01*
X724499Y37226D01*
X724469Y37196D01*
Y36066D01*
X724459Y35941D01*
X724419Y35816D01*
X724359Y35706D01*
X724279Y35606D01*
X724179Y35526D01*
X724069Y35466D01*
X723944Y35426D01*
X723819Y35416D01*
G37*
G36*
G01X719094D02*
X718969Y35426D01*
X718844Y35466D01*
X718734Y35526D01*
X718634Y35606D01*
X718554Y35706D01*
X718494Y35816D01*
X718454Y35941D01*
X718444Y36066D01*
Y37196D01*
X718414Y37226D01*
X718314Y37366D01*
X718294Y37406D01*
X718279Y37441D01*
X718259Y37481D01*
X718244Y37521D01*
X718234Y37561D01*
X718219Y37606D01*
X718214Y37646D01*
X718204Y37686D01*
X718199Y37731D01*
Y37771D01*
X718194Y37816D01*
X718199Y37861D01*
Y37901D01*
X718204Y37946D01*
X718214Y37986D01*
X718219Y38026D01*
X718234Y38071D01*
X718244Y38111D01*
X718259Y38151D01*
X718279Y38191D01*
X718294Y38226D01*
X718314Y38266D01*
X718414Y38406D01*
X718444Y38436D01*
Y41866D01*
X718454Y41991D01*
X718494Y42116D01*
X718554Y42226D01*
X718634Y42326D01*
X718734Y42406D01*
X718844Y42466D01*
X718969Y42506D01*
X719094Y42516D01*
X719219Y42506D01*
X719344Y42466D01*
X719454Y42406D01*
X719554Y42326D01*
X719634Y42226D01*
X719694Y42116D01*
X719734Y41991D01*
X719744Y41866D01*
Y38436D01*
X719774Y38406D01*
X719874Y38266D01*
X719894Y38226D01*
X719909Y38191D01*
X719929Y38151D01*
X719944Y38111D01*
X719954Y38071D01*
X719969Y38026D01*
X719974Y37986D01*
X719984Y37946D01*
X719989Y37901D01*
Y37861D01*
X719994Y37816D01*
X719989Y37771D01*
Y37731D01*
X719984Y37686D01*
X719974Y37646D01*
X719969Y37606D01*
X719954Y37561D01*
X719944Y37521D01*
X719929Y37481D01*
X719909Y37441D01*
X719894Y37406D01*
X719874Y37366D01*
X719774Y37226D01*
X719744Y37196D01*
Y36066D01*
X719734Y35941D01*
X719694Y35816D01*
X719634Y35706D01*
X719554Y35606D01*
X719454Y35526D01*
X719344Y35466D01*
X719219Y35426D01*
X719094Y35416D01*
G37*
G36*
G01X714370D02*
X714245Y35426D01*
X714120Y35466D01*
X714010Y35526D01*
X713910Y35606D01*
X713830Y35706D01*
X713770Y35816D01*
X713730Y35941D01*
X713720Y36066D01*
Y37196D01*
X713690Y37226D01*
X713590Y37366D01*
X713570Y37406D01*
X713555Y37441D01*
X713535Y37481D01*
X713520Y37521D01*
X713510Y37561D01*
X713495Y37606D01*
X713490Y37646D01*
X713480Y37686D01*
X713475Y37731D01*
Y37771D01*
X713470Y37816D01*
X713475Y37861D01*
Y37901D01*
X713480Y37946D01*
X713490Y37986D01*
X713495Y38026D01*
X713510Y38071D01*
X713520Y38111D01*
X713535Y38151D01*
X713555Y38191D01*
X713570Y38226D01*
X713590Y38266D01*
X713690Y38406D01*
X713720Y38436D01*
Y41866D01*
X713730Y41991D01*
X713770Y42116D01*
X713830Y42226D01*
X713910Y42326D01*
X714010Y42406D01*
X714120Y42466D01*
X714245Y42506D01*
X714370Y42516D01*
X714495Y42506D01*
X714620Y42466D01*
X714730Y42406D01*
X714830Y42326D01*
X714910Y42226D01*
X714970Y42116D01*
X715010Y41991D01*
X715020Y41866D01*
Y38436D01*
X715050Y38406D01*
X715150Y38266D01*
X715170Y38226D01*
X715185Y38191D01*
X715205Y38151D01*
X715220Y38111D01*
X715230Y38071D01*
X715245Y38026D01*
X715250Y37986D01*
X715260Y37946D01*
X715265Y37901D01*
Y37861D01*
X715270Y37816D01*
X715265Y37771D01*
Y37731D01*
X715260Y37686D01*
X715250Y37646D01*
X715245Y37606D01*
X715230Y37561D01*
X715220Y37521D01*
X715205Y37481D01*
X715185Y37441D01*
X715170Y37406D01*
X715150Y37366D01*
X715050Y37226D01*
X715020Y37196D01*
Y36066D01*
X715010Y35941D01*
X714970Y35816D01*
X714910Y35706D01*
X714830Y35606D01*
X714730Y35526D01*
X714620Y35466D01*
X714495Y35426D01*
X714370Y35416D01*
G37*
G36*
G01X737992D02*
X737867Y35426D01*
X737742Y35466D01*
X737632Y35526D01*
X737532Y35606D01*
X737452Y35706D01*
X737392Y35816D01*
X737352Y35941D01*
X737342Y36066D01*
Y37196D01*
X737312Y37226D01*
X737212Y37366D01*
X737192Y37406D01*
X737177Y37441D01*
X737157Y37481D01*
X737142Y37521D01*
X737132Y37561D01*
X737117Y37606D01*
X737112Y37646D01*
X737102Y37686D01*
X737097Y37731D01*
Y37771D01*
X737092Y37816D01*
X737097Y37861D01*
Y37901D01*
X737102Y37946D01*
X737112Y37986D01*
X737117Y38026D01*
X737132Y38071D01*
X737142Y38111D01*
X737157Y38151D01*
X737177Y38191D01*
X737192Y38226D01*
X737212Y38266D01*
X737312Y38406D01*
X737342Y38436D01*
Y41866D01*
X737352Y41991D01*
X737392Y42116D01*
X737452Y42226D01*
X737532Y42326D01*
X737632Y42406D01*
X737742Y42466D01*
X737867Y42506D01*
X737992Y42516D01*
X738117Y42506D01*
X738242Y42466D01*
X738352Y42406D01*
X738452Y42326D01*
X738532Y42226D01*
X738592Y42116D01*
X738632Y41991D01*
X738642Y41866D01*
Y38436D01*
X738672Y38406D01*
X738772Y38266D01*
X738792Y38226D01*
X738807Y38191D01*
X738827Y38151D01*
X738842Y38111D01*
X738852Y38071D01*
X738867Y38026D01*
X738872Y37986D01*
X738882Y37946D01*
X738887Y37901D01*
Y37861D01*
X738892Y37816D01*
X738887Y37771D01*
Y37731D01*
X738882Y37686D01*
X738872Y37646D01*
X738867Y37606D01*
X738852Y37561D01*
X738842Y37521D01*
X738827Y37481D01*
X738807Y37441D01*
X738792Y37406D01*
X738772Y37366D01*
X738672Y37226D01*
X738642Y37196D01*
Y36066D01*
X738632Y35941D01*
X738592Y35816D01*
X738532Y35706D01*
X738452Y35606D01*
X738352Y35526D01*
X738242Y35466D01*
X738117Y35426D01*
X737992Y35416D01*
G37*
G36*
G01X733267D02*
X733142Y35426D01*
X733017Y35466D01*
X732907Y35526D01*
X732807Y35606D01*
X732727Y35706D01*
X732667Y35816D01*
X732627Y35941D01*
X732617Y36066D01*
Y37196D01*
X732587Y37226D01*
X732487Y37366D01*
X732467Y37406D01*
X732452Y37441D01*
X732432Y37481D01*
X732417Y37521D01*
X732407Y37561D01*
X732392Y37606D01*
X732387Y37646D01*
X732377Y37686D01*
X732372Y37731D01*
Y37771D01*
X732367Y37816D01*
X732372Y37861D01*
Y37901D01*
X732377Y37946D01*
X732387Y37986D01*
X732392Y38026D01*
X732407Y38071D01*
X732417Y38111D01*
X732432Y38151D01*
X732452Y38191D01*
X732467Y38226D01*
X732487Y38266D01*
X732587Y38406D01*
X732617Y38436D01*
Y41866D01*
X732627Y41991D01*
X732667Y42116D01*
X732727Y42226D01*
X732807Y42326D01*
X732907Y42406D01*
X733017Y42466D01*
X733142Y42506D01*
X733267Y42516D01*
X733392Y42506D01*
X733517Y42466D01*
X733627Y42406D01*
X733727Y42326D01*
X733807Y42226D01*
X733867Y42116D01*
X733907Y41991D01*
X733917Y41866D01*
Y38436D01*
X733947Y38406D01*
X734047Y38266D01*
X734067Y38226D01*
X734082Y38191D01*
X734102Y38151D01*
X734117Y38111D01*
X734127Y38071D01*
X734142Y38026D01*
X734147Y37986D01*
X734157Y37946D01*
X734162Y37901D01*
Y37861D01*
X734167Y37816D01*
X734162Y37771D01*
Y37731D01*
X734157Y37686D01*
X734147Y37646D01*
X734142Y37606D01*
X734127Y37561D01*
X734117Y37521D01*
X734102Y37481D01*
X734082Y37441D01*
X734067Y37406D01*
X734047Y37366D01*
X733947Y37226D01*
X733917Y37196D01*
Y36066D01*
X733907Y35941D01*
X733867Y35816D01*
X733807Y35706D01*
X733727Y35606D01*
X733627Y35526D01*
X733517Y35466D01*
X733392Y35426D01*
X733267Y35416D01*
G37*
G36*
G01X728543D02*
X728418Y35426D01*
X728293Y35466D01*
X728183Y35526D01*
X728083Y35606D01*
X728003Y35706D01*
X727943Y35816D01*
X727903Y35941D01*
X727893Y36066D01*
Y37196D01*
X727863Y37226D01*
X727763Y37366D01*
X727743Y37406D01*
X727728Y37441D01*
X727708Y37481D01*
X727693Y37521D01*
X727683Y37561D01*
X727668Y37606D01*
X727663Y37646D01*
X727653Y37686D01*
X727648Y37731D01*
Y37771D01*
X727643Y37816D01*
X727648Y37861D01*
Y37901D01*
X727653Y37946D01*
X727663Y37986D01*
X727668Y38026D01*
X727683Y38071D01*
X727693Y38111D01*
X727708Y38151D01*
X727728Y38191D01*
X727743Y38226D01*
X727763Y38266D01*
X727863Y38406D01*
X727893Y38436D01*
Y41866D01*
X727903Y41991D01*
X727943Y42116D01*
X728003Y42226D01*
X728083Y42326D01*
X728183Y42406D01*
X728293Y42466D01*
X728418Y42506D01*
X728543Y42516D01*
X728668Y42506D01*
X728793Y42466D01*
X728903Y42406D01*
X729003Y42326D01*
X729083Y42226D01*
X729143Y42116D01*
X729183Y41991D01*
X729193Y41866D01*
Y38436D01*
X729223Y38406D01*
X729323Y38266D01*
X729343Y38226D01*
X729358Y38191D01*
X729378Y38151D01*
X729393Y38111D01*
X729403Y38071D01*
X729418Y38026D01*
X729423Y37986D01*
X729433Y37946D01*
X729438Y37901D01*
Y37861D01*
X729443Y37816D01*
X729438Y37771D01*
Y37731D01*
X729433Y37686D01*
X729423Y37646D01*
X729418Y37606D01*
X729403Y37561D01*
X729393Y37521D01*
X729378Y37481D01*
X729358Y37441D01*
X729343Y37406D01*
X729323Y37366D01*
X729223Y37226D01*
X729193Y37196D01*
Y36066D01*
X729183Y35941D01*
X729143Y35816D01*
X729083Y35706D01*
X729003Y35606D01*
X728903Y35526D01*
X728793Y35466D01*
X728668Y35426D01*
X728543Y35416D01*
G37*
G36*
G01X752165D02*
X752040Y35426D01*
X751915Y35466D01*
X751805Y35526D01*
X751705Y35606D01*
X751625Y35706D01*
X751565Y35816D01*
X751525Y35941D01*
X751515Y36066D01*
Y37196D01*
X751485Y37226D01*
X751385Y37366D01*
X751365Y37406D01*
X751350Y37441D01*
X751330Y37481D01*
X751315Y37521D01*
X751305Y37561D01*
X751290Y37606D01*
X751285Y37646D01*
X751275Y37686D01*
X751270Y37731D01*
Y37771D01*
X751265Y37816D01*
X751270Y37861D01*
Y37901D01*
X751275Y37946D01*
X751285Y37986D01*
X751290Y38026D01*
X751305Y38071D01*
X751315Y38111D01*
X751330Y38151D01*
X751350Y38191D01*
X751365Y38226D01*
X751385Y38266D01*
X751485Y38406D01*
X751515Y38436D01*
Y41866D01*
X751525Y41991D01*
X751565Y42116D01*
X751625Y42226D01*
X751705Y42326D01*
X751805Y42406D01*
X751915Y42466D01*
X752040Y42506D01*
X752165Y42516D01*
X752290Y42506D01*
X752415Y42466D01*
X752525Y42406D01*
X752625Y42326D01*
X752705Y42226D01*
X752765Y42116D01*
X752805Y41991D01*
X752815Y41866D01*
Y38436D01*
X752845Y38406D01*
X752945Y38266D01*
X752965Y38226D01*
X752980Y38191D01*
X753000Y38151D01*
X753015Y38111D01*
X753025Y38071D01*
X753040Y38026D01*
X753045Y37986D01*
X753055Y37946D01*
X753060Y37901D01*
Y37861D01*
X753065Y37816D01*
X753060Y37771D01*
Y37731D01*
X753055Y37686D01*
X753045Y37646D01*
X753040Y37606D01*
X753025Y37561D01*
X753015Y37521D01*
X753000Y37481D01*
X752980Y37441D01*
X752965Y37406D01*
X752945Y37366D01*
X752845Y37226D01*
X752815Y37196D01*
Y36066D01*
X752805Y35941D01*
X752765Y35816D01*
X752705Y35706D01*
X752625Y35606D01*
X752525Y35526D01*
X752415Y35466D01*
X752290Y35426D01*
X752165Y35416D01*
G37*
G36*
G01X747441D02*
X747316Y35426D01*
X747191Y35466D01*
X747081Y35526D01*
X746981Y35606D01*
X746901Y35706D01*
X746841Y35816D01*
X746801Y35941D01*
X746791Y36066D01*
Y37196D01*
X746761Y37226D01*
X746661Y37366D01*
X746641Y37406D01*
X746626Y37441D01*
X746606Y37481D01*
X746591Y37521D01*
X746581Y37561D01*
X746566Y37606D01*
X746561Y37646D01*
X746551Y37686D01*
X746546Y37731D01*
Y37771D01*
X746541Y37816D01*
X746546Y37861D01*
Y37901D01*
X746551Y37946D01*
X746561Y37986D01*
X746566Y38026D01*
X746581Y38071D01*
X746591Y38111D01*
X746606Y38151D01*
X746626Y38191D01*
X746641Y38226D01*
X746661Y38266D01*
X746761Y38406D01*
X746791Y38436D01*
Y41866D01*
X746801Y41991D01*
X746841Y42116D01*
X746901Y42226D01*
X746981Y42326D01*
X747081Y42406D01*
X747191Y42466D01*
X747316Y42506D01*
X747441Y42516D01*
X747566Y42506D01*
X747691Y42466D01*
X747801Y42406D01*
X747901Y42326D01*
X747981Y42226D01*
X748041Y42116D01*
X748081Y41991D01*
X748091Y41866D01*
Y38436D01*
X748121Y38406D01*
X748221Y38266D01*
X748241Y38226D01*
X748256Y38191D01*
X748276Y38151D01*
X748291Y38111D01*
X748301Y38071D01*
X748316Y38026D01*
X748321Y37986D01*
X748331Y37946D01*
X748336Y37901D01*
Y37861D01*
X748341Y37816D01*
X748336Y37771D01*
Y37731D01*
X748331Y37686D01*
X748321Y37646D01*
X748316Y37606D01*
X748301Y37561D01*
X748291Y37521D01*
X748276Y37481D01*
X748256Y37441D01*
X748241Y37406D01*
X748221Y37366D01*
X748121Y37226D01*
X748091Y37196D01*
Y36066D01*
X748081Y35941D01*
X748041Y35816D01*
X747981Y35706D01*
X747901Y35606D01*
X747801Y35526D01*
X747691Y35466D01*
X747566Y35426D01*
X747441Y35416D01*
G37*
G36*
G01X742716D02*
X742591Y35426D01*
X742466Y35466D01*
X742356Y35526D01*
X742256Y35606D01*
X742176Y35706D01*
X742116Y35816D01*
X742076Y35941D01*
X742066Y36066D01*
Y37196D01*
X742036Y37226D01*
X741936Y37366D01*
X741916Y37406D01*
X741901Y37441D01*
X741881Y37481D01*
X741866Y37521D01*
X741856Y37561D01*
X741841Y37606D01*
X741836Y37646D01*
X741826Y37686D01*
X741821Y37731D01*
Y37771D01*
X741816Y37816D01*
X741821Y37861D01*
Y37901D01*
X741826Y37946D01*
X741836Y37986D01*
X741841Y38026D01*
X741856Y38071D01*
X741866Y38111D01*
X741881Y38151D01*
X741901Y38191D01*
X741916Y38226D01*
X741936Y38266D01*
X742036Y38406D01*
X742066Y38436D01*
Y41866D01*
X742076Y41991D01*
X742116Y42116D01*
X742176Y42226D01*
X742256Y42326D01*
X742356Y42406D01*
X742466Y42466D01*
X742591Y42506D01*
X742716Y42516D01*
X742841Y42506D01*
X742966Y42466D01*
X743076Y42406D01*
X743176Y42326D01*
X743256Y42226D01*
X743316Y42116D01*
X743356Y41991D01*
X743366Y41866D01*
Y38436D01*
X743396Y38406D01*
X743496Y38266D01*
X743516Y38226D01*
X743531Y38191D01*
X743551Y38151D01*
X743566Y38111D01*
X743576Y38071D01*
X743591Y38026D01*
X743596Y37986D01*
X743606Y37946D01*
X743611Y37901D01*
Y37861D01*
X743616Y37816D01*
X743611Y37771D01*
Y37731D01*
X743606Y37686D01*
X743596Y37646D01*
X743591Y37606D01*
X743576Y37561D01*
X743566Y37521D01*
X743551Y37481D01*
X743531Y37441D01*
X743516Y37406D01*
X743496Y37366D01*
X743396Y37226D01*
X743366Y37196D01*
Y36066D01*
X743356Y35941D01*
X743316Y35816D01*
X743256Y35706D01*
X743176Y35606D01*
X743076Y35526D01*
X742966Y35466D01*
X742841Y35426D01*
X742716Y35416D01*
G37*
G54D87*
G01X18000Y200300D02*
X16800D01*
X14500Y198000D01*
G01X25800Y139400D02*
X26400Y138800D01*
X31037D01*
X31800Y139563D01*
X34357D01*
G01Y141531D02*
X31520D01*
X31189Y141200D01*
X29700D01*
G01X45857Y99531D02*
X43844D01*
X43575Y99800D01*
X42500D01*
X41500Y100800D01*
G01X38464Y98248D02*
X38612Y98100D01*
X42870D01*
X43407Y97563D01*
X45857D01*
G01X49500Y120000D02*
X52800Y116700D01*
Y116000D01*
G01X65500Y123800D02*
X60000D01*
G01X52643Y139563D02*
X60937D01*
X62200Y138300D01*
G01X60700Y223800D02*
X60100Y223200D01*
X57500D01*
G01X54000Y224300D02*
X56400D01*
X57500Y223200D01*
G01X64143Y97563D02*
X69437D01*
X70000Y97000D01*
G01X70600Y207200D02*
Y208299D01*
X72137Y209836D01*
Y210237D01*
G01X113500Y54200D02*
X112346D01*
X104500Y62046D01*
Y78042D01*
X102542Y80000D01*
X95500D01*
X91500Y84000D01*
G01X92600Y197200D02*
X95700D01*
G01X98500Y195800D02*
X97300D01*
X95900Y197200D01*
X95700D01*
G01X113500Y54200D02*
X112300Y53000D01*
X112044D01*
X111000Y51956D01*
Y48500D01*
X115990Y43510D01*
X124290D01*
X125100Y42700D01*
X143200D01*
X146300Y45800D01*
Y48850D01*
X142847Y52303D01*
X138097D01*
X137200Y53200D01*
X135000D01*
G01X123800Y134800D02*
X121700D01*
X121000Y135500D01*
X120700D01*
G01X127500Y129180D02*
Y129400D01*
X125200Y131700D01*
X124500D01*
G01X123800Y137800D02*
X122900D01*
X121700Y139000D01*
X120500D01*
G01X123700Y150900D02*
X123800Y150800D01*
Y147500D01*
G01D02*
Y144400D01*
X123700Y144300D01*
G01D02*
X120600D01*
X119600Y143300D01*
G01X164000Y205000D02*
X152200D01*
G01X172800Y72500D02*
X168300Y68000D01*
X167500D01*
G01X167602Y160684D02*
X167688D01*
X170000Y162996D01*
Y163620D01*
X171320Y164940D01*
G01X163060Y165320D02*
Y162860D01*
X161900Y161700D01*
G01X164860Y175960D02*
Y170724D01*
X163060Y168924D01*
Y165320D01*
G01X160900Y155200D02*
Y159420D01*
X158500Y161820D01*
G01X186800Y72500D02*
X183200D01*
G01D02*
X183300Y72600D01*
Y75500D01*
G01X177700Y84500D02*
Y81500D01*
G01D02*
Y79800D01*
X175600Y77700D01*
X174900D01*
G01X184300Y78500D02*
X183901Y78101D01*
Y77175D01*
X183300Y76574D01*
Y75500D01*
G01X184300Y78500D02*
X183400Y79400D01*
Y82439D01*
X182339Y83500D01*
X182300D01*
X181000Y84800D01*
G01X182500Y87700D02*
Y86200D01*
X181100Y84800D01*
X181000D01*
G01X189000Y87700D02*
X185600D01*
X185500Y87800D01*
G01X179700Y75500D02*
Y77500D01*
X180700Y78500D01*
G01X181000Y81200D02*
Y78800D01*
X180700Y78500D01*
G01X174500Y99500D02*
Y98500D01*
X173000Y97000D01*
G01X183344Y94056D02*
X182500Y93212D01*
Y91300D01*
G01X178800Y127700D02*
X179000Y127500D01*
Y120800D01*
X178100Y119900D01*
X176360D01*
G01X183840D02*
X186900D01*
G01D02*
X187500Y120500D01*
Y127200D01*
X183700Y131000D01*
G01X187597Y133697D02*
X185897D01*
X183594Y136000D01*
X183500D01*
X182200Y137300D01*
G01X183700Y131000D02*
X182500Y132200D01*
Y132456D01*
X182200Y132756D01*
Y133700D01*
G01X178680Y160560D02*
X179460D01*
X181280Y162380D01*
Y167220D01*
X181000Y167500D01*
G01X178680Y170060D02*
Y169820D01*
X181000Y167500D01*
G01X174739Y207381D02*
Y203761D01*
X175200Y203300D01*
G01X182100Y207900D02*
Y204200D01*
X181800Y203900D01*
G01X178800D02*
X181800D01*
G01X175200Y203300D02*
X178200D01*
X178800Y203900D01*
G01X197200Y72500D02*
Y69000D01*
X196900Y68700D01*
G01X204200Y92500D02*
Y95300D01*
X202500Y97000D01*
G01X222200Y148000D02*
X221200Y149000D01*
Y149139D01*
X220239Y150100D01*
X215500D01*
X212800Y147400D01*
X203900D01*
X197300Y140800D01*
Y139200D01*
G01X199900Y154200D02*
X195846Y158254D01*
Y169698D01*
X195700Y169844D01*
Y171200D01*
X190400Y176500D01*
Y177000D01*
G01X213558Y98500D02*
X212628D01*
X211200Y97072D01*
Y92500D01*
G01X205700Y103300D02*
X214846D01*
X219573Y98573D01*
Y92627D01*
X219700Y92500D01*
G01X209060Y182250D02*
Y180840D01*
X210050Y179850D01*
X213850D01*
G01X228455Y185945D02*
X219955D01*
X217700Y188200D01*
G01X209500Y199400D02*
X209800D01*
G01X207900Y210500D02*
Y212230D01*
X205920Y214210D01*
Y221550D01*
G01X218795Y204953D02*
X216907D01*
X216776Y205084D01*
X214514D01*
X213054Y203624D01*
Y202654D01*
X209800Y199400D01*
G01X226100Y89900D02*
X227500Y88500D01*
Y84560D01*
X229036Y83024D01*
Y83000D01*
G01X232791Y82260D02*
X229776D01*
X229036Y83000D01*
G01X223350Y84900D02*
Y89050D01*
X222500Y89900D01*
G01D02*
X222300D01*
X219700Y92500D01*
G01X237000Y128600D02*
X231600D01*
X223871Y120871D01*
X221299D01*
G01X222200Y136000D02*
X224300D01*
X228000Y139700D01*
G01X233200Y164500D02*
X232921Y164779D01*
Y167505D01*
G01X225060Y168750D02*
Y166860D01*
X223700Y165500D01*
X221120D01*
X219940Y164320D01*
Y162250D01*
G01X219200Y157000D02*
X232000D01*
X233200Y155800D01*
X242950D01*
G01X227000Y183300D02*
Y182178D01*
X229600Y179578D01*
Y179500D01*
X230680Y178420D01*
Y171820D01*
X232921Y169579D01*
Y167505D01*
G01X220700Y180500D02*
X220400Y180200D01*
Y178100D01*
X219500Y177200D01*
G01X220700Y183500D02*
Y180500D01*
G01X227000Y183300D02*
X226800Y183500D01*
X220700D01*
G01X218795Y204953D02*
X220847D01*
X222816Y202984D01*
X229205D01*
G01X233981Y59125D02*
X236031Y57075D01*
X241463D01*
X246638Y62250D01*
X278550D01*
X278800Y62000D01*
G01X244759Y85200D02*
X246200D01*
X247400Y86400D01*
X250256D01*
X253520Y89664D01*
G01X245300Y91500D02*
X240000D01*
X236400Y95100D01*
G01X235700Y102000D02*
Y99000D01*
G01X239000Y98800D02*
Y97700D01*
X236400Y95100D01*
G01X235700Y99000D02*
Y95800D01*
X236400Y95100D01*
G01X248500Y119800D02*
X245860D01*
X244100Y118040D01*
G01X254700Y127000D02*
Y124200D01*
X250300Y119800D01*
X248500D01*
G01X251300Y130000D02*
X245118D01*
X244463Y130655D01*
G01D02*
X243318Y131800D01*
X240200D01*
X237000Y128600D01*
G01X250400Y164600D02*
Y167536D01*
X249486Y168450D01*
X245409D01*
X242500Y165541D01*
Y163087D01*
X240815Y161402D01*
Y157935D01*
X242950Y155800D01*
G01X242000Y177800D02*
X238848D01*
X238786Y177862D01*
X238642Y177959D01*
X237243Y179357D01*
G01D02*
X236477D01*
G01X250400Y180400D02*
Y177464D01*
X247603Y174667D01*
X247596D01*
G01X242000Y174200D02*
X247129D01*
X247596Y174667D01*
G01X254600Y41100D02*
X256376Y42876D01*
Y50800D01*
X258276Y52700D01*
X259000D01*
G01X261700Y49500D02*
Y45100D01*
X261900Y44900D01*
G01X265300Y49500D02*
Y49744D01*
X262300Y52744D01*
Y53000D01*
G01D02*
X259300D01*
X259000Y52700D01*
G01X255500Y93300D02*
Y91644D01*
X253520Y89664D01*
G01X267000Y81300D02*
X266600D01*
X264650Y79350D01*
X264125D01*
G01X254700Y127000D02*
Y130000D01*
G01X263775Y140327D02*
Y135275D01*
X258500Y130000D01*
G01X254700D02*
X258500D01*
G01X276740Y50500D02*
X275644D01*
X274000Y52144D01*
Y55800D01*
G01X278800Y59000D02*
Y62000D01*
G01X269260Y50500D02*
X268000D01*
X267000Y49500D01*
X265300D01*
G01X269200Y94700D02*
Y101200D01*
X266528Y103872D01*
Y127014D01*
X268900Y129386D01*
G01X272300Y121000D02*
Y119300D01*
X268928Y115928D01*
Y112625D01*
G01X272300Y129442D02*
Y124000D01*
G01X274600Y166300D02*
X274050Y165750D01*
Y163350D01*
X274100Y163300D01*
G01X280300Y178400D02*
Y178144D01*
X278278Y176122D01*
Y173322D01*
X278300Y173300D01*
G01X275300Y173600D02*
X275600Y173300D01*
X278300D01*
G01X273791Y193260D02*
X272860D01*
X270175Y190575D01*
Y188677D01*
X269772Y188274D01*
G01X270341Y211835D02*
X272700Y214194D01*
Y214900D01*
G01X269700Y201000D02*
Y201200D01*
X277710Y209210D01*
X284115D01*
X284326Y209000D01*
X287826Y205500D01*
X305754D01*
X307300Y203954D01*
Y202200D01*
X303950Y198850D01*
Y195850D01*
X303500Y195400D01*
G01X274000Y225000D02*
Y222800D01*
X274700Y222100D01*
G01X271000Y225500D02*
X273500D01*
X274000Y225000D01*
G01X277000D02*
X274000D01*
G01X272700Y214900D02*
Y218600D01*
X272300Y219000D01*
G01X281300Y222000D02*
Y221350D01*
X278450Y218500D01*
Y216800D01*
G01X267500Y232100D02*
X268325Y231275D01*
Y223575D01*
X269674Y222226D01*
X270774D01*
G01X267500Y232100D02*
X268325Y232925D01*
Y243426D01*
X273100Y248201D01*
Y255012D01*
X277574Y259486D01*
X298427D01*
X301900Y262959D01*
Y263900D01*
X303100Y265100D01*
X304163D01*
X312338Y273275D01*
X312875D01*
X316400Y276800D01*
G01X291700Y104000D02*
Y100700D01*
X291800Y100600D01*
G01D02*
X291700Y100500D01*
X289100D01*
X288100Y99500D01*
G01X289800Y118000D02*
X288300D01*
X286500Y119800D01*
Y119900D01*
G01X289800Y126500D02*
Y129500D01*
G01D02*
X286800D01*
X286781Y129481D01*
X285219D01*
X285190Y129510D01*
X285100D01*
G01X288300Y144000D02*
X286600Y142300D01*
Y136000D01*
G01X293400Y151500D02*
Y154100D01*
X293300Y154200D01*
G01X288300Y144000D02*
Y147500D01*
G01X293300Y163800D02*
X296997D01*
X297097Y163700D01*
X297250D01*
G01X295900Y154200D02*
X293300D01*
G01X290300Y167000D02*
Y164100D01*
X290200Y164000D01*
G01X290300Y170500D02*
Y167000D01*
G01Y170500D02*
Y173500D01*
G01X287071Y173154D02*
X287200D01*
Y171300D01*
X288000Y170500D01*
X290300D01*
G01X301320Y191060D02*
Y192180D01*
X297800Y195700D01*
X293000D01*
G01X289900Y188800D02*
X289385D01*
X286300Y191885D01*
G01X289500Y215300D02*
X290300Y214500D01*
Y214246D01*
X292146Y212400D01*
X293300D01*
G01X295500Y253500D02*
X290700Y248700D01*
Y231043D01*
X295185Y226558D01*
Y220301D01*
X291384Y216500D01*
X290700D01*
X289500Y215300D01*
G01X282200Y219000D02*
Y214249D01*
G01D02*
X282209Y214240D01*
G01X281300Y225000D02*
Y222000D01*
G01X298900Y253300D02*
X298700D01*
X293100Y247700D01*
Y232114D01*
X300314Y224900D01*
X304400D01*
G01X319000Y221200D02*
X309300Y230900D01*
X309200D01*
X307155Y232945D01*
X302650D01*
G01Y238060D02*
X310240D01*
X310500Y237800D01*
G01X302650Y250855D02*
X301345D01*
X298900Y253300D01*
G01X304300Y262900D02*
X306000Y261200D01*
X308000D01*
G01X313932Y102711D02*
Y102531D01*
X315613Y100850D01*
G01X317132Y102711D02*
Y102369D01*
X315613Y100850D01*
G01X313932Y102711D02*
Y105911D01*
G01X317132Y102711D02*
Y105911D01*
G01X311410Y118110D02*
X311771Y118471D01*
X313392D01*
G01X320112D02*
X321908D01*
X322010Y118573D01*
G01X321992Y120481D02*
Y118591D01*
X322010Y118573D01*
G01X313932Y112311D02*
X313111D01*
X311600Y110800D01*
G01X313932Y109111D02*
Y109332D01*
X315400Y110800D01*
G01X317132Y109111D02*
X317089D01*
X315400Y110800D01*
G01X318702Y111401D02*
X316001D01*
X315400Y110800D01*
G01X313392Y118471D02*
X316912D01*
X317112Y118671D01*
G01X325350Y114500D02*
Y115169D01*
X326322Y116141D01*
G01X313932Y115511D02*
X311911D01*
X311200Y114800D01*
G01X314500Y240700D02*
X313600Y239800D01*
Y237700D01*
G01X310500Y237800D02*
X313500D01*
X313600Y237700D01*
G01X322000Y264300D02*
X319600Y266700D01*
X316461D01*
X312099Y262338D01*
Y261799D01*
X311500Y261200D01*
G01X322000Y264300D02*
Y261200D01*
G01X319000D02*
Y263900D01*
X318600Y264300D01*
G01D02*
X317600D01*
X314500Y261200D01*
G01X359000Y53700D02*
X358400D01*
X356900Y52200D01*
X335025D01*
X331300Y48475D01*
G01X342312Y102171D02*
X339671D01*
X339500Y102000D01*
G01X340302Y110771D02*
X342182Y108891D01*
X342312D01*
G01X329322Y116141D02*
X329779D01*
X330910Y115010D01*
G01X332292Y116601D02*
Y116349D01*
X333551Y115090D01*
G01X330470Y112515D02*
X331206D01*
X332292Y113601D01*
G01X329242Y106111D02*
X329212D01*
X327262Y108061D01*
G01X337352Y115101D02*
X333562D01*
X333551Y115090D01*
G01X340112Y115101D02*
X339711Y114700D01*
X337753D01*
X337352Y115101D01*
G01X339280Y127380D02*
Y124933D01*
X340112Y124101D01*
G01X341322Y129021D02*
X340921D01*
X339280Y127380D01*
G01X331290Y125810D02*
X331973D01*
X333822Y123961D01*
G01X330822D02*
X331000Y124139D01*
Y125520D01*
X331290Y125810D01*
G01X336822Y123961D02*
X333822D01*
G01X333919Y177224D02*
X333842D01*
G01X335322Y175941D02*
Y175939D01*
X334037Y177224D01*
X333919D01*
G01X335322Y178701D02*
Y178627D01*
X333919Y177224D01*
G01X339822Y183761D02*
Y183878D01*
X338000Y185700D01*
G01X355282Y106131D02*
Y106129D01*
G01X342112Y105891D02*
Y103537D01*
X342312Y103337D01*
Y102171D01*
G01X342112Y105891D02*
X342142Y105921D01*
Y106824D01*
X342312Y106994D01*
Y108891D01*
G01X347982Y102171D02*
Y100942D01*
X347230Y100190D01*
G01X347092Y110971D02*
Y109894D01*
X348076Y108910D01*
G01X346972Y106111D02*
Y107806D01*
X348076Y108910D01*
G01X349762Y110221D02*
X349387D01*
X348076Y108910D01*
G01X358032Y110771D02*
X357749D01*
X355906Y108928D01*
X355891D01*
X355175Y108212D01*
G01X344322Y110771D02*
X344292Y110741D01*
X344162D01*
X342312Y108891D01*
G01X355282Y106131D02*
Y108105D01*
X355175Y108212D01*
G01X355752Y115101D02*
X355753Y115102D01*
X357602D01*
X358000Y115500D01*
G01X345172Y119601D02*
X346600Y121029D01*
Y121100D01*
G01D02*
X347932Y122432D01*
Y122601D01*
G01X352992Y115101D02*
X352285D01*
X351342Y114158D01*
G01X352512Y110221D02*
X352479D01*
X351000Y111700D01*
G01X347932Y113601D02*
X350785D01*
X351342Y114158D01*
G01X352512Y110221D02*
X354752D01*
X355242Y110711D01*
G01X355752Y127101D02*
Y127084D01*
X354333Y125665D01*
G01X355752Y124101D02*
Y124246D01*
X354333Y125665D01*
G01X352992Y124101D02*
Y124324D01*
X354333Y125665D01*
G01X345172Y125601D02*
X343571Y124000D01*
X343000D01*
G01D02*
X344399Y122601D01*
X345172D01*
G01X349600Y126700D02*
X349031D01*
X347932Y125601D01*
G01X350582Y132671D02*
Y127682D01*
X349600Y126700D01*
G01X353742Y166931D02*
X353740D01*
X353220Y167451D01*
X351851D01*
X351700Y167300D01*
G01X353742Y166931D02*
X356882D01*
G01X351700Y167300D02*
X351600Y167200D01*
Y166989D01*
X350422Y165811D01*
G01X362000Y53700D02*
X359000D01*
G01X365000D02*
X368000D01*
G01X362000D02*
X365000D01*
G01X363032Y103911D02*
X361329D01*
X361141Y104099D01*
G01X371392Y115101D02*
Y115099D01*
X369999Y113706D01*
X369997D01*
G01X368632Y115101D02*
Y115043D01*
X369953Y113722D01*
X369978D01*
X369994Y113706D01*
X369997D01*
G01X363572Y116601D02*
X364648D01*
X365721Y115528D01*
G01X360812Y119601D02*
X360810Y119599D01*
X360808D01*
X358000Y116791D01*
Y115500D01*
G01X359942Y110924D02*
X361899D01*
X362052Y110771D01*
G01X366400Y112200D02*
X364999Y113601D01*
X363572D01*
G01X364822Y110971D02*
X365171D01*
X366400Y112200D01*
G01X367482Y110221D02*
Y109767D01*
X368721Y108528D01*
G01X370242Y110221D02*
Y110049D01*
X368721Y108528D01*
G01X360042Y108891D02*
Y110824D01*
X359942Y110924D01*
G01X362722Y108061D02*
X360872D01*
X360042Y108891D01*
G01X372972Y110731D02*
X370752D01*
X370242Y110221D01*
G01X371392Y124101D02*
Y123955D01*
X370000Y122563D01*
G01X372642Y135431D02*
X372635D01*
X371176Y136890D01*
G01X367121Y128628D02*
X368592Y130099D01*
X368632D01*
G01Y124101D02*
Y124099D01*
X368550D01*
X367221Y125428D01*
G01X360812Y131601D02*
Y131427D01*
X362111Y130128D01*
G01X363572Y131601D02*
Y131589D01*
X362111Y130128D01*
G01X368632Y130099D02*
Y130101D01*
G01X371392Y127101D02*
Y127339D01*
X368632Y130099D01*
G01X369482Y135431D02*
Y135662D01*
X368026Y137118D01*
G01X366342Y135431D02*
Y135434D01*
X368026Y137118D01*
G01X369882Y132671D02*
Y132669D01*
X369305D01*
X367992Y133982D01*
G01X369482Y148031D02*
Y148262D01*
X368026Y149718D01*
G01X369482Y151181D02*
Y151174D01*
X368026Y149718D01*
G01X366342Y138581D02*
X366118D01*
X364600Y137063D01*
G01X372642Y138581D02*
X371176Y137115D01*
Y136890D01*
G01X366342Y144881D02*
Y144874D01*
X364796Y143328D01*
X364621D01*
G01X363182Y138581D02*
Y138579D01*
X363197D01*
X364886Y140268D01*
G01X369482Y144881D02*
Y144874D01*
X368026Y143418D01*
G01X369482Y138581D02*
Y138812D01*
X368026Y140268D01*
G01X363182Y141731D02*
Y141729D01*
X363425D01*
X364886Y140268D01*
G01X363182Y144881D02*
Y144879D01*
X363425D01*
X364621Y143683D01*
Y143328D01*
G01X366342Y141731D02*
Y141729D01*
X366565D01*
X368026Y140268D01*
G01X369482Y141731D02*
Y141962D01*
X368026Y143418D01*
G01X366342Y148031D02*
X366469D01*
X368000Y146500D01*
G01X366342Y151181D02*
X365500Y150339D01*
Y148873D01*
X366342Y148031D01*
G01X367900Y152550D02*
X367950Y152600D01*
Y152650D01*
X369482Y154182D01*
Y154331D01*
G01D02*
Y157481D01*
G01Y160631D02*
X368100Y162013D01*
Y162200D01*
G01X363182Y154331D02*
X364700Y152813D01*
Y152713D01*
G01X363182Y160631D02*
X362981D01*
X361600Y159250D01*
G01X363182Y157481D02*
X361600Y159063D01*
Y159250D01*
G01X372642Y160631D02*
Y160629D01*
X371176Y159163D01*
Y158940D01*
G01X372642Y157481D02*
Y157479D01*
X371181Y158940D01*
X371176D01*
G01X367950Y159200D02*
Y159000D01*
X367861D01*
X366342Y157481D01*
G01Y173231D02*
Y173229D01*
X367906Y171665D01*
Y171458D01*
G01X362632Y177061D02*
Y177059D01*
X364563D01*
X364607Y177103D01*
G01X366342Y175991D02*
Y175989D01*
X365228Y177103D01*
X364607D01*
G01X360042Y173231D02*
X360231D01*
X361500Y174500D01*
Y175000D01*
G01X376452Y119601D02*
Y119646D01*
X377713Y120907D01*
Y121061D01*
G01X376452Y113601D02*
Y113642D01*
X377818Y115008D01*
G01X376452Y116601D02*
Y116599D01*
X377818Y115233D01*
Y115008D01*
G01X379212Y113601D02*
X377800Y112189D01*
Y112063D01*
G01X375762Y110771D02*
X376508D01*
X377800Y112063D01*
G01X379212Y119601D02*
Y119656D01*
X377807Y121061D01*
X377713D01*
G01X375762Y110771D02*
X377642Y108891D01*
X377772D01*
G01X387000Y112300D02*
X388632Y113932D01*
Y116501D01*
X387032Y118101D01*
G01X377800Y124163D02*
Y123949D01*
X376452Y122601D01*
G01X372642Y132671D02*
Y135431D01*
G01X378942Y138581D02*
X378625Y138264D01*
Y135748D01*
X378942Y135431D01*
G01X380400Y133928D02*
Y133973D01*
X378942Y135431D01*
G01X380400Y133928D02*
X380825D01*
X382082Y132671D01*
G01X376452Y131601D02*
X373712D01*
X372642Y132671D01*
G01X376452Y125601D02*
Y125511D01*
X377800Y124163D01*
G01X376452Y128601D02*
Y125601D01*
G01X379212Y128601D02*
X376452D01*
G01X385242Y148031D02*
Y148029D01*
X386853Y149640D01*
G01X388382Y148031D02*
Y148111D01*
X386853Y149640D01*
G01X372642Y141731D02*
Y141736D01*
X374200Y143294D01*
G01X372642Y144881D02*
Y144852D01*
X374200Y143294D01*
G01X375782Y148031D02*
Y144881D01*
G01D02*
Y144876D01*
X374200Y143294D01*
G01X382082Y144881D02*
Y144879D01*
X380621Y143418D01*
X380398D01*
G01X378942Y144881D02*
Y144874D01*
X380398Y143418D01*
G01X387000Y143280D02*
X386791D01*
X385242Y141731D01*
G01Y144881D02*
X383667Y143306D01*
X383395D01*
G01D02*
Y143044D01*
X382082Y141731D01*
G01X385242Y157481D02*
X385253D01*
X386777Y159005D01*
G01X388382Y160631D02*
Y160629D01*
X386777Y159024D01*
Y159005D01*
G01X388382Y157481D02*
Y157327D01*
X387050Y155995D01*
Y155900D01*
X387000Y155850D01*
G01X385242Y160631D02*
X386766Y162155D01*
X386777D01*
G01X375782Y154331D02*
X375787D01*
X377456Y156000D01*
X377500D01*
G01X378942Y157481D02*
Y157470D01*
X377500Y156028D01*
Y156000D01*
G01X387000Y155850D02*
X387050Y155800D01*
Y155661D01*
X388380Y154331D01*
X388382D01*
G01X385242Y163781D02*
Y163779D01*
X385237D01*
X383781Y165235D01*
G01X382082Y163781D02*
Y163779D01*
X381859D01*
X380398Y165240D01*
G01X378942Y163781D02*
Y163784D01*
X380398Y165240D01*
G01X376742Y181524D02*
Y181291D01*
X375512Y180061D01*
G01X376800Y178600D02*
Y178349D01*
X375512Y177061D01*
G01X376742Y181524D02*
Y181831D01*
X375512Y183061D01*
G01X386092Y181561D02*
Y181728D01*
X384650Y183170D01*
G01X378272Y177061D02*
Y177128D01*
X376800Y178600D01*
G01X380510Y185500D02*
X382393D01*
X383332Y184561D01*
G01X392662Y104121D02*
Y102625D01*
X392382Y102345D01*
Y102149D01*
G01X400982Y151181D02*
Y151179D01*
X402725Y152922D01*
X403078D01*
G01X397842Y151181D02*
Y150974D01*
X399198Y149618D01*
G01X397842Y148031D02*
Y148029D01*
X399198Y146673D01*
Y146468D01*
G01X391542Y151181D02*
Y151174D01*
X392998Y149718D01*
G01X394682Y151181D02*
Y151174D01*
X396182Y149674D01*
G01X391542Y148031D02*
Y148262D01*
X392998Y149718D01*
G01X394682Y148031D02*
Y147954D01*
X396192Y146444D01*
G01X391542Y141731D02*
Y141726D01*
X393000Y140268D01*
G01X388382Y141731D02*
X389721Y143070D01*
Y143320D01*
G01X388382Y144881D02*
X389104Y144159D01*
Y144157D01*
X389721Y143540D01*
Y143320D01*
G01X394682Y141731D02*
X393219Y140268D01*
X393000D01*
G01X388382Y151181D02*
Y154331D01*
G01X397842Y144881D02*
X398223Y144500D01*
X400601D01*
X400982Y144881D01*
G01X397842Y141731D02*
X397455Y142118D01*
X395069D01*
X394682Y141731D01*
G01X400982Y154329D02*
Y154331D01*
G01Y160631D02*
Y160629D01*
X400759D01*
X399298Y162090D01*
G01X400982Y157481D02*
Y157479D01*
X402373Y156088D01*
Y155952D01*
G01X400982Y154331D02*
Y154561D01*
X402373Y155952D01*
G01X397842Y160631D02*
Y160629D01*
X399298Y162085D01*
Y162090D01*
G01X397842Y157481D02*
Y157479D01*
X399298Y158935D01*
Y158940D01*
G01X391542Y160631D02*
Y160596D01*
X393198Y158940D01*
G01X391542Y157481D02*
X391739D01*
X393198Y158940D01*
G01X394682Y160631D02*
X393254Y162059D01*
X393028D01*
G01X394682Y157481D02*
Y157479D01*
X394687D01*
X396148Y158940D01*
G01X404302Y151121D02*
Y151698D01*
X403078Y152922D01*
G01X404302Y158491D02*
Y158489D01*
X403149D01*
X402505Y159133D01*
G01X399300Y168400D02*
Y168389D01*
X397842Y166931D01*
G01X391542Y154331D02*
Y154329D01*
X391547D01*
X393008Y155790D01*
X393208D01*
G01X397842Y154331D02*
Y154329D01*
X397609D01*
X396148Y155790D01*
G01X394682Y154331D02*
Y154329D01*
X394687D01*
X396148Y155790D01*
G01X391542Y166931D02*
Y166929D01*
X391551D01*
X393077Y168455D01*
G01X391542Y163781D02*
Y163784D01*
X392998Y165240D01*
G01X394682Y163781D02*
Y163779D01*
X394459D01*
X392998Y165240D01*
G01X394682Y170081D02*
Y170079D01*
X396225Y171622D01*
Y171686D01*
G01X391542Y170081D02*
Y170079D01*
X393085Y171622D01*
Y171686D01*
G01X397842Y170081D02*
Y170079D01*
X399385Y171622D01*
Y171686D01*
G01X388382Y173231D02*
Y173229D01*
X389825Y174672D01*
X390025D01*
G01X394682Y173231D02*
Y173229D01*
X396225Y171686D01*
G01X391542Y173231D02*
Y173229D01*
X393085Y174772D01*
Y174836D01*
G01X397842Y173231D02*
Y173229D01*
X399385Y171686D01*
G01X400900Y273000D02*
Y267400D01*
X399600Y266100D01*
X397800D01*
G01D02*
Y263100D01*
G01X412100Y135600D02*
Y137583D01*
X411902Y137781D01*
G01X412100Y135600D02*
X411083D01*
X408902Y137781D01*
G01X404302Y151121D02*
Y151119D01*
G01X407402Y145601D02*
Y145599D01*
X409038Y143963D01*
X409096D01*
G01X404642Y145601D02*
Y145599D01*
X405990Y144251D01*
G01X404302Y142851D02*
Y142849D01*
X404588D01*
X405990Y144251D01*
G01X404642Y148361D02*
Y148359D01*
X404708D01*
X406042Y147025D01*
G01X408902Y140541D02*
X408912D01*
X410235Y141864D01*
X410302D01*
G01X407402Y148361D02*
Y148359D01*
X408607Y149564D01*
Y149579D01*
X408837Y149809D01*
G01X407399Y142561D02*
Y142038D01*
X405902Y140541D01*
G01Y137781D02*
Y140541D01*
G01X408837Y149809D02*
X408954D01*
X410402Y148361D01*
G01X405902Y153421D02*
Y153419D01*
G01X410272Y154794D02*
X410277D01*
G01X405902Y156181D02*
Y156179D01*
X404558Y154835D01*
G01X405902Y153421D02*
Y153491D01*
X404558Y154835D01*
G01X408902Y153421D02*
X408904D01*
X410272Y154789D01*
Y154794D01*
G01X408902Y156181D02*
X408904D01*
X410000Y157277D01*
Y157600D01*
X410100Y157700D01*
G01X411902Y153421D02*
X411904D01*
X413200Y154717D01*
Y154794D01*
X413314Y154908D01*
G01X417900Y178363D02*
X417884D01*
X416402Y176881D01*
G01X417000Y258000D02*
Y256600D01*
X422400Y251200D01*
X423500D01*
G01X421800Y81500D02*
Y84900D01*
X427650Y90750D01*
Y97000D01*
X426800Y97850D01*
G01X423912Y104569D02*
X423692Y104789D01*
Y107379D01*
X423792Y107479D01*
G01X430342Y119724D02*
X431909Y121291D01*
X432732D01*
G01Y117271D02*
Y117334D01*
X430342Y119724D01*
G01X425402Y132721D02*
X425595D01*
X426982Y131334D01*
G01X420902Y156181D02*
X422100Y154983D01*
Y154963D01*
X422363Y154700D01*
G01X432732Y152731D02*
Y153508D01*
X431620Y154620D01*
G01X422363Y154700D02*
X423642Y153421D01*
X423902D01*
G01X428132Y197891D02*
X428642Y197381D01*
X429835D01*
X429933Y197283D01*
G01X435180Y257060D02*
X432560D01*
X430300Y254800D01*
X423500D01*
G01X423900Y257500D02*
Y258051D01*
X422700Y259251D01*
Y260500D01*
G01X423500Y254800D02*
X423900Y255200D01*
Y257500D01*
G01X427820Y251940D02*
X424240D01*
X423500Y251200D01*
G01X436600Y275000D02*
Y273600D01*
X432000Y269000D01*
X427649D01*
X420300Y261651D01*
Y258000D01*
X420500Y257800D01*
G01X437940Y263250D02*
X425294D01*
X424000Y261956D01*
Y261800D01*
X422700Y260500D01*
G01X433300Y274100D02*
Y274800D01*
X430300Y277800D01*
Y278000D01*
G01X434392Y102711D02*
Y100499D01*
X434021Y100128D01*
G01X440792Y109111D02*
X444811D01*
G01X440792Y115511D02*
X445211D01*
G01X440792Y112311D02*
X445911D01*
G01X445300Y274400D02*
Y275400D01*
X443407Y277293D01*
Y277893D01*
X443000Y278300D01*
G01X443060Y269750D02*
Y270960D01*
X445043Y272943D01*
Y274143D01*
X445300Y274400D01*
G01X449000Y278300D02*
Y274100D01*
X449400Y273700D01*
G01X447940Y270180D02*
Y272040D01*
X449400Y273500D01*
Y273700D01*
G01X443000Y278300D02*
X440600D01*
X440300Y278000D01*
G01X446000Y278300D02*
X449000D01*
G01X452000D02*
X454300D01*
X456200Y276400D01*
Y275400D01*
X456300Y275300D01*
G01X493000Y119299D02*
Y120200D01*
X502800Y130000D01*
Y132000D01*
G01X513500Y188400D02*
X499400D01*
X495400Y184400D01*
Y183500D01*
G01X507677Y6630D02*
Y12030D01*
X506800Y12907D01*
G01X506496Y38966D02*
Y32811D01*
X506500Y32807D01*
G01X520200Y123205D02*
X511705D01*
X508000Y119500D01*
G01X502800Y132000D02*
Y135000D01*
G01X520200Y162575D02*
X511925D01*
X508500Y166000D01*
Y172000D01*
X509800Y173300D01*
X511500D01*
G01X503200Y155000D02*
X503000D01*
X500900Y157100D01*
Y183400D01*
G01X506800Y155000D02*
Y159200D01*
X504400Y161600D01*
Y183400D01*
G01X506800Y155000D02*
X507800Y156000D01*
X516000D01*
X517300Y154700D01*
X520200D01*
G01X522500Y205200D02*
X519700Y208000D01*
X512375D01*
X510675Y209700D01*
G01X505315Y278766D02*
Y274289D01*
X503996Y272970D01*
Y272181D01*
G01X524212Y6630D02*
Y10190D01*
X526000Y11978D01*
Y12507D01*
G01X517126Y6630D02*
Y10013D01*
X519426Y12313D01*
Y12318D01*
G01X514764Y6630D02*
Y11918D01*
X514360Y12322D01*
Y12417D01*
G01X520669Y38966D02*
Y34609D01*
X519400Y33340D01*
G01X525740Y88960D02*
X522000Y85220D01*
Y79200D01*
X523000Y78200D01*
G01X520200Y119270D02*
X515000D01*
G01X520200Y131080D02*
X523420D01*
X524700Y129800D01*
Y119500D01*
G01X520200Y121235D02*
X516147D01*
X515912Y121470D01*
X513470D01*
X511500Y119500D01*
G01X520200Y133045D02*
X525055D01*
X528100Y130000D01*
Y119500D01*
G01X520200Y148795D02*
X522886D01*
X524700Y146981D01*
Y145041D01*
G01X520200Y150765D02*
X523830D01*
X528400Y146195D01*
Y145041D01*
G01X518200Y183400D02*
Y177300D01*
X525000Y170500D01*
Y165500D01*
X524045Y164545D01*
X520200D01*
G01D02*
X516425D01*
X515995Y164975D01*
X513525D01*
X511500Y167000D01*
Y169700D01*
G01X511200Y183400D02*
Y179000D01*
G01D02*
Y176000D01*
G01D02*
Y173600D01*
X511500Y173300D01*
G01X514800Y183400D02*
Y179000D01*
G01X520200Y170450D02*
X516550D01*
X515000Y172000D01*
Y175800D01*
X514800Y176000D01*
G01Y179000D02*
Y176000D01*
G01X538386Y6630D02*
Y11895D01*
X537964Y12317D01*
G01X534842Y38966D02*
Y35565D01*
X534800D01*
X532542Y33307D01*
G01X527756Y38966D02*
Y35173D01*
X526700Y34117D01*
Y33207D01*
G01X537204Y38966D02*
Y33211D01*
X537200Y33207D01*
G01X526750Y63060D02*
X528940D01*
X530000Y62000D01*
Y58500D01*
X530560Y57940D01*
G01D02*
X533250D01*
G01X538500Y81200D02*
X539200D01*
X546349Y88349D01*
Y89512D01*
G01X530000Y75700D02*
Y76336D01*
X529975Y76361D01*
Y85386D01*
X530126Y85537D01*
Y86493D01*
X533267Y89634D01*
G01X537395Y94200D02*
Y89923D01*
X537374Y89902D01*
Y88078D01*
X537395Y88057D01*
Y85605D01*
X538200Y84800D01*
X538500D01*
G01X539360Y94200D02*
Y98220D01*
X541000Y99860D01*
X543910D01*
X545270Y98500D01*
Y94200D01*
G01X526600Y183500D02*
X527050Y183050D01*
G01D02*
Y178300D01*
X527550Y177800D01*
G01X530214Y183481D02*
Y181694D01*
X529520Y181000D01*
Y177800D01*
G01X538150Y183600D02*
X538300D01*
X541330Y180570D01*
Y177800D01*
G01X535210Y222285D02*
X530215D01*
X529698Y222802D01*
G01D02*
X527000Y225500D01*
G01X535210Y220316D02*
X532316D01*
X531500Y219500D01*
G01X531000Y228350D02*
X531500Y227850D01*
G01D02*
Y225500D01*
X532746Y224254D01*
X535210D01*
G01X540748Y278766D02*
Y273800D01*
X539937Y272989D01*
G01X541929Y38966D02*
Y33361D01*
X541950Y33340D01*
G01X543200Y75500D02*
Y72500D01*
G01X556500Y89000D02*
X555110Y90390D01*
Y94200D01*
G01X545270D02*
Y90591D01*
X546349Y89512D01*
G01X543300Y94200D02*
Y89750D01*
X542950Y89400D01*
G01X543200Y75500D02*
X545432Y77732D01*
X546768D01*
X552900Y83864D01*
Y89100D01*
G01X555110Y94200D02*
Y97426D01*
X556684Y99000D01*
X559500D01*
X561000Y97500D01*
X561015D01*
Y94200D01*
G01X555110Y177800D02*
Y174500D01*
X556220Y173390D01*
X560000D01*
X561015Y174405D01*
Y177800D01*
G01X545270D02*
Y180486D01*
X544835Y180921D01*
Y183476D01*
G01X547235Y177800D02*
Y182481D01*
X548354Y183600D01*
G01X544835Y183476D02*
X544954Y183595D01*
Y183600D01*
G01X551652Y209752D02*
X552248D01*
X554200Y207800D01*
X555300D01*
G01X551700Y209800D02*
X551652Y209752D01*
G01X551800Y199200D02*
Y202200D01*
G01X551652Y209752D02*
X551600Y209700D01*
Y205400D01*
X551800Y205200D01*
G01Y202200D02*
Y205200D01*
G01X555300Y211400D02*
X556900D01*
X558300Y210000D01*
G01X555300Y214100D02*
Y211400D01*
G01X546710Y222285D02*
X550400D01*
G01X546710Y226222D02*
Y228500D01*
G01X557080Y230982D02*
Y227520D01*
X557900Y226700D01*
G01X554922Y278766D02*
Y273402D01*
X554434Y272914D01*
G01X547835Y278766D02*
Y274035D01*
X546900Y273100D01*
G01X557284Y278766D02*
Y275216D01*
X559600Y272900D01*
G01X566732Y6630D02*
Y11625D01*
X566040Y12317D01*
G01X559645Y6630D02*
X559600Y6675D01*
Y11255D01*
X558448Y12407D01*
G01X570860Y94200D02*
Y89415D01*
X570715Y89270D01*
Y89100D01*
G01X566920Y94200D02*
Y89920D01*
X566100Y89100D01*
X566000D01*
G01X566500Y84700D02*
Y87000D01*
X566000Y87500D01*
Y89100D01*
G01X561015Y177800D02*
Y181373D01*
X559000Y183388D01*
Y183518D01*
X558915Y183603D01*
G01X564398Y183481D02*
Y183002D01*
X564955Y182445D01*
Y177800D01*
G01X560200Y190000D02*
X561074Y189126D01*
X561413D01*
X564000Y186539D01*
Y183879D01*
X564398Y183481D01*
G01X575150Y216680D02*
X572704D01*
X570184Y214160D01*
X567060D01*
X562900Y210000D01*
X558300D01*
G01X557900Y226700D02*
X560530D01*
X561196Y227366D01*
G01X564700Y227000D02*
X561900D01*
X561534Y227366D01*
X561196D01*
G01X576181Y6630D02*
Y9708D01*
X578620Y12147D01*
Y12357D01*
G01X573819Y6630D02*
Y11918D01*
X573470Y12267D01*
Y12347D01*
G01X577000Y83200D02*
Y87700D01*
X578400Y89100D01*
G01X587500Y88913D02*
Y85300D01*
X585500Y83300D01*
G01X584640Y94200D02*
Y84160D01*
X585500Y83300D01*
G01X584640Y94200D02*
Y98640D01*
X593000Y107000D01*
Y115330D01*
G01X580745Y187050D02*
Y187645D01*
X582397Y189297D01*
Y193447D01*
X583700Y194750D01*
G01X580745Y187050D02*
Y186505D01*
X582254Y184996D01*
Y183313D01*
G01X585630Y278766D02*
Y269870D01*
X587200Y268300D01*
X589733D01*
X589900Y268133D01*
G01X599803Y6630D02*
Y11314D01*
X600896Y12407D01*
G01X600700Y46000D02*
Y45246D01*
X603346Y42600D01*
Y38966D01*
G01Y38940D02*
Y35853D01*
X600780Y33287D01*
X600360D01*
G01X600800Y49000D02*
Y46100D01*
X600700Y46000D01*
G01X596450Y94200D02*
Y90650D01*
X596845Y90255D01*
Y89624D01*
G01X594480Y94200D02*
Y83320D01*
X594500Y83300D01*
G01X590898Y89045D02*
X591500Y88443D01*
Y83300D01*
G01X594500D02*
X591500D01*
G01X599500Y87500D02*
X606000D01*
X608200Y89700D01*
Y93000D01*
G01X603800Y119270D02*
X599300D01*
G01X603800Y117300D02*
X600442D01*
X600212Y117070D01*
X598388D01*
X593400Y122058D01*
Y126000D01*
G01X593000Y115330D02*
X603800D01*
G01X593000D02*
X591000Y117330D01*
Y140297D01*
X595744Y145041D01*
G01X603800Y127140D02*
X594540D01*
X593400Y126000D01*
G01X603800Y144860D02*
X599340D01*
X599200Y145000D01*
G01X603800Y162575D02*
X593075D01*
X588800Y158300D01*
Y145000D01*
G01X603800Y160605D02*
X599605D01*
X592200Y153200D01*
Y145000D01*
G01X603800Y150765D02*
X600365D01*
X595744Y146144D01*
Y145041D01*
G01X590975Y183275D02*
Y182425D01*
X590545Y181995D01*
Y177800D01*
G01X588475Y183300D02*
Y177900D01*
X588575Y177800D01*
G01X588800Y205900D02*
Y205700D01*
X592300Y202200D01*
X595500D01*
G01X603964Y210400D02*
X600244Y214120D01*
X596850D01*
G01X604528Y278766D02*
Y275228D01*
X602450Y273150D01*
Y272900D01*
G01X595079Y278766D02*
Y273239D01*
X595386Y272932D01*
G01X606890Y6630D02*
Y11288D01*
X605871Y12307D01*
X605800D01*
X605700Y12407D01*
G01X613976Y6630D02*
Y13383D01*
X614700Y14107D01*
G01X612795Y38966D02*
Y34185D01*
X612900Y34080D01*
Y28207D01*
X611800Y27107D01*
Y17607D01*
X612000Y17407D01*
G01X604300Y46000D02*
Y44700D01*
X605384Y43616D01*
X611579D01*
X612795Y42400D01*
Y38966D01*
G01X605708D02*
X605707Y38965D01*
Y35177D01*
X607544Y33340D01*
G01X608300Y46000D02*
X604300D01*
G01X604200Y49000D02*
Y46100D01*
X604300Y46000D01*
G01X627300Y104700D02*
X620905D01*
X619905Y105700D01*
X616000D01*
G01D02*
X613000D01*
G01X608200Y93000D02*
Y96000D01*
G01X603800Y101550D02*
X606150D01*
X608200Y99500D01*
Y96000D01*
G01X616000Y109300D02*
Y112300D01*
G01X613000Y109300D02*
X616000D01*
G01D02*
X616050Y109250D01*
X622871D01*
X624726Y107395D01*
G01X613000Y112300D02*
X611423D01*
X607400Y116323D01*
Y116386D01*
X606486Y117300D01*
X603800D01*
G01Y129110D02*
X609390D01*
X613000Y125500D01*
X617700D01*
G01X603800Y142890D02*
X606486D01*
X608300Y144704D01*
Y144890D01*
G01X622400Y178500D02*
Y181100D01*
X619000Y184500D01*
Y194500D01*
X616100Y197400D01*
G01X611614Y278766D02*
Y274000D01*
X611896Y273718D01*
Y273523D01*
X612393Y273026D01*
G01X623425Y6630D02*
Y11831D01*
X624000Y12406D01*
G01X632874Y6630D02*
Y11780D01*
X633500Y12406D01*
G01X622500Y88700D02*
X624500Y90700D01*
Y101900D01*
X627300Y104700D01*
G01D02*
X627500Y104900D01*
G01X630700Y100500D02*
X635000D01*
X644925Y110425D01*
Y130076D01*
X654000Y139151D01*
Y148788D01*
X656642Y151430D01*
G01X634000Y97500D02*
X636000D01*
X647325Y108825D01*
Y129081D01*
X657744Y139500D01*
X658400D01*
G01X623000Y112300D02*
X624200Y113500D01*
X624456D01*
X625100Y114144D01*
Y114400D01*
X627600Y116900D01*
Y123100D01*
X630200Y125700D01*
Y133000D01*
G01X634000Y132700D02*
X633700Y133000D01*
X630200D01*
G01X630512Y278766D02*
Y273565D01*
X629937Y272990D01*
G01X621063Y278766D02*
Y273616D01*
X620437Y272990D01*
G01X642323Y6630D02*
Y11396D01*
X642041Y11678D01*
Y12071D01*
X641745Y12367D01*
G01X649409Y6630D02*
Y10137D01*
X650872Y11600D01*
Y11916D01*
X651316Y12360D01*
G01X658400Y91000D02*
X656500Y89100D01*
X647100D01*
X645085Y91115D01*
X640677D01*
G01X638500Y94000D02*
X656000Y111500D01*
X658400D01*
G01X640200Y163000D02*
Y161936D01*
X648500Y153636D01*
Y144000D01*
G01Y165200D02*
Y162882D01*
X648418Y162800D01*
Y162682D01*
X648500Y162600D01*
G01X645000Y168700D02*
X644156D01*
X642900Y167444D01*
Y163922D01*
X641978Y163000D01*
X640200D01*
G01X653638Y167248D02*
X652086Y168800D01*
X648500D01*
G01X645000Y168700D02*
X647000D01*
X647100Y168800D01*
X648500D01*
G01X643800Y232600D02*
Y237500D01*
G01X641142Y246430D02*
Y243158D01*
X643700Y240600D01*
Y237600D01*
X643800Y237500D01*
G01X648229Y246430D02*
Y251871D01*
X647800Y252300D01*
G01X644550Y267170D02*
X642400Y265020D01*
Y258300D01*
X640850Y256750D01*
Y254001D01*
X640843Y253994D01*
Y250357D01*
X641142Y250058D01*
Y246430D01*
G01X647047Y278766D02*
Y275334D01*
X648291Y274090D01*
Y273140D01*
G01X639961Y278766D02*
Y269261D01*
X639500Y268800D01*
G01X658858Y6630D02*
Y11149D01*
X657897Y12110D01*
Y12504D01*
G01X656477Y148033D02*
X658400Y146110D01*
Y139500D01*
G01X663800Y199900D02*
X661088D01*
X659400Y198212D01*
Y196388D01*
X660863Y194925D01*
X661914D01*
X663000Y193839D01*
Y193700D01*
X664200Y192500D01*
G01X650591Y246430D02*
Y249561D01*
X653160Y252130D01*
X653600D01*
G01X654134Y278766D02*
Y274082D01*
X653041Y272989D01*
G01X668307Y6630D02*
Y16614D01*
X669600Y17907D01*
G01X694900Y181400D02*
X697900D01*
X698000Y181500D01*
G01X691500Y226700D02*
X694500D01*
G01D02*
Y228700D01*
X694600Y228800D01*
Y229800D01*
G01X685500Y226700D02*
X688500D01*
G01D02*
Y230500D01*
X690400Y232400D01*
X695961D01*
X697500Y230861D01*
Y226700D01*
G01X711300Y153000D02*
Y154425D01*
X712700Y155825D01*
Y155978D01*
G01X701245Y183800D02*
X704045Y181000D01*
X707000D01*
X712500Y186500D01*
Y191500D01*
X714800Y193800D01*
X717000D01*
G01X696500Y194250D02*
X699950D01*
X701700Y192500D01*
G01X727403Y79365D02*
X723735D01*
X722600Y80500D01*
G01X714900Y131900D02*
X716600Y133600D01*
X718000D01*
G01D02*
Y136800D01*
X717800Y137000D01*
G01X711300Y147000D02*
Y150000D01*
G01D02*
Y153000D01*
G01X721000Y140200D02*
X721200Y140000D01*
X727187D01*
G01X718000Y140300D02*
X717800Y140100D01*
Y137000D01*
G01X721260Y190000D02*
X717200D01*
X717000Y190200D01*
G01D02*
Y187500D01*
G01X728740Y192560D02*
X726940D01*
X725500Y194000D01*
Y195500D01*
G01X721380Y197525D02*
X719205Y199700D01*
X717000D01*
G01Y193800D02*
Y199700D01*
G01X721260Y192560D02*
X718240D01*
X717000Y193800D01*
G01X725000Y213700D02*
Y217200D01*
G01X731340Y67865D02*
Y64160D01*
G01D02*
X732000Y63500D01*
G01X738000Y65700D02*
X737400Y65100D01*
X734100D01*
X733309Y65891D01*
Y67865D01*
G01X727800Y64200D02*
X729371Y65771D01*
Y67865D01*
G01X731340Y82515D02*
Y79365D01*
G01X735500Y179300D02*
Y178700D01*
X733000Y176200D01*
G01X733320Y190000D02*
X735500D01*
X737000Y188500D01*
Y188315D01*
G01X740680Y192560D02*
X744260D01*
X744500Y192800D01*
G01X728740Y200085D02*
X731585D01*
X734000Y202500D01*
Y205000D01*
G01X737000Y201200D02*
Y206500D01*
X733300Y210200D01*
X731000D01*
G01X728000Y213700D02*
X729800D01*
X731000Y212500D01*
Y210200D01*
G01X750100Y16100D02*
X749900D01*
X748622Y14822D01*
Y6630D01*
G01X759000Y128500D02*
X762100D01*
X762800Y129200D01*
G01X743100Y195500D02*
X744500Y194100D01*
Y192800D01*
G01X766500Y132800D02*
X766800D01*
X771000Y128600D01*
X771726D01*
G01X766500Y132800D02*
X765100D01*
X762900Y135000D01*
X762100D01*
G01X766500Y129200D02*
X762800D01*
G01X784000Y31000D02*
X781700Y28700D01*
Y28000D01*
G01Y25000D02*
X784500D01*
X786401Y26901D01*
Y35200D01*
X793201Y42000D01*
X794799D01*
X799000Y46201D01*
Y49500D01*
X804032Y54532D01*
Y57032D01*
G01X781700Y22000D02*
Y25000D01*
X318702Y111401D03*
X317132Y113711D03*
X319282Y115791D03*
X320112Y118471D03*
X317112Y118671D03*
X319112Y121101D03*
X324582Y108891D03*
X322572Y110771D03*
X322192Y113691D03*
X324822Y121201D03*
X321992Y116451D03*
Y120481D03*
X324582Y105891D03*
X318702Y129131D03*
X315782Y129151D03*
X317332Y131541D03*
X317112Y136391D03*
X320112Y136191D03*
X319282Y133521D03*
X315132Y133201D03*
X321442Y128751D03*
X322192Y131421D03*
X321992Y134181D03*
X315342Y121311D03*
X315792Y125511D03*
X318702Y125631D03*
X317352Y123221D03*
X324822Y123961D03*
X321442Y125991D03*
X321922Y123261D03*
X317332Y149271D03*
X318702Y146861D03*
X315782Y146881D03*
X319282Y151251D03*
X315132Y150931D03*
X321442Y146481D03*
X322192Y149151D03*
X321992Y151911D03*
X319112Y138831D03*
X315342Y139031D03*
X317352Y140951D03*
X318702Y143361D03*
X315792Y143231D03*
X321992Y138211D03*
X324822Y139601D03*
Y136841D03*
X321442Y143721D03*
X321922Y140991D03*
X317332Y166991D03*
X322192Y166871D03*
X317112Y154121D03*
X318702Y161091D03*
X317352Y158681D03*
X319112Y156551D03*
X315792Y160961D03*
X315342Y156761D03*
X318702Y164591D03*
X315782Y164611D03*
X320112Y153921D03*
X321442Y161451D03*
X321992Y155931D03*
X321922Y158721D03*
X324822Y152481D03*
Y155241D03*
X321442Y164201D03*
X319282Y168971D03*
X315132Y168661D03*
X317352Y176411D03*
X319112Y174281D03*
X315342Y174491D03*
X317112Y171851D03*
X318702Y178811D03*
X315792Y178691D03*
X318702Y182311D03*
X315782Y182341D03*
X320112Y171651D03*
X324822Y168121D03*
X321992Y169641D03*
X324822Y170881D03*
X321922Y176451D03*
X321992Y173661D03*
X321442Y179181D03*
Y181931D03*
X317332Y184721D03*
X315132Y186391D03*
X319282Y186701D03*
X317112Y189581D03*
X319282Y192051D03*
X317132Y194131D03*
X318702Y196441D03*
X320112Y189381D03*
X324822Y186521D03*
X322192Y184601D03*
X321992Y187371D03*
Y191391D03*
X325782Y197891D03*
X321442Y196901D03*
X321922Y194171D03*
X324822Y194341D03*
Y183761D03*
X323772Y199771D03*
Y202771D03*
X331622Y104561D03*
X335272Y104571D03*
X339472Y104121D03*
X334782Y110221D03*
X332032D03*
X332292Y113601D03*
Y116601D03*
X337522Y110711D03*
X340302Y110771D03*
X340112Y115101D03*
X337352D03*
X340112Y118101D03*
X337352D03*
Y121101D03*
X340112D03*
X330822Y121201D03*
X335152Y107481D03*
X331652D03*
X339682Y107891D03*
X337552Y106131D03*
X327262Y108061D03*
X329362Y110971D03*
X326592Y110771D03*
X327822Y113601D03*
X329322Y116141D03*
X326322D03*
X327822Y121201D03*
X329242Y106111D03*
X336822Y123961D03*
X332322Y129021D03*
X335322D03*
X332322Y131781D03*
X335322D03*
X338322Y129021D03*
Y131781D03*
X333822Y123961D03*
X340112Y124101D03*
X330822Y123961D03*
X329322Y129021D03*
X326322D03*
X329322Y131781D03*
X326322D03*
X327822Y123961D03*
X332322Y147421D03*
X335322D03*
X338322D03*
X329322D03*
X333822Y139601D03*
Y136841D03*
X332322Y144661D03*
X335322D03*
X336822Y139601D03*
X339822D03*
X336822Y136841D03*
X339822D03*
X338322Y144661D03*
X330822Y139601D03*
Y136841D03*
X329322Y144661D03*
X326322Y147421D03*
X327822Y139601D03*
Y136841D03*
X326322Y144661D03*
X332322Y160301D03*
X333822Y152481D03*
Y155241D03*
X335322Y160301D03*
X332322Y163061D03*
X335322D03*
X338322Y160301D03*
X339822Y152481D03*
X336822D03*
X339822Y155241D03*
X336822D03*
X338322Y163061D03*
X329322Y160301D03*
X330822Y152481D03*
Y155241D03*
X329322Y163061D03*
X326322Y160301D03*
X327822Y152481D03*
Y155241D03*
X326322Y163061D03*
X333822Y168121D03*
Y170881D03*
X332322Y175941D03*
X335322D03*
X332322Y178701D03*
X335322D03*
X336822Y168121D03*
X339822D03*
X336822Y170881D03*
X339822D03*
X338322Y175941D03*
Y178701D03*
X330822Y168121D03*
Y170881D03*
X329322Y175941D03*
Y178701D03*
X327822Y168121D03*
Y170881D03*
X326322Y175941D03*
Y178701D03*
X331352Y189061D03*
Y192061D03*
Y195061D03*
X336412Y190561D03*
Y187561D03*
X339172Y190561D03*
Y187561D03*
X336722Y197691D03*
X339492Y197891D03*
X336412Y193561D03*
X339172D03*
X333822Y183761D03*
X339822D03*
X336822D03*
X330822D03*
X328592Y192061D03*
X327822Y186521D03*
X328562Y197951D03*
X328592Y195061D03*
X327822Y183761D03*
X334462Y204101D03*
X338512Y204751D03*
X330812Y204091D03*
X331302Y198441D03*
X334052D03*
X334432Y201181D03*
X338822Y200601D03*
X336842Y202551D03*
X330932Y201181D03*
X326442Y200601D03*
X328532Y202531D03*
X353002Y104571D03*
X349352Y104561D03*
X345302Y103911D03*
X352512Y110221D03*
X355242Y110711D03*
X352992Y115101D03*
Y121101D03*
Y118101D03*
X355752Y115101D03*
Y121101D03*
Y118101D03*
X349762Y110221D03*
X352882Y107481D03*
X355282Y106131D03*
X349382Y107481D03*
X344992Y108061D03*
X342312Y108891D03*
X347092Y110971D03*
X344322Y110771D03*
X347932Y113601D03*
X345172D03*
X347932Y116601D03*
Y119601D03*
X345172Y116601D03*
Y119601D03*
X346972Y106111D03*
X342112Y105891D03*
X350582Y132671D03*
X352992Y130101D03*
Y127101D03*
X355752D03*
Y130101D03*
X354132Y132671D03*
X352992Y124101D03*
X355752D03*
X347932Y128601D03*
X345172D03*
X341322Y129021D03*
X347932Y131601D03*
X345172D03*
X341322Y131781D03*
X347932Y122601D03*
Y125601D03*
X345172Y122601D03*
Y125601D03*
X350082Y147421D03*
X350422Y150171D03*
X350082Y144661D03*
X350422Y141901D03*
X348822Y136841D03*
Y139601D03*
X347322Y147421D03*
X341322D03*
X344322D03*
X345822Y139601D03*
X342822D03*
X345822Y136841D03*
X342822D03*
X347322Y144661D03*
X341322D03*
X344322D03*
X350422Y165811D03*
X350082Y160301D03*
X350422Y157541D03*
X350082Y163061D03*
X348822Y155241D03*
Y152481D03*
X347322Y160301D03*
X345822Y152481D03*
Y155241D03*
X341322Y160301D03*
X342822Y155241D03*
Y152481D03*
X344322Y160301D03*
X347322Y163061D03*
X341322D03*
X344322D03*
X350982Y175991D03*
X350882Y173231D03*
X353742Y175991D03*
X354812Y181561D03*
X352052D03*
Y178561D03*
X354812D03*
X348822Y168121D03*
Y170881D03*
X345822Y168121D03*
X342822D03*
X346992Y177061D03*
X344232D03*
X345822Y170881D03*
X342822D03*
X341322Y175941D03*
X346992Y180061D03*
X344232D03*
X341322Y178701D03*
X352052Y190561D03*
Y187561D03*
X354812Y190561D03*
Y187561D03*
X352052Y184561D03*
X354812D03*
X354452Y197691D03*
X354812Y193561D03*
X352052D03*
X346992Y192061D03*
Y189061D03*
Y186061D03*
X344232D03*
Y189061D03*
Y192061D03*
X343512Y197891D03*
X346292Y197951D03*
X346992Y195061D03*
X344232D03*
X346992Y183061D03*
X344232D03*
X356242Y204751D03*
X352182Y204101D03*
X348542Y204091D03*
X351782Y198441D03*
X356552Y200601D03*
X352162Y201181D03*
X354572Y202551D03*
X349022Y198441D03*
X348662Y201181D03*
X344342Y204541D03*
X341502Y199771D03*
X344132Y200771D03*
X341702Y202771D03*
X346252Y202531D03*
X370732Y104571D03*
X357202Y104121D03*
X363032Y103911D03*
X367082Y104561D03*
X370242Y110221D03*
X371392Y118101D03*
Y121101D03*
Y115101D03*
X368632Y118101D03*
Y121101D03*
Y115101D03*
X370602Y107481D03*
X367482Y110221D03*
X360042Y108891D03*
X362722Y108061D03*
X363572Y113601D03*
X360812D03*
X358032Y110771D03*
X364822Y110971D03*
X362052Y110771D03*
X363572Y119601D03*
Y116601D03*
X360812Y119601D03*
Y116601D03*
X357412Y107891D03*
X364702Y106111D03*
X367102Y107481D03*
X359842Y105891D03*
X371392Y127101D03*
Y130101D03*
X368632Y127101D03*
Y130101D03*
X371392Y124101D03*
X368632D03*
X363572Y128601D03*
X360812D03*
X363572Y131601D03*
X360812D03*
X363572Y125601D03*
Y122601D03*
X360812Y125601D03*
Y122601D03*
X370452Y178561D03*
Y181561D03*
X367692Y178561D03*
Y181561D03*
X362632Y177061D03*
X359872D03*
Y180061D03*
X362632D03*
X370452Y187561D03*
Y190561D03*
Y184561D03*
Y193561D03*
X367692Y187561D03*
Y190561D03*
Y184561D03*
Y193561D03*
X359872Y186061D03*
Y189061D03*
Y192061D03*
X362632Y186061D03*
Y189061D03*
Y192061D03*
X361242Y197891D03*
X364022Y197931D03*
X359872Y195061D03*
X362632D03*
X357212Y197891D03*
X359872Y183061D03*
X362632D03*
X369912Y204101D03*
X369512Y198441D03*
X369892Y201181D03*
X362062Y204541D03*
X366262Y204091D03*
X366752Y198441D03*
X359222Y199771D03*
X359422Y202771D03*
X361862Y200771D03*
X363982Y202531D03*
X366392Y201181D03*
X374932Y104121D03*
X380762Y103911D03*
X384812Y104561D03*
X387032Y115101D03*
Y121101D03*
Y118101D03*
X377772Y108891D03*
X380442Y108061D03*
X376452Y113601D03*
X379212D03*
X372972Y110731D03*
X375762Y110771D03*
X379782D03*
X382542Y110971D03*
X376452Y116601D03*
Y119601D03*
X379212Y116601D03*
Y119601D03*
X385212Y110221D03*
X384272Y115101D03*
Y121101D03*
Y118101D03*
X373012Y106131D03*
X375142Y107891D03*
X377572Y105891D03*
X382422Y106111D03*
X384832Y107481D03*
X387032Y127101D03*
Y130101D03*
Y124101D03*
X376452Y128601D03*
X379212D03*
X376452Y131601D03*
X379212D03*
X384272Y130101D03*
Y127101D03*
X376452Y122601D03*
Y125601D03*
X379212Y122601D03*
Y125601D03*
X384272Y124101D03*
X386092Y181561D03*
Y178561D03*
X378272Y177061D03*
X375512D03*
X378272Y180061D03*
X375512D03*
X383332Y181561D03*
Y178561D03*
X386092Y190561D03*
Y187561D03*
Y184561D03*
Y193561D03*
X378272Y192061D03*
Y189061D03*
Y186061D03*
X375512Y192061D03*
Y189061D03*
Y186061D03*
X378962Y197891D03*
X378272Y195061D03*
X374942Y197891D03*
X372182Y197691D03*
X375512Y195061D03*
X381752Y197931D03*
X383332Y190561D03*
Y187561D03*
Y184561D03*
Y193561D03*
X378272Y183061D03*
X375512D03*
X387242Y198441D03*
X379792Y204541D03*
X373962Y204751D03*
X383992Y204091D03*
X376952Y199771D03*
X374282Y200601D03*
X379582Y200771D03*
X377152Y202771D03*
X372302Y202551D03*
X381712Y202531D03*
X384482Y198441D03*
X384122Y201181D03*
X388462Y104571D03*
X392662Y104121D03*
X398482Y103911D03*
X402542Y104561D03*
X395502Y108891D03*
X398172Y108061D03*
X392092Y113601D03*
X394852D03*
X393482Y110771D03*
X390702Y110711D03*
X397512Y110771D03*
X392092Y119601D03*
Y116601D03*
X394852Y119601D03*
Y116601D03*
X400272Y110971D03*
X402672Y118101D03*
Y121101D03*
X399912Y118101D03*
Y121101D03*
Y115101D03*
X402672D03*
X387972Y110221D03*
X395302Y105891D03*
X390742Y106131D03*
X388332Y107481D03*
X392862Y107891D03*
X402562Y107481D03*
X400152Y106111D03*
X392092Y128601D03*
X394852D03*
X392092Y131601D03*
X394852D03*
X399912Y127101D03*
X402672D03*
X399912Y130101D03*
X402672D03*
X400982Y132671D03*
X392092Y125601D03*
Y122601D03*
X394852Y125601D03*
Y122601D03*
X402672Y124101D03*
X399912D03*
X391152Y177061D03*
X393912D03*
X398972Y178561D03*
Y181561D03*
X393912Y180061D03*
X391152D03*
X400592Y175991D03*
X401732Y178561D03*
Y181561D03*
X398972Y187561D03*
Y190561D03*
Y184561D03*
X393912Y186061D03*
Y189061D03*
Y192061D03*
X391152Y186061D03*
Y189061D03*
Y192061D03*
X396692Y197891D03*
X398972Y193561D03*
X389902Y197691D03*
X392672Y197891D03*
X393912Y195061D03*
X391152D03*
X401732Y187561D03*
Y190561D03*
Y184561D03*
X399482Y197931D03*
X401732Y193561D03*
X393912Y183061D03*
X391152D03*
X397522Y204541D03*
X391692Y204751D03*
X401722Y204091D03*
X387642Y204101D03*
X392002Y200601D03*
X394682Y199771D03*
X397312Y200771D03*
X390022Y202551D03*
X394882Y202771D03*
X402212Y198441D03*
X401842Y201181D03*
X399442Y202531D03*
X387622Y201181D03*
X410382Y104121D03*
X416212Y103911D03*
X406182Y104571D03*
X407732Y113601D03*
X410492D03*
X408432Y110711D03*
X413222Y108891D03*
X411212Y110771D03*
X415232D03*
X407732Y116601D03*
Y119601D03*
X410492Y116601D03*
Y119601D03*
X415902Y108061D03*
X418002Y110971D03*
X418312Y115101D03*
X415552D03*
Y121101D03*
Y118101D03*
X418312Y121101D03*
Y118101D03*
X410592Y107891D03*
X408472Y106131D03*
X413022Y105891D03*
X417882Y106111D03*
X406062Y107481D03*
X402942Y110221D03*
X405702D03*
X403842Y135431D03*
X407732Y128601D03*
X410492D03*
X413402Y129961D03*
X410492Y131601D03*
X407732D03*
X413402Y132721D03*
X416402Y129961D03*
Y132721D03*
X407732Y122601D03*
Y125601D03*
X410492Y122601D03*
Y125601D03*
X414902Y124901D03*
X417902D03*
X403742Y132671D03*
X407402Y148361D03*
X413402D03*
X410402D03*
X416402D03*
X408902Y137781D03*
Y140541D03*
X407402Y145601D03*
X411902Y137781D03*
Y140541D03*
X414902Y137781D03*
Y140541D03*
X413402Y145601D03*
X410402D03*
X417902Y137781D03*
Y140541D03*
X416402Y145601D03*
X405902Y137781D03*
Y140541D03*
X404642Y148361D03*
X404302Y151121D03*
Y142851D03*
X404642Y145601D03*
X408902Y153421D03*
Y156181D03*
X407402Y161241D03*
X411902Y156181D03*
Y153421D03*
X413402Y161241D03*
X410402D03*
X407402Y164001D03*
X413402D03*
X410402D03*
X417902Y153421D03*
X414902D03*
X417902Y156181D03*
X414902D03*
X416402Y161241D03*
Y164001D03*
X405902Y153421D03*
Y156181D03*
X404302Y166761D03*
Y158491D03*
X404642Y161241D03*
Y164001D03*
X408902Y169061D03*
X409552Y177061D03*
X408902Y171821D03*
X411902Y169061D03*
Y171821D03*
X413402Y176881D03*
X409552Y180061D03*
X413402Y179641D03*
X414902Y169061D03*
X417902D03*
X414902Y171821D03*
X417902D03*
X416402Y176881D03*
Y179641D03*
X405902Y169061D03*
X406792Y177061D03*
X405902Y171821D03*
X406792Y180061D03*
X404142Y175991D03*
X409552Y192061D03*
Y189061D03*
Y186061D03*
X414612Y190561D03*
Y187561D03*
Y184561D03*
X407632Y197691D03*
X409552Y195061D03*
X414612Y193561D03*
X414422Y197891D03*
X410402D03*
X417372Y190561D03*
Y187561D03*
X417902Y184701D03*
X417202Y197931D03*
X417372Y193561D03*
X406792Y192061D03*
Y189061D03*
Y186061D03*
Y195061D03*
X409552Y183061D03*
X406792D03*
X409422Y204751D03*
X415252Y204541D03*
X405372Y204101D03*
X409732Y200601D03*
X407752Y202551D03*
X412412Y199771D03*
X412612Y202771D03*
X415042Y200771D03*
X417172Y202531D03*
X405342Y201181D03*
X404962Y198441D03*
X423912Y104571D03*
X420262Y104561D03*
X428282Y108061D03*
X430952Y108891D03*
X426132Y113601D03*
X428942Y110771D03*
X426162Y110711D03*
X426132Y116601D03*
X429902Y114321D03*
X433282Y111761D03*
X432802Y114491D03*
X432732Y117271D03*
X430952Y105891D03*
X426192Y106131D03*
X420672Y110221D03*
X423422D03*
X423372Y113601D03*
Y116601D03*
Y119601D03*
X420292Y107481D03*
X423792D03*
X428402Y129961D03*
Y132721D03*
X433282Y129481D03*
X432732Y135001D03*
X432802Y132211D03*
X426902Y124901D03*
X429902D03*
X426902Y122141D03*
X429902D03*
X432732Y121291D03*
X433282Y126731D03*
X432532Y124061D03*
X425402Y129961D03*
X419402D03*
X422402D03*
X425402Y132721D03*
X419402D03*
X422402D03*
X420902Y124901D03*
X423902D03*
X428402Y148361D03*
X433282Y147211D03*
X432802Y149941D03*
X425402Y148361D03*
X429902Y137781D03*
X426902D03*
X429902Y140541D03*
X426902D03*
X428402Y145601D03*
X432732Y139021D03*
X432532Y141791D03*
X433282Y144461D03*
X425402Y145601D03*
X422402Y148361D03*
X419402D03*
X420902Y137781D03*
Y140541D03*
X423902Y137781D03*
Y140541D03*
X422402Y145601D03*
X419402D03*
X426902Y153421D03*
X429902D03*
X426902Y156181D03*
X429902D03*
X428402Y161241D03*
Y164001D03*
X432732Y156751D03*
Y152731D03*
X432532Y159511D03*
X433282Y162181D03*
Y164941D03*
X425402Y161241D03*
Y164001D03*
X420902Y153421D03*
Y156181D03*
X423902Y153421D03*
Y156181D03*
X419402Y161241D03*
X422402D03*
X419402Y164001D03*
X422402D03*
X429902Y169061D03*
X426902D03*
X429902Y171821D03*
X426902D03*
X428402Y176881D03*
Y179641D03*
X432732Y170451D03*
X432802Y167671D03*
X432732Y174481D03*
X432532Y177241D03*
X433282Y179911D03*
Y182671D03*
X425402Y176881D03*
Y179641D03*
X420902Y169061D03*
X423902D03*
X420902Y171821D03*
X423902D03*
X422402Y176881D03*
X419402D03*
X422402Y179641D03*
X419402D03*
X426902Y184701D03*
X429902D03*
X426902Y187461D03*
X429902D03*
X428402Y192521D03*
X428132Y197891D03*
X426902Y195061D03*
X432802Y185401D03*
X432732Y188181D03*
Y192211D03*
X432152Y197891D03*
X432532Y194971D03*
X425402Y192521D03*
X425362Y197691D03*
X422432Y192061D03*
X423902Y184701D03*
Y187461D03*
X420902Y184701D03*
X422432Y195061D03*
X427462Y200601D03*
X430142Y199771D03*
Y202771D03*
X425482Y202551D03*
X419452Y204091D03*
X423102Y204101D03*
X419942Y198441D03*
X422692D03*
X419572Y201181D03*
X423072D03*
X436022Y112221D03*
X437592Y114531D03*
X435442Y116611D03*
X437612Y119081D03*
X434612Y119281D03*
X438932Y129971D03*
X436022Y129851D03*
X439382Y134171D03*
X435612Y134381D03*
X437372Y132251D03*
X435442Y121961D03*
X437392Y123941D03*
X436022Y126351D03*
X439592Y122271D03*
X438942Y126321D03*
X438932Y147701D03*
X436022Y147571D03*
X439382Y151901D03*
X437372Y149981D03*
X434612Y137011D03*
X437612Y136811D03*
X439592Y140001D03*
X435442Y139691D03*
X436022Y144071D03*
X437392Y141671D03*
X438942Y144051D03*
X438932Y165431D03*
X436022Y165301D03*
X435612Y152111D03*
X434612Y154741D03*
X437612Y154541D03*
X439592Y157731D03*
X435442Y157411D03*
X437392Y159391D03*
X436022Y161801D03*
X438942Y161781D03*
X435612Y169831D03*
X439382Y169631D03*
X437372Y167711D03*
X434612Y172471D03*
X437612Y172271D03*
X439592Y175461D03*
X435442Y175141D03*
X437392Y177121D03*
X438942Y179511D03*
X436022Y179531D03*
X437372Y185441D03*
X435612Y187561D03*
X439382Y187351D03*
X437612Y189991D03*
X434612Y190191D03*
X435442Y192871D03*
X437592Y194951D03*
X436022Y197261D03*
Y183031D03*
X438932Y183151D03*
G54D79*
X259750Y177440D03*
Y180000D03*
Y182560D03*
X279750Y81060D03*
Y78500D03*
Y75940D03*
X266250Y177440D03*
Y180000D03*
Y182560D03*
X286250Y81060D03*
Y78500D03*
Y75940D03*
X526750Y57940D03*
Y60500D03*
Y63060D03*
X533250Y57940D03*
Y60500D03*
Y63060D03*
X628650Y182440D03*
X635150D03*
X628650Y185000D03*
Y187560D03*
X635150Y185000D03*
Y187560D03*
X651750Y179940D03*
Y182500D03*
X658250Y179940D03*
Y182500D03*
X651750Y185060D03*
X658250D03*
G36*
G01X499410Y249980D02*
X499535Y249970D01*
X499660Y249930D01*
X499770Y249870D01*
X499870Y249790D01*
X499950Y249690D01*
X500010Y249580D01*
X500050Y249455D01*
X500060Y249330D01*
Y247205D01*
X500090Y247175D01*
X500115Y247140D01*
X500145Y247105D01*
X500165Y247070D01*
X500190Y247035D01*
X500230Y246955D01*
X500275Y246835D01*
X500285Y246795D01*
X500295Y246750D01*
X500300Y246710D01*
X500310Y246665D01*
Y246495D01*
X500300Y246450D01*
X500295Y246410D01*
X500285Y246365D01*
X500275Y246325D01*
X500230Y246205D01*
X500190Y246125D01*
X500165Y246090D01*
X500145Y246055D01*
X500115Y246020D01*
X500090Y245985D01*
X500060Y245955D01*
Y243530D01*
X500050Y243405D01*
X500010Y243280D01*
X499950Y243170D01*
X499870Y243070D01*
X499770Y242990D01*
X499660Y242930D01*
X499535Y242890D01*
X499410Y242880D01*
X499285Y242890D01*
X499160Y242930D01*
X499050Y242990D01*
X498950Y243070D01*
X498870Y243170D01*
X498810Y243280D01*
X498770Y243405D01*
X498760Y243530D01*
Y245960D01*
X498730Y245990D01*
X498630Y246130D01*
X498610Y246170D01*
X498595Y246205D01*
X498575Y246245D01*
X498560Y246285D01*
X498550Y246325D01*
X498535Y246370D01*
X498530Y246410D01*
X498520Y246450D01*
X498515Y246495D01*
Y246535D01*
X498510Y246580D01*
X498515Y246625D01*
Y246665D01*
X498520Y246710D01*
X498530Y246750D01*
X498535Y246790D01*
X498550Y246835D01*
X498560Y246875D01*
X498575Y246915D01*
X498595Y246955D01*
X498610Y246990D01*
X498630Y247030D01*
X498730Y247170D01*
X498760Y247200D01*
Y249330D01*
X498770Y249455D01*
X498810Y249580D01*
X498870Y249690D01*
X498950Y249790D01*
X499050Y249870D01*
X499160Y249930D01*
X499285Y249970D01*
X499410Y249980D01*
G37*
G36*
G01X504134D02*
X504259Y249970D01*
X504384Y249930D01*
X504494Y249870D01*
X504594Y249790D01*
X504674Y249690D01*
X504734Y249580D01*
X504774Y249455D01*
X504784Y249330D01*
Y247205D01*
X504814Y247175D01*
X504839Y247140D01*
X504869Y247105D01*
X504889Y247070D01*
X504914Y247035D01*
X504954Y246955D01*
X504999Y246835D01*
X505009Y246795D01*
X505019Y246750D01*
X505024Y246710D01*
X505034Y246665D01*
Y246495D01*
X505024Y246450D01*
X505019Y246410D01*
X505009Y246365D01*
X504999Y246325D01*
X504954Y246205D01*
X504914Y246125D01*
X504889Y246090D01*
X504869Y246055D01*
X504839Y246020D01*
X504814Y245985D01*
X504784Y245955D01*
Y243530D01*
X504774Y243405D01*
X504734Y243280D01*
X504674Y243170D01*
X504594Y243070D01*
X504494Y242990D01*
X504384Y242930D01*
X504259Y242890D01*
X504134Y242880D01*
X504009Y242890D01*
X503884Y242930D01*
X503774Y242990D01*
X503674Y243070D01*
X503594Y243170D01*
X503534Y243280D01*
X503494Y243405D01*
X503484Y243530D01*
Y245960D01*
X503454Y245990D01*
X503354Y246130D01*
X503334Y246170D01*
X503319Y246205D01*
X503299Y246245D01*
X503284Y246285D01*
X503274Y246325D01*
X503259Y246370D01*
X503254Y246410D01*
X503244Y246450D01*
X503239Y246495D01*
Y246535D01*
X503234Y246580D01*
X503239Y246625D01*
Y246665D01*
X503244Y246710D01*
X503254Y246750D01*
X503259Y246790D01*
X503274Y246835D01*
X503284Y246875D01*
X503299Y246915D01*
X503319Y246955D01*
X503334Y246990D01*
X503354Y247030D01*
X503454Y247170D01*
X503484Y247200D01*
Y249330D01*
X503494Y249455D01*
X503534Y249580D01*
X503594Y249690D01*
X503674Y249790D01*
X503774Y249870D01*
X503884Y249930D01*
X504009Y249970D01*
X504134Y249980D01*
G37*
G36*
G01X508859D02*
X508984Y249970D01*
X509109Y249930D01*
X509219Y249870D01*
X509319Y249790D01*
X509399Y249690D01*
X509459Y249580D01*
X509499Y249455D01*
X509509Y249330D01*
Y247205D01*
X509539Y247175D01*
X509564Y247140D01*
X509594Y247105D01*
X509614Y247070D01*
X509639Y247035D01*
X509679Y246955D01*
X509724Y246835D01*
X509734Y246795D01*
X509744Y246750D01*
X509749Y246710D01*
X509759Y246665D01*
Y246495D01*
X509749Y246450D01*
X509744Y246410D01*
X509734Y246365D01*
X509724Y246325D01*
X509679Y246205D01*
X509639Y246125D01*
X509614Y246090D01*
X509594Y246055D01*
X509564Y246020D01*
X509539Y245985D01*
X509509Y245955D01*
Y243530D01*
X509499Y243405D01*
X509459Y243280D01*
X509399Y243170D01*
X509319Y243070D01*
X509219Y242990D01*
X509109Y242930D01*
X508984Y242890D01*
X508859Y242880D01*
X508734Y242890D01*
X508609Y242930D01*
X508499Y242990D01*
X508399Y243070D01*
X508319Y243170D01*
X508259Y243280D01*
X508219Y243405D01*
X508209Y243530D01*
Y245960D01*
X508179Y245990D01*
X508079Y246130D01*
X508059Y246170D01*
X508044Y246205D01*
X508024Y246245D01*
X508009Y246285D01*
X507999Y246325D01*
X507984Y246370D01*
X507979Y246410D01*
X507969Y246450D01*
X507964Y246495D01*
Y246535D01*
X507959Y246580D01*
X507964Y246625D01*
Y246665D01*
X507969Y246710D01*
X507979Y246750D01*
X507984Y246790D01*
X507999Y246835D01*
X508009Y246875D01*
X508024Y246915D01*
X508044Y246955D01*
X508059Y246990D01*
X508079Y247030D01*
X508179Y247170D01*
X508209Y247200D01*
Y249330D01*
X508219Y249455D01*
X508259Y249580D01*
X508319Y249690D01*
X508399Y249790D01*
X508499Y249870D01*
X508609Y249930D01*
X508734Y249970D01*
X508859Y249980D01*
G37*
G36*
G01X513583D02*
X513708Y249970D01*
X513833Y249930D01*
X513943Y249870D01*
X514043Y249790D01*
X514123Y249690D01*
X514183Y249580D01*
X514223Y249455D01*
X514233Y249330D01*
Y247205D01*
X514263Y247175D01*
X514288Y247140D01*
X514318Y247105D01*
X514338Y247070D01*
X514363Y247035D01*
X514403Y246955D01*
X514448Y246835D01*
X514458Y246795D01*
X514468Y246750D01*
X514473Y246710D01*
X514483Y246665D01*
Y246495D01*
X514473Y246450D01*
X514468Y246410D01*
X514458Y246365D01*
X514448Y246325D01*
X514403Y246205D01*
X514363Y246125D01*
X514338Y246090D01*
X514318Y246055D01*
X514288Y246020D01*
X514263Y245985D01*
X514233Y245955D01*
Y243530D01*
X514223Y243405D01*
X514183Y243280D01*
X514123Y243170D01*
X514043Y243070D01*
X513943Y242990D01*
X513833Y242930D01*
X513708Y242890D01*
X513583Y242880D01*
X513458Y242890D01*
X513333Y242930D01*
X513223Y242990D01*
X513123Y243070D01*
X513043Y243170D01*
X512983Y243280D01*
X512943Y243405D01*
X512933Y243530D01*
Y245960D01*
X512903Y245990D01*
X512803Y246130D01*
X512783Y246170D01*
X512768Y246205D01*
X512748Y246245D01*
X512733Y246285D01*
X512723Y246325D01*
X512708Y246370D01*
X512703Y246410D01*
X512693Y246450D01*
X512688Y246495D01*
Y246535D01*
X512683Y246580D01*
X512688Y246625D01*
Y246665D01*
X512693Y246710D01*
X512703Y246750D01*
X512708Y246790D01*
X512723Y246835D01*
X512733Y246875D01*
X512748Y246915D01*
X512768Y246955D01*
X512783Y246990D01*
X512803Y247030D01*
X512903Y247170D01*
X512933Y247200D01*
Y249330D01*
X512943Y249455D01*
X512983Y249580D01*
X513043Y249690D01*
X513123Y249790D01*
X513223Y249870D01*
X513333Y249930D01*
X513458Y249970D01*
X513583Y249980D01*
G37*
G36*
G01X518307D02*
X518432Y249970D01*
X518557Y249930D01*
X518667Y249870D01*
X518767Y249790D01*
X518847Y249690D01*
X518907Y249580D01*
X518947Y249455D01*
X518957Y249330D01*
Y247205D01*
X518987Y247175D01*
X519012Y247140D01*
X519042Y247105D01*
X519062Y247070D01*
X519087Y247035D01*
X519127Y246955D01*
X519172Y246835D01*
X519182Y246795D01*
X519192Y246750D01*
X519197Y246710D01*
X519207Y246665D01*
Y246495D01*
X519197Y246450D01*
X519192Y246410D01*
X519182Y246365D01*
X519172Y246325D01*
X519127Y246205D01*
X519087Y246125D01*
X519062Y246090D01*
X519042Y246055D01*
X519012Y246020D01*
X518987Y245985D01*
X518957Y245955D01*
Y243530D01*
X518947Y243405D01*
X518907Y243280D01*
X518847Y243170D01*
X518767Y243070D01*
X518667Y242990D01*
X518557Y242930D01*
X518432Y242890D01*
X518307Y242880D01*
X518182Y242890D01*
X518057Y242930D01*
X517947Y242990D01*
X517847Y243070D01*
X517767Y243170D01*
X517707Y243280D01*
X517667Y243405D01*
X517657Y243530D01*
Y245960D01*
X517627Y245990D01*
X517527Y246130D01*
X517507Y246170D01*
X517492Y246205D01*
X517472Y246245D01*
X517457Y246285D01*
X517447Y246325D01*
X517432Y246370D01*
X517427Y246410D01*
X517417Y246450D01*
X517412Y246495D01*
Y246535D01*
X517407Y246580D01*
X517412Y246625D01*
Y246665D01*
X517417Y246710D01*
X517427Y246750D01*
X517432Y246790D01*
X517447Y246835D01*
X517457Y246875D01*
X517472Y246915D01*
X517492Y246955D01*
X517507Y246990D01*
X517527Y247030D01*
X517627Y247170D01*
X517657Y247200D01*
Y249330D01*
X517667Y249455D01*
X517707Y249580D01*
X517767Y249690D01*
X517847Y249790D01*
X517947Y249870D01*
X518057Y249930D01*
X518182Y249970D01*
X518307Y249980D01*
G37*
G36*
G01X523032D02*
X523157Y249970D01*
X523282Y249930D01*
X523392Y249870D01*
X523492Y249790D01*
X523572Y249690D01*
X523632Y249580D01*
X523672Y249455D01*
X523682Y249330D01*
Y247205D01*
X523712Y247175D01*
X523737Y247140D01*
X523767Y247105D01*
X523787Y247070D01*
X523812Y247035D01*
X523852Y246955D01*
X523897Y246835D01*
X523907Y246795D01*
X523917Y246750D01*
X523922Y246710D01*
X523932Y246665D01*
Y246495D01*
X523922Y246450D01*
X523917Y246410D01*
X523907Y246365D01*
X523897Y246325D01*
X523852Y246205D01*
X523812Y246125D01*
X523787Y246090D01*
X523767Y246055D01*
X523737Y246020D01*
X523712Y245985D01*
X523682Y245955D01*
Y243530D01*
X523672Y243405D01*
X523632Y243280D01*
X523572Y243170D01*
X523492Y243070D01*
X523392Y242990D01*
X523282Y242930D01*
X523157Y242890D01*
X523032Y242880D01*
X522907Y242890D01*
X522782Y242930D01*
X522672Y242990D01*
X522572Y243070D01*
X522492Y243170D01*
X522432Y243280D01*
X522392Y243405D01*
X522382Y243530D01*
Y245960D01*
X522352Y245990D01*
X522252Y246130D01*
X522232Y246170D01*
X522217Y246205D01*
X522197Y246245D01*
X522182Y246285D01*
X522172Y246325D01*
X522157Y246370D01*
X522152Y246410D01*
X522142Y246450D01*
X522137Y246495D01*
Y246535D01*
X522132Y246580D01*
X522137Y246625D01*
Y246665D01*
X522142Y246710D01*
X522152Y246750D01*
X522157Y246790D01*
X522172Y246835D01*
X522182Y246875D01*
X522197Y246915D01*
X522217Y246955D01*
X522232Y246990D01*
X522252Y247030D01*
X522352Y247170D01*
X522382Y247200D01*
Y249330D01*
X522392Y249455D01*
X522432Y249580D01*
X522492Y249690D01*
X522572Y249790D01*
X522672Y249870D01*
X522782Y249930D01*
X522907Y249970D01*
X523032Y249980D01*
G37*
G36*
G01X527756D02*
X527881Y249970D01*
X528006Y249930D01*
X528116Y249870D01*
X528216Y249790D01*
X528296Y249690D01*
X528356Y249580D01*
X528396Y249455D01*
X528406Y249330D01*
Y247205D01*
X528436Y247175D01*
X528461Y247140D01*
X528491Y247105D01*
X528511Y247070D01*
X528536Y247035D01*
X528576Y246955D01*
X528621Y246835D01*
X528631Y246795D01*
X528641Y246750D01*
X528646Y246710D01*
X528656Y246665D01*
Y246495D01*
X528646Y246450D01*
X528641Y246410D01*
X528631Y246365D01*
X528621Y246325D01*
X528576Y246205D01*
X528536Y246125D01*
X528511Y246090D01*
X528491Y246055D01*
X528461Y246020D01*
X528436Y245985D01*
X528406Y245955D01*
Y243530D01*
X528396Y243405D01*
X528356Y243280D01*
X528296Y243170D01*
X528216Y243070D01*
X528116Y242990D01*
X528006Y242930D01*
X527881Y242890D01*
X527756Y242880D01*
X527631Y242890D01*
X527506Y242930D01*
X527396Y242990D01*
X527296Y243070D01*
X527216Y243170D01*
X527156Y243280D01*
X527116Y243405D01*
X527106Y243530D01*
Y245960D01*
X527076Y245990D01*
X526976Y246130D01*
X526956Y246170D01*
X526941Y246205D01*
X526921Y246245D01*
X526906Y246285D01*
X526896Y246325D01*
X526881Y246370D01*
X526876Y246410D01*
X526866Y246450D01*
X526861Y246495D01*
Y246535D01*
X526856Y246580D01*
X526861Y246625D01*
Y246665D01*
X526866Y246710D01*
X526876Y246750D01*
X526881Y246790D01*
X526896Y246835D01*
X526906Y246875D01*
X526921Y246915D01*
X526941Y246955D01*
X526956Y246990D01*
X526976Y247030D01*
X527076Y247170D01*
X527106Y247200D01*
Y249330D01*
X527116Y249455D01*
X527156Y249580D01*
X527216Y249690D01*
X527296Y249790D01*
X527396Y249870D01*
X527506Y249930D01*
X527631Y249970D01*
X527756Y249980D01*
G37*
G36*
G01X532481D02*
X532606Y249970D01*
X532731Y249930D01*
X532841Y249870D01*
X532941Y249790D01*
X533021Y249690D01*
X533081Y249580D01*
X533121Y249455D01*
X533131Y249330D01*
Y247205D01*
X533161Y247175D01*
X533186Y247140D01*
X533216Y247105D01*
X533236Y247070D01*
X533261Y247035D01*
X533301Y246955D01*
X533346Y246835D01*
X533356Y246795D01*
X533366Y246750D01*
X533371Y246710D01*
X533381Y246665D01*
Y246495D01*
X533371Y246450D01*
X533366Y246410D01*
X533356Y246365D01*
X533346Y246325D01*
X533301Y246205D01*
X533261Y246125D01*
X533236Y246090D01*
X533216Y246055D01*
X533186Y246020D01*
X533161Y245985D01*
X533131Y245955D01*
Y243530D01*
X533121Y243405D01*
X533081Y243280D01*
X533021Y243170D01*
X532941Y243070D01*
X532841Y242990D01*
X532731Y242930D01*
X532606Y242890D01*
X532481Y242880D01*
X532356Y242890D01*
X532231Y242930D01*
X532121Y242990D01*
X532021Y243070D01*
X531941Y243170D01*
X531881Y243280D01*
X531841Y243405D01*
X531831Y243530D01*
Y245960D01*
X531801Y245990D01*
X531701Y246130D01*
X531681Y246170D01*
X531666Y246205D01*
X531646Y246245D01*
X531631Y246285D01*
X531621Y246325D01*
X531606Y246370D01*
X531601Y246410D01*
X531591Y246450D01*
X531586Y246495D01*
Y246535D01*
X531581Y246580D01*
X531586Y246625D01*
Y246665D01*
X531591Y246710D01*
X531601Y246750D01*
X531606Y246790D01*
X531621Y246835D01*
X531631Y246875D01*
X531646Y246915D01*
X531666Y246955D01*
X531681Y246990D01*
X531701Y247030D01*
X531801Y247170D01*
X531831Y247200D01*
Y249330D01*
X531841Y249455D01*
X531881Y249580D01*
X531941Y249690D01*
X532021Y249790D01*
X532121Y249870D01*
X532231Y249930D01*
X532356Y249970D01*
X532481Y249980D01*
G37*
G36*
G01X537205D02*
X537330Y249970D01*
X537455Y249930D01*
X537565Y249870D01*
X537665Y249790D01*
X537745Y249690D01*
X537805Y249580D01*
X537845Y249455D01*
X537855Y249330D01*
Y247205D01*
X537885Y247175D01*
X537910Y247140D01*
X537940Y247105D01*
X537960Y247070D01*
X537985Y247035D01*
X538025Y246955D01*
X538070Y246835D01*
X538080Y246795D01*
X538090Y246750D01*
X538095Y246710D01*
X538105Y246665D01*
Y246495D01*
X538095Y246450D01*
X538090Y246410D01*
X538080Y246365D01*
X538070Y246325D01*
X538025Y246205D01*
X537985Y246125D01*
X537960Y246090D01*
X537940Y246055D01*
X537910Y246020D01*
X537885Y245985D01*
X537855Y245955D01*
Y243530D01*
X537845Y243405D01*
X537805Y243280D01*
X537745Y243170D01*
X537665Y243070D01*
X537565Y242990D01*
X537455Y242930D01*
X537330Y242890D01*
X537205Y242880D01*
X537080Y242890D01*
X536955Y242930D01*
X536845Y242990D01*
X536745Y243070D01*
X536665Y243170D01*
X536605Y243280D01*
X536565Y243405D01*
X536555Y243530D01*
Y245960D01*
X536525Y245990D01*
X536425Y246130D01*
X536405Y246170D01*
X536390Y246205D01*
X536370Y246245D01*
X536355Y246285D01*
X536345Y246325D01*
X536330Y246370D01*
X536325Y246410D01*
X536315Y246450D01*
X536310Y246495D01*
Y246535D01*
X536305Y246580D01*
X536310Y246625D01*
Y246665D01*
X536315Y246710D01*
X536325Y246750D01*
X536330Y246790D01*
X536345Y246835D01*
X536355Y246875D01*
X536370Y246915D01*
X536390Y246955D01*
X536405Y246990D01*
X536425Y247030D01*
X536525Y247170D01*
X536555Y247200D01*
Y249330D01*
X536565Y249455D01*
X536605Y249580D01*
X536665Y249690D01*
X536745Y249790D01*
X536845Y249870D01*
X536955Y249930D01*
X537080Y249970D01*
X537205Y249980D01*
G37*
G36*
G01X541929D02*
X542054Y249970D01*
X542179Y249930D01*
X542289Y249870D01*
X542389Y249790D01*
X542469Y249690D01*
X542529Y249580D01*
X542569Y249455D01*
X542579Y249330D01*
Y247205D01*
X542609Y247175D01*
X542634Y247140D01*
X542664Y247105D01*
X542684Y247070D01*
X542709Y247035D01*
X542749Y246955D01*
X542794Y246835D01*
X542804Y246795D01*
X542814Y246750D01*
X542819Y246710D01*
X542829Y246665D01*
Y246495D01*
X542819Y246450D01*
X542814Y246410D01*
X542804Y246365D01*
X542794Y246325D01*
X542749Y246205D01*
X542709Y246125D01*
X542684Y246090D01*
X542664Y246055D01*
X542634Y246020D01*
X542609Y245985D01*
X542579Y245955D01*
Y243530D01*
X542569Y243405D01*
X542529Y243280D01*
X542469Y243170D01*
X542389Y243070D01*
X542289Y242990D01*
X542179Y242930D01*
X542054Y242890D01*
X541929Y242880D01*
X541804Y242890D01*
X541679Y242930D01*
X541569Y242990D01*
X541469Y243070D01*
X541389Y243170D01*
X541329Y243280D01*
X541289Y243405D01*
X541279Y243530D01*
Y245960D01*
X541249Y245990D01*
X541149Y246130D01*
X541129Y246170D01*
X541114Y246205D01*
X541094Y246245D01*
X541079Y246285D01*
X541069Y246325D01*
X541054Y246370D01*
X541049Y246410D01*
X541039Y246450D01*
X541034Y246495D01*
Y246535D01*
X541029Y246580D01*
X541034Y246625D01*
Y246665D01*
X541039Y246710D01*
X541049Y246750D01*
X541054Y246790D01*
X541069Y246835D01*
X541079Y246875D01*
X541094Y246915D01*
X541114Y246955D01*
X541129Y246990D01*
X541149Y247030D01*
X541249Y247170D01*
X541279Y247200D01*
Y249330D01*
X541289Y249455D01*
X541329Y249580D01*
X541389Y249690D01*
X541469Y249790D01*
X541569Y249870D01*
X541679Y249930D01*
X541804Y249970D01*
X541929Y249980D01*
G37*
G36*
G01X546654D02*
X546779Y249970D01*
X546904Y249930D01*
X547014Y249870D01*
X547114Y249790D01*
X547194Y249690D01*
X547254Y249580D01*
X547294Y249455D01*
X547304Y249330D01*
Y247205D01*
X547334Y247175D01*
X547359Y247140D01*
X547389Y247105D01*
X547409Y247070D01*
X547434Y247035D01*
X547474Y246955D01*
X547519Y246835D01*
X547529Y246795D01*
X547539Y246750D01*
X547544Y246710D01*
X547554Y246665D01*
Y246495D01*
X547544Y246450D01*
X547539Y246410D01*
X547529Y246365D01*
X547519Y246325D01*
X547474Y246205D01*
X547434Y246125D01*
X547409Y246090D01*
X547389Y246055D01*
X547359Y246020D01*
X547334Y245985D01*
X547304Y245955D01*
Y243530D01*
X547294Y243405D01*
X547254Y243280D01*
X547194Y243170D01*
X547114Y243070D01*
X547014Y242990D01*
X546904Y242930D01*
X546779Y242890D01*
X546654Y242880D01*
X546529Y242890D01*
X546404Y242930D01*
X546294Y242990D01*
X546194Y243070D01*
X546114Y243170D01*
X546054Y243280D01*
X546014Y243405D01*
X546004Y243530D01*
Y245960D01*
X545974Y245990D01*
X545874Y246130D01*
X545854Y246170D01*
X545839Y246205D01*
X545819Y246245D01*
X545804Y246285D01*
X545794Y246325D01*
X545779Y246370D01*
X545774Y246410D01*
X545764Y246450D01*
X545759Y246495D01*
Y246535D01*
X545754Y246580D01*
X545759Y246625D01*
Y246665D01*
X545764Y246710D01*
X545774Y246750D01*
X545779Y246790D01*
X545794Y246835D01*
X545804Y246875D01*
X545819Y246915D01*
X545839Y246955D01*
X545854Y246990D01*
X545874Y247030D01*
X545974Y247170D01*
X546004Y247200D01*
Y249330D01*
X546014Y249455D01*
X546054Y249580D01*
X546114Y249690D01*
X546194Y249790D01*
X546294Y249870D01*
X546404Y249930D01*
X546529Y249970D01*
X546654Y249980D01*
G37*
G36*
G01X551378D02*
X551503Y249970D01*
X551628Y249930D01*
X551738Y249870D01*
X551838Y249790D01*
X551918Y249690D01*
X551978Y249580D01*
X552018Y249455D01*
X552028Y249330D01*
Y247205D01*
X552058Y247175D01*
X552083Y247140D01*
X552113Y247105D01*
X552133Y247070D01*
X552158Y247035D01*
X552198Y246955D01*
X552243Y246835D01*
X552253Y246795D01*
X552263Y246750D01*
X552268Y246710D01*
X552278Y246665D01*
Y246495D01*
X552268Y246450D01*
X552263Y246410D01*
X552253Y246365D01*
X552243Y246325D01*
X552198Y246205D01*
X552158Y246125D01*
X552133Y246090D01*
X552113Y246055D01*
X552083Y246020D01*
X552058Y245985D01*
X552028Y245955D01*
Y243530D01*
X552018Y243405D01*
X551978Y243280D01*
X551918Y243170D01*
X551838Y243070D01*
X551738Y242990D01*
X551628Y242930D01*
X551503Y242890D01*
X551378Y242880D01*
X551253Y242890D01*
X551128Y242930D01*
X551018Y242990D01*
X550918Y243070D01*
X550838Y243170D01*
X550778Y243280D01*
X550738Y243405D01*
X550728Y243530D01*
Y245960D01*
X550698Y245990D01*
X550598Y246130D01*
X550578Y246170D01*
X550563Y246205D01*
X550543Y246245D01*
X550528Y246285D01*
X550518Y246325D01*
X550503Y246370D01*
X550498Y246410D01*
X550488Y246450D01*
X550483Y246495D01*
Y246535D01*
X550478Y246580D01*
X550483Y246625D01*
Y246665D01*
X550488Y246710D01*
X550498Y246750D01*
X550503Y246790D01*
X550518Y246835D01*
X550528Y246875D01*
X550543Y246915D01*
X550563Y246955D01*
X550578Y246990D01*
X550598Y247030D01*
X550698Y247170D01*
X550728Y247200D01*
Y249330D01*
X550738Y249455D01*
X550778Y249580D01*
X550838Y249690D01*
X550918Y249790D01*
X551018Y249870D01*
X551128Y249930D01*
X551253Y249970D01*
X551378Y249980D01*
G37*
G36*
G01X556103D02*
X556228Y249970D01*
X556353Y249930D01*
X556463Y249870D01*
X556563Y249790D01*
X556643Y249690D01*
X556703Y249580D01*
X556743Y249455D01*
X556753Y249330D01*
Y247205D01*
X556783Y247175D01*
X556808Y247140D01*
X556838Y247105D01*
X556858Y247070D01*
X556883Y247035D01*
X556923Y246955D01*
X556968Y246835D01*
X556978Y246795D01*
X556988Y246750D01*
X556993Y246710D01*
X557003Y246665D01*
Y246495D01*
X556993Y246450D01*
X556988Y246410D01*
X556978Y246365D01*
X556968Y246325D01*
X556923Y246205D01*
X556883Y246125D01*
X556858Y246090D01*
X556838Y246055D01*
X556808Y246020D01*
X556783Y245985D01*
X556753Y245955D01*
Y243530D01*
X556743Y243405D01*
X556703Y243280D01*
X556643Y243170D01*
X556563Y243070D01*
X556463Y242990D01*
X556353Y242930D01*
X556228Y242890D01*
X556103Y242880D01*
X555978Y242890D01*
X555853Y242930D01*
X555743Y242990D01*
X555643Y243070D01*
X555563Y243170D01*
X555503Y243280D01*
X555463Y243405D01*
X555453Y243530D01*
Y245960D01*
X555423Y245990D01*
X555323Y246130D01*
X555303Y246170D01*
X555288Y246205D01*
X555268Y246245D01*
X555253Y246285D01*
X555243Y246325D01*
X555228Y246370D01*
X555223Y246410D01*
X555213Y246450D01*
X555208Y246495D01*
Y246535D01*
X555203Y246580D01*
X555208Y246625D01*
Y246665D01*
X555213Y246710D01*
X555223Y246750D01*
X555228Y246790D01*
X555243Y246835D01*
X555253Y246875D01*
X555268Y246915D01*
X555288Y246955D01*
X555303Y246990D01*
X555323Y247030D01*
X555423Y247170D01*
X555453Y247200D01*
Y249330D01*
X555463Y249455D01*
X555503Y249580D01*
X555563Y249690D01*
X555643Y249790D01*
X555743Y249870D01*
X555853Y249930D01*
X555978Y249970D01*
X556103Y249980D01*
G37*
G36*
G01X560827D02*
X560952Y249970D01*
X561077Y249930D01*
X561187Y249870D01*
X561287Y249790D01*
X561367Y249690D01*
X561427Y249580D01*
X561467Y249455D01*
X561477Y249330D01*
Y247205D01*
X561507Y247175D01*
X561532Y247140D01*
X561562Y247105D01*
X561582Y247070D01*
X561607Y247035D01*
X561647Y246955D01*
X561692Y246835D01*
X561702Y246795D01*
X561712Y246750D01*
X561717Y246710D01*
X561727Y246665D01*
Y246495D01*
X561717Y246450D01*
X561712Y246410D01*
X561702Y246365D01*
X561692Y246325D01*
X561647Y246205D01*
X561607Y246125D01*
X561582Y246090D01*
X561562Y246055D01*
X561532Y246020D01*
X561507Y245985D01*
X561477Y245955D01*
Y243530D01*
X561467Y243405D01*
X561427Y243280D01*
X561367Y243170D01*
X561287Y243070D01*
X561187Y242990D01*
X561077Y242930D01*
X560952Y242890D01*
X560827Y242880D01*
X560702Y242890D01*
X560577Y242930D01*
X560467Y242990D01*
X560367Y243070D01*
X560287Y243170D01*
X560227Y243280D01*
X560187Y243405D01*
X560177Y243530D01*
Y245960D01*
X560147Y245990D01*
X560047Y246130D01*
X560027Y246170D01*
X560012Y246205D01*
X559992Y246245D01*
X559977Y246285D01*
X559967Y246325D01*
X559952Y246370D01*
X559947Y246410D01*
X559937Y246450D01*
X559932Y246495D01*
Y246535D01*
X559927Y246580D01*
X559932Y246625D01*
Y246665D01*
X559937Y246710D01*
X559947Y246750D01*
X559952Y246790D01*
X559967Y246835D01*
X559977Y246875D01*
X559992Y246915D01*
X560012Y246955D01*
X560027Y246990D01*
X560047Y247030D01*
X560147Y247170D01*
X560177Y247200D01*
Y249330D01*
X560187Y249455D01*
X560227Y249580D01*
X560287Y249690D01*
X560367Y249790D01*
X560467Y249870D01*
X560577Y249930D01*
X560702Y249970D01*
X560827Y249980D01*
G37*
G36*
G01X565551D02*
X565676Y249970D01*
X565801Y249930D01*
X565911Y249870D01*
X566011Y249790D01*
X566091Y249690D01*
X566151Y249580D01*
X566191Y249455D01*
X566201Y249330D01*
Y247205D01*
X566231Y247175D01*
X566256Y247140D01*
X566286Y247105D01*
X566306Y247070D01*
X566331Y247035D01*
X566371Y246955D01*
X566416Y246835D01*
X566426Y246795D01*
X566436Y246750D01*
X566441Y246710D01*
X566451Y246665D01*
Y246495D01*
X566441Y246450D01*
X566436Y246410D01*
X566426Y246365D01*
X566416Y246325D01*
X566371Y246205D01*
X566331Y246125D01*
X566306Y246090D01*
X566286Y246055D01*
X566256Y246020D01*
X566231Y245985D01*
X566201Y245955D01*
Y243530D01*
X566191Y243405D01*
X566151Y243280D01*
X566091Y243170D01*
X566011Y243070D01*
X565911Y242990D01*
X565801Y242930D01*
X565676Y242890D01*
X565551Y242880D01*
X565426Y242890D01*
X565301Y242930D01*
X565191Y242990D01*
X565091Y243070D01*
X565011Y243170D01*
X564951Y243280D01*
X564911Y243405D01*
X564901Y243530D01*
Y245960D01*
X564871Y245990D01*
X564771Y246130D01*
X564751Y246170D01*
X564736Y246205D01*
X564716Y246245D01*
X564701Y246285D01*
X564691Y246325D01*
X564676Y246370D01*
X564671Y246410D01*
X564661Y246450D01*
X564656Y246495D01*
Y246535D01*
X564651Y246580D01*
X564656Y246625D01*
Y246665D01*
X564661Y246710D01*
X564671Y246750D01*
X564676Y246790D01*
X564691Y246835D01*
X564701Y246875D01*
X564716Y246915D01*
X564736Y246955D01*
X564751Y246990D01*
X564771Y247030D01*
X564871Y247170D01*
X564901Y247200D01*
Y249330D01*
X564911Y249455D01*
X564951Y249580D01*
X565011Y249690D01*
X565091Y249790D01*
X565191Y249870D01*
X565301Y249930D01*
X565426Y249970D01*
X565551Y249980D01*
G37*
G36*
G01X570276D02*
X570401Y249970D01*
X570526Y249930D01*
X570636Y249870D01*
X570736Y249790D01*
X570816Y249690D01*
X570876Y249580D01*
X570916Y249455D01*
X570926Y249330D01*
Y247205D01*
X570956Y247175D01*
X570981Y247140D01*
X571011Y247105D01*
X571031Y247070D01*
X571056Y247035D01*
X571096Y246955D01*
X571141Y246835D01*
X571151Y246795D01*
X571161Y246750D01*
X571166Y246710D01*
X571176Y246665D01*
Y246495D01*
X571166Y246450D01*
X571161Y246410D01*
X571151Y246365D01*
X571141Y246325D01*
X571096Y246205D01*
X571056Y246125D01*
X571031Y246090D01*
X571011Y246055D01*
X570981Y246020D01*
X570956Y245985D01*
X570926Y245955D01*
Y243530D01*
X570916Y243405D01*
X570876Y243280D01*
X570816Y243170D01*
X570736Y243070D01*
X570636Y242990D01*
X570526Y242930D01*
X570401Y242890D01*
X570276Y242880D01*
X570151Y242890D01*
X570026Y242930D01*
X569916Y242990D01*
X569816Y243070D01*
X569736Y243170D01*
X569676Y243280D01*
X569636Y243405D01*
X569626Y243530D01*
Y245960D01*
X569596Y245990D01*
X569496Y246130D01*
X569476Y246170D01*
X569461Y246205D01*
X569441Y246245D01*
X569426Y246285D01*
X569416Y246325D01*
X569401Y246370D01*
X569396Y246410D01*
X569386Y246450D01*
X569381Y246495D01*
Y246535D01*
X569376Y246580D01*
X569381Y246625D01*
Y246665D01*
X569386Y246710D01*
X569396Y246750D01*
X569401Y246790D01*
X569416Y246835D01*
X569426Y246875D01*
X569441Y246915D01*
X569461Y246955D01*
X569476Y246990D01*
X569496Y247030D01*
X569596Y247170D01*
X569626Y247200D01*
Y249330D01*
X569636Y249455D01*
X569676Y249580D01*
X569736Y249690D01*
X569816Y249790D01*
X569916Y249870D01*
X570026Y249930D01*
X570151Y249970D01*
X570276Y249980D01*
G37*
G36*
G01X575000D02*
X575125Y249970D01*
X575250Y249930D01*
X575360Y249870D01*
X575460Y249790D01*
X575540Y249690D01*
X575600Y249580D01*
X575640Y249455D01*
X575650Y249330D01*
Y247205D01*
X575680Y247175D01*
X575705Y247140D01*
X575735Y247105D01*
X575755Y247070D01*
X575780Y247035D01*
X575820Y246955D01*
X575865Y246835D01*
X575875Y246795D01*
X575885Y246750D01*
X575890Y246710D01*
X575900Y246665D01*
Y246495D01*
X575890Y246450D01*
X575885Y246410D01*
X575875Y246365D01*
X575865Y246325D01*
X575820Y246205D01*
X575780Y246125D01*
X575755Y246090D01*
X575735Y246055D01*
X575705Y246020D01*
X575680Y245985D01*
X575650Y245955D01*
Y243530D01*
X575640Y243405D01*
X575600Y243280D01*
X575540Y243170D01*
X575460Y243070D01*
X575360Y242990D01*
X575250Y242930D01*
X575125Y242890D01*
X575000Y242880D01*
X574875Y242890D01*
X574750Y242930D01*
X574640Y242990D01*
X574540Y243070D01*
X574460Y243170D01*
X574400Y243280D01*
X574360Y243405D01*
X574350Y243530D01*
Y245960D01*
X574320Y245990D01*
X574220Y246130D01*
X574200Y246170D01*
X574185Y246205D01*
X574165Y246245D01*
X574150Y246285D01*
X574140Y246325D01*
X574125Y246370D01*
X574120Y246410D01*
X574110Y246450D01*
X574105Y246495D01*
Y246535D01*
X574100Y246580D01*
X574105Y246625D01*
Y246665D01*
X574110Y246710D01*
X574120Y246750D01*
X574125Y246790D01*
X574140Y246835D01*
X574150Y246875D01*
X574165Y246915D01*
X574185Y246955D01*
X574200Y246990D01*
X574220Y247030D01*
X574320Y247170D01*
X574350Y247200D01*
Y249330D01*
X574360Y249455D01*
X574400Y249580D01*
X574460Y249690D01*
X574540Y249790D01*
X574640Y249870D01*
X574750Y249930D01*
X574875Y249970D01*
X575000Y249980D01*
G37*
G36*
G01X579725D02*
X579850Y249970D01*
X579975Y249930D01*
X580085Y249870D01*
X580185Y249790D01*
X580265Y249690D01*
X580325Y249580D01*
X580365Y249455D01*
X580375Y249330D01*
Y247205D01*
X580405Y247175D01*
X580430Y247140D01*
X580460Y247105D01*
X580480Y247070D01*
X580505Y247035D01*
X580545Y246955D01*
X580590Y246835D01*
X580600Y246795D01*
X580610Y246750D01*
X580615Y246710D01*
X580625Y246665D01*
Y246495D01*
X580615Y246450D01*
X580610Y246410D01*
X580600Y246365D01*
X580590Y246325D01*
X580545Y246205D01*
X580505Y246125D01*
X580480Y246090D01*
X580460Y246055D01*
X580430Y246020D01*
X580405Y245985D01*
X580375Y245955D01*
Y243530D01*
X580365Y243405D01*
X580325Y243280D01*
X580265Y243170D01*
X580185Y243070D01*
X580085Y242990D01*
X579975Y242930D01*
X579850Y242890D01*
X579725Y242880D01*
X579600Y242890D01*
X579475Y242930D01*
X579365Y242990D01*
X579265Y243070D01*
X579185Y243170D01*
X579125Y243280D01*
X579085Y243405D01*
X579075Y243530D01*
Y245960D01*
X579045Y245990D01*
X578945Y246130D01*
X578925Y246170D01*
X578910Y246205D01*
X578890Y246245D01*
X578875Y246285D01*
X578865Y246325D01*
X578850Y246370D01*
X578845Y246410D01*
X578835Y246450D01*
X578830Y246495D01*
Y246535D01*
X578825Y246580D01*
X578830Y246625D01*
Y246665D01*
X578835Y246710D01*
X578845Y246750D01*
X578850Y246790D01*
X578865Y246835D01*
X578875Y246875D01*
X578890Y246915D01*
X578910Y246955D01*
X578925Y246990D01*
X578945Y247030D01*
X579045Y247170D01*
X579075Y247200D01*
Y249330D01*
X579085Y249455D01*
X579125Y249580D01*
X579185Y249690D01*
X579265Y249790D01*
X579365Y249870D01*
X579475Y249930D01*
X579600Y249970D01*
X579725Y249980D01*
G37*
G36*
G01X584449D02*
X584574Y249970D01*
X584699Y249930D01*
X584809Y249870D01*
X584909Y249790D01*
X584989Y249690D01*
X585049Y249580D01*
X585089Y249455D01*
X585099Y249330D01*
Y247205D01*
X585129Y247175D01*
X585154Y247140D01*
X585184Y247105D01*
X585204Y247070D01*
X585229Y247035D01*
X585269Y246955D01*
X585314Y246835D01*
X585324Y246795D01*
X585334Y246750D01*
X585339Y246710D01*
X585349Y246665D01*
Y246495D01*
X585339Y246450D01*
X585334Y246410D01*
X585324Y246365D01*
X585314Y246325D01*
X585269Y246205D01*
X585229Y246125D01*
X585204Y246090D01*
X585184Y246055D01*
X585154Y246020D01*
X585129Y245985D01*
X585099Y245955D01*
Y243530D01*
X585089Y243405D01*
X585049Y243280D01*
X584989Y243170D01*
X584909Y243070D01*
X584809Y242990D01*
X584699Y242930D01*
X584574Y242890D01*
X584449Y242880D01*
X584324Y242890D01*
X584199Y242930D01*
X584089Y242990D01*
X583989Y243070D01*
X583909Y243170D01*
X583849Y243280D01*
X583809Y243405D01*
X583799Y243530D01*
Y245960D01*
X583769Y245990D01*
X583669Y246130D01*
X583649Y246170D01*
X583634Y246205D01*
X583614Y246245D01*
X583599Y246285D01*
X583589Y246325D01*
X583574Y246370D01*
X583569Y246410D01*
X583559Y246450D01*
X583554Y246495D01*
Y246535D01*
X583549Y246580D01*
X583554Y246625D01*
Y246665D01*
X583559Y246710D01*
X583569Y246750D01*
X583574Y246790D01*
X583589Y246835D01*
X583599Y246875D01*
X583614Y246915D01*
X583634Y246955D01*
X583649Y246990D01*
X583669Y247030D01*
X583769Y247170D01*
X583799Y247200D01*
Y249330D01*
X583809Y249455D01*
X583849Y249580D01*
X583909Y249690D01*
X583989Y249790D01*
X584089Y249870D01*
X584199Y249930D01*
X584324Y249970D01*
X584449Y249980D01*
G37*
G36*
G01X589173D02*
X589298Y249970D01*
X589423Y249930D01*
X589533Y249870D01*
X589633Y249790D01*
X589713Y249690D01*
X589773Y249580D01*
X589813Y249455D01*
X589823Y249330D01*
Y247205D01*
X589853Y247175D01*
X589878Y247140D01*
X589908Y247105D01*
X589928Y247070D01*
X589953Y247035D01*
X589993Y246955D01*
X590038Y246835D01*
X590048Y246795D01*
X590058Y246750D01*
X590063Y246710D01*
X590073Y246665D01*
Y246495D01*
X590063Y246450D01*
X590058Y246410D01*
X590048Y246365D01*
X590038Y246325D01*
X589993Y246205D01*
X589953Y246125D01*
X589928Y246090D01*
X589908Y246055D01*
X589878Y246020D01*
X589853Y245985D01*
X589823Y245955D01*
Y243530D01*
X589813Y243405D01*
X589773Y243280D01*
X589713Y243170D01*
X589633Y243070D01*
X589533Y242990D01*
X589423Y242930D01*
X589298Y242890D01*
X589173Y242880D01*
X589048Y242890D01*
X588923Y242930D01*
X588813Y242990D01*
X588713Y243070D01*
X588633Y243170D01*
X588573Y243280D01*
X588533Y243405D01*
X588523Y243530D01*
Y245960D01*
X588493Y245990D01*
X588393Y246130D01*
X588373Y246170D01*
X588358Y246205D01*
X588338Y246245D01*
X588323Y246285D01*
X588313Y246325D01*
X588298Y246370D01*
X588293Y246410D01*
X588283Y246450D01*
X588278Y246495D01*
Y246535D01*
X588273Y246580D01*
X588278Y246625D01*
Y246665D01*
X588283Y246710D01*
X588293Y246750D01*
X588298Y246790D01*
X588313Y246835D01*
X588323Y246875D01*
X588338Y246915D01*
X588358Y246955D01*
X588373Y246990D01*
X588393Y247030D01*
X588493Y247170D01*
X588523Y247200D01*
Y249330D01*
X588533Y249455D01*
X588573Y249580D01*
X588633Y249690D01*
X588713Y249790D01*
X588813Y249870D01*
X588923Y249930D01*
X589048Y249970D01*
X589173Y249980D01*
G37*
G36*
G01X593898D02*
X594023Y249970D01*
X594148Y249930D01*
X594258Y249870D01*
X594358Y249790D01*
X594438Y249690D01*
X594498Y249580D01*
X594538Y249455D01*
X594548Y249330D01*
Y247205D01*
X594578Y247175D01*
X594603Y247140D01*
X594633Y247105D01*
X594653Y247070D01*
X594678Y247035D01*
X594718Y246955D01*
X594763Y246835D01*
X594773Y246795D01*
X594783Y246750D01*
X594788Y246710D01*
X594798Y246665D01*
Y246495D01*
X594788Y246450D01*
X594783Y246410D01*
X594773Y246365D01*
X594763Y246325D01*
X594718Y246205D01*
X594678Y246125D01*
X594653Y246090D01*
X594633Y246055D01*
X594603Y246020D01*
X594578Y245985D01*
X594548Y245955D01*
Y243530D01*
X594538Y243405D01*
X594498Y243280D01*
X594438Y243170D01*
X594358Y243070D01*
X594258Y242990D01*
X594148Y242930D01*
X594023Y242890D01*
X593898Y242880D01*
X593773Y242890D01*
X593648Y242930D01*
X593538Y242990D01*
X593438Y243070D01*
X593358Y243170D01*
X593298Y243280D01*
X593258Y243405D01*
X593248Y243530D01*
Y245960D01*
X593218Y245990D01*
X593118Y246130D01*
X593098Y246170D01*
X593083Y246205D01*
X593063Y246245D01*
X593048Y246285D01*
X593038Y246325D01*
X593023Y246370D01*
X593018Y246410D01*
X593008Y246450D01*
X593003Y246495D01*
Y246535D01*
X592998Y246580D01*
X593003Y246625D01*
Y246665D01*
X593008Y246710D01*
X593018Y246750D01*
X593023Y246790D01*
X593038Y246835D01*
X593048Y246875D01*
X593063Y246915D01*
X593083Y246955D01*
X593098Y246990D01*
X593118Y247030D01*
X593218Y247170D01*
X593248Y247200D01*
Y249330D01*
X593258Y249455D01*
X593298Y249580D01*
X593358Y249690D01*
X593438Y249790D01*
X593538Y249870D01*
X593648Y249930D01*
X593773Y249970D01*
X593898Y249980D01*
G37*
G36*
G01X598622D02*
X598747Y249970D01*
X598872Y249930D01*
X598982Y249870D01*
X599082Y249790D01*
X599162Y249690D01*
X599222Y249580D01*
X599262Y249455D01*
X599272Y249330D01*
Y247205D01*
X599302Y247175D01*
X599327Y247140D01*
X599357Y247105D01*
X599377Y247070D01*
X599402Y247035D01*
X599442Y246955D01*
X599487Y246835D01*
X599497Y246795D01*
X599507Y246750D01*
X599512Y246710D01*
X599522Y246665D01*
Y246495D01*
X599512Y246450D01*
X599507Y246410D01*
X599497Y246365D01*
X599487Y246325D01*
X599442Y246205D01*
X599402Y246125D01*
X599377Y246090D01*
X599357Y246055D01*
X599327Y246020D01*
X599302Y245985D01*
X599272Y245955D01*
Y243530D01*
X599262Y243405D01*
X599222Y243280D01*
X599162Y243170D01*
X599082Y243070D01*
X598982Y242990D01*
X598872Y242930D01*
X598747Y242890D01*
X598622Y242880D01*
X598497Y242890D01*
X598372Y242930D01*
X598262Y242990D01*
X598162Y243070D01*
X598082Y243170D01*
X598022Y243280D01*
X597982Y243405D01*
X597972Y243530D01*
Y245960D01*
X597942Y245990D01*
X597842Y246130D01*
X597822Y246170D01*
X597807Y246205D01*
X597787Y246245D01*
X597772Y246285D01*
X597762Y246325D01*
X597747Y246370D01*
X597742Y246410D01*
X597732Y246450D01*
X597727Y246495D01*
Y246535D01*
X597722Y246580D01*
X597727Y246625D01*
Y246665D01*
X597732Y246710D01*
X597742Y246750D01*
X597747Y246790D01*
X597762Y246835D01*
X597772Y246875D01*
X597787Y246915D01*
X597807Y246955D01*
X597822Y246990D01*
X597842Y247030D01*
X597942Y247170D01*
X597972Y247200D01*
Y249330D01*
X597982Y249455D01*
X598022Y249580D01*
X598082Y249690D01*
X598162Y249790D01*
X598262Y249870D01*
X598372Y249930D01*
X598497Y249970D01*
X598622Y249980D01*
G37*
G36*
G01X603347D02*
X603472Y249970D01*
X603597Y249930D01*
X603707Y249870D01*
X603807Y249790D01*
X603887Y249690D01*
X603947Y249580D01*
X603987Y249455D01*
X603997Y249330D01*
Y247205D01*
X604027Y247175D01*
X604052Y247140D01*
X604082Y247105D01*
X604102Y247070D01*
X604127Y247035D01*
X604167Y246955D01*
X604212Y246835D01*
X604222Y246795D01*
X604232Y246750D01*
X604237Y246710D01*
X604247Y246665D01*
Y246495D01*
X604237Y246450D01*
X604232Y246410D01*
X604222Y246365D01*
X604212Y246325D01*
X604167Y246205D01*
X604127Y246125D01*
X604102Y246090D01*
X604082Y246055D01*
X604052Y246020D01*
X604027Y245985D01*
X603997Y245955D01*
Y243530D01*
X603987Y243405D01*
X603947Y243280D01*
X603887Y243170D01*
X603807Y243070D01*
X603707Y242990D01*
X603597Y242930D01*
X603472Y242890D01*
X603347Y242880D01*
X603222Y242890D01*
X603097Y242930D01*
X602987Y242990D01*
X602887Y243070D01*
X602807Y243170D01*
X602747Y243280D01*
X602707Y243405D01*
X602697Y243530D01*
Y245960D01*
X602667Y245990D01*
X602567Y246130D01*
X602547Y246170D01*
X602532Y246205D01*
X602512Y246245D01*
X602497Y246285D01*
X602487Y246325D01*
X602472Y246370D01*
X602467Y246410D01*
X602457Y246450D01*
X602452Y246495D01*
Y246535D01*
X602447Y246580D01*
X602452Y246625D01*
Y246665D01*
X602457Y246710D01*
X602467Y246750D01*
X602472Y246790D01*
X602487Y246835D01*
X602497Y246875D01*
X602512Y246915D01*
X602532Y246955D01*
X602547Y246990D01*
X602567Y247030D01*
X602667Y247170D01*
X602697Y247200D01*
Y249330D01*
X602707Y249455D01*
X602747Y249580D01*
X602807Y249690D01*
X602887Y249790D01*
X602987Y249870D01*
X603097Y249930D01*
X603222Y249970D01*
X603347Y249980D01*
G37*
G36*
G01X608071D02*
X608196Y249970D01*
X608321Y249930D01*
X608431Y249870D01*
X608531Y249790D01*
X608611Y249690D01*
X608671Y249580D01*
X608711Y249455D01*
X608721Y249330D01*
Y247205D01*
X608751Y247175D01*
X608776Y247140D01*
X608806Y247105D01*
X608826Y247070D01*
X608851Y247035D01*
X608891Y246955D01*
X608936Y246835D01*
X608946Y246795D01*
X608956Y246750D01*
X608961Y246710D01*
X608971Y246665D01*
Y246495D01*
X608961Y246450D01*
X608956Y246410D01*
X608946Y246365D01*
X608936Y246325D01*
X608891Y246205D01*
X608851Y246125D01*
X608826Y246090D01*
X608806Y246055D01*
X608776Y246020D01*
X608751Y245985D01*
X608721Y245955D01*
Y243530D01*
X608711Y243405D01*
X608671Y243280D01*
X608611Y243170D01*
X608531Y243070D01*
X608431Y242990D01*
X608321Y242930D01*
X608196Y242890D01*
X608071Y242880D01*
X607946Y242890D01*
X607821Y242930D01*
X607711Y242990D01*
X607611Y243070D01*
X607531Y243170D01*
X607471Y243280D01*
X607431Y243405D01*
X607421Y243530D01*
Y245960D01*
X607391Y245990D01*
X607291Y246130D01*
X607271Y246170D01*
X607256Y246205D01*
X607236Y246245D01*
X607221Y246285D01*
X607211Y246325D01*
X607196Y246370D01*
X607191Y246410D01*
X607181Y246450D01*
X607176Y246495D01*
Y246535D01*
X607171Y246580D01*
X607176Y246625D01*
Y246665D01*
X607181Y246710D01*
X607191Y246750D01*
X607196Y246790D01*
X607211Y246835D01*
X607221Y246875D01*
X607236Y246915D01*
X607256Y246955D01*
X607271Y246990D01*
X607291Y247030D01*
X607391Y247170D01*
X607421Y247200D01*
Y249330D01*
X607431Y249455D01*
X607471Y249580D01*
X607531Y249690D01*
X607611Y249790D01*
X607711Y249870D01*
X607821Y249930D01*
X607946Y249970D01*
X608071Y249980D01*
G37*
G36*
G01X612796D02*
X612921Y249970D01*
X613046Y249930D01*
X613156Y249870D01*
X613256Y249790D01*
X613336Y249690D01*
X613396Y249580D01*
X613436Y249455D01*
X613446Y249330D01*
Y247205D01*
X613476Y247175D01*
X613501Y247140D01*
X613531Y247105D01*
X613551Y247070D01*
X613576Y247035D01*
X613616Y246955D01*
X613661Y246835D01*
X613671Y246795D01*
X613681Y246750D01*
X613686Y246710D01*
X613696Y246665D01*
Y246495D01*
X613686Y246450D01*
X613681Y246410D01*
X613671Y246365D01*
X613661Y246325D01*
X613616Y246205D01*
X613576Y246125D01*
X613551Y246090D01*
X613531Y246055D01*
X613501Y246020D01*
X613476Y245985D01*
X613446Y245955D01*
Y243530D01*
X613436Y243405D01*
X613396Y243280D01*
X613336Y243170D01*
X613256Y243070D01*
X613156Y242990D01*
X613046Y242930D01*
X612921Y242890D01*
X612796Y242880D01*
X612671Y242890D01*
X612546Y242930D01*
X612436Y242990D01*
X612336Y243070D01*
X612256Y243170D01*
X612196Y243280D01*
X612156Y243405D01*
X612146Y243530D01*
Y245960D01*
X612116Y245990D01*
X612016Y246130D01*
X611996Y246170D01*
X611981Y246205D01*
X611961Y246245D01*
X611946Y246285D01*
X611936Y246325D01*
X611921Y246370D01*
X611916Y246410D01*
X611906Y246450D01*
X611901Y246495D01*
Y246535D01*
X611896Y246580D01*
X611901Y246625D01*
Y246665D01*
X611906Y246710D01*
X611916Y246750D01*
X611921Y246790D01*
X611936Y246835D01*
X611946Y246875D01*
X611961Y246915D01*
X611981Y246955D01*
X611996Y246990D01*
X612016Y247030D01*
X612116Y247170D01*
X612146Y247200D01*
Y249330D01*
X612156Y249455D01*
X612196Y249580D01*
X612256Y249690D01*
X612336Y249790D01*
X612436Y249870D01*
X612546Y249930D01*
X612671Y249970D01*
X612796Y249980D01*
G37*
G36*
G01X617520D02*
X617645Y249970D01*
X617770Y249930D01*
X617880Y249870D01*
X617980Y249790D01*
X618060Y249690D01*
X618120Y249580D01*
X618160Y249455D01*
X618170Y249330D01*
Y247205D01*
X618200Y247175D01*
X618225Y247140D01*
X618255Y247105D01*
X618275Y247070D01*
X618300Y247035D01*
X618340Y246955D01*
X618385Y246835D01*
X618395Y246795D01*
X618405Y246750D01*
X618410Y246710D01*
X618420Y246665D01*
Y246495D01*
X618410Y246450D01*
X618405Y246410D01*
X618395Y246365D01*
X618385Y246325D01*
X618340Y246205D01*
X618300Y246125D01*
X618275Y246090D01*
X618255Y246055D01*
X618225Y246020D01*
X618200Y245985D01*
X618170Y245955D01*
Y243530D01*
X618160Y243405D01*
X618120Y243280D01*
X618060Y243170D01*
X617980Y243070D01*
X617880Y242990D01*
X617770Y242930D01*
X617645Y242890D01*
X617520Y242880D01*
X617395Y242890D01*
X617270Y242930D01*
X617160Y242990D01*
X617060Y243070D01*
X616980Y243170D01*
X616920Y243280D01*
X616880Y243405D01*
X616870Y243530D01*
Y245960D01*
X616840Y245990D01*
X616740Y246130D01*
X616720Y246170D01*
X616705Y246205D01*
X616685Y246245D01*
X616670Y246285D01*
X616660Y246325D01*
X616645Y246370D01*
X616640Y246410D01*
X616630Y246450D01*
X616625Y246495D01*
Y246535D01*
X616620Y246580D01*
X616625Y246625D01*
Y246665D01*
X616630Y246710D01*
X616640Y246750D01*
X616645Y246790D01*
X616660Y246835D01*
X616670Y246875D01*
X616685Y246915D01*
X616705Y246955D01*
X616720Y246990D01*
X616740Y247030D01*
X616840Y247170D01*
X616870Y247200D01*
Y249330D01*
X616880Y249455D01*
X616920Y249580D01*
X616980Y249690D01*
X617060Y249790D01*
X617160Y249870D01*
X617270Y249930D01*
X617395Y249970D01*
X617520Y249980D01*
G37*
G36*
G01X622244D02*
X622369Y249970D01*
X622494Y249930D01*
X622604Y249870D01*
X622704Y249790D01*
X622784Y249690D01*
X622844Y249580D01*
X622884Y249455D01*
X622894Y249330D01*
Y247205D01*
X622924Y247175D01*
X622949Y247140D01*
X622979Y247105D01*
X622999Y247070D01*
X623024Y247035D01*
X623064Y246955D01*
X623109Y246835D01*
X623119Y246795D01*
X623129Y246750D01*
X623134Y246710D01*
X623144Y246665D01*
Y246495D01*
X623134Y246450D01*
X623129Y246410D01*
X623119Y246365D01*
X623109Y246325D01*
X623064Y246205D01*
X623024Y246125D01*
X622999Y246090D01*
X622979Y246055D01*
X622949Y246020D01*
X622924Y245985D01*
X622894Y245955D01*
Y243530D01*
X622884Y243405D01*
X622844Y243280D01*
X622784Y243170D01*
X622704Y243070D01*
X622604Y242990D01*
X622494Y242930D01*
X622369Y242890D01*
X622244Y242880D01*
X622119Y242890D01*
X621994Y242930D01*
X621884Y242990D01*
X621784Y243070D01*
X621704Y243170D01*
X621644Y243280D01*
X621604Y243405D01*
X621594Y243530D01*
Y245960D01*
X621564Y245990D01*
X621464Y246130D01*
X621444Y246170D01*
X621429Y246205D01*
X621409Y246245D01*
X621394Y246285D01*
X621384Y246325D01*
X621369Y246370D01*
X621364Y246410D01*
X621354Y246450D01*
X621349Y246495D01*
Y246535D01*
X621344Y246580D01*
X621349Y246625D01*
Y246665D01*
X621354Y246710D01*
X621364Y246750D01*
X621369Y246790D01*
X621384Y246835D01*
X621394Y246875D01*
X621409Y246915D01*
X621429Y246955D01*
X621444Y246990D01*
X621464Y247030D01*
X621564Y247170D01*
X621594Y247200D01*
Y249330D01*
X621604Y249455D01*
X621644Y249580D01*
X621704Y249690D01*
X621784Y249790D01*
X621884Y249870D01*
X621994Y249930D01*
X622119Y249970D01*
X622244Y249980D01*
G37*
G36*
G01X626969D02*
X627094Y249970D01*
X627219Y249930D01*
X627329Y249870D01*
X627429Y249790D01*
X627509Y249690D01*
X627569Y249580D01*
X627609Y249455D01*
X627619Y249330D01*
Y247205D01*
X627649Y247175D01*
X627674Y247140D01*
X627704Y247105D01*
X627724Y247070D01*
X627749Y247035D01*
X627789Y246955D01*
X627834Y246835D01*
X627844Y246795D01*
X627854Y246750D01*
X627859Y246710D01*
X627869Y246665D01*
Y246495D01*
X627859Y246450D01*
X627854Y246410D01*
X627844Y246365D01*
X627834Y246325D01*
X627789Y246205D01*
X627749Y246125D01*
X627724Y246090D01*
X627704Y246055D01*
X627674Y246020D01*
X627649Y245985D01*
X627619Y245955D01*
Y243530D01*
X627609Y243405D01*
X627569Y243280D01*
X627509Y243170D01*
X627429Y243070D01*
X627329Y242990D01*
X627219Y242930D01*
X627094Y242890D01*
X626969Y242880D01*
X626844Y242890D01*
X626719Y242930D01*
X626609Y242990D01*
X626509Y243070D01*
X626429Y243170D01*
X626369Y243280D01*
X626329Y243405D01*
X626319Y243530D01*
Y245960D01*
X626289Y245990D01*
X626189Y246130D01*
X626169Y246170D01*
X626154Y246205D01*
X626134Y246245D01*
X626119Y246285D01*
X626109Y246325D01*
X626094Y246370D01*
X626089Y246410D01*
X626079Y246450D01*
X626074Y246495D01*
Y246535D01*
X626069Y246580D01*
X626074Y246625D01*
Y246665D01*
X626079Y246710D01*
X626089Y246750D01*
X626094Y246790D01*
X626109Y246835D01*
X626119Y246875D01*
X626134Y246915D01*
X626154Y246955D01*
X626169Y246990D01*
X626189Y247030D01*
X626289Y247170D01*
X626319Y247200D01*
Y249330D01*
X626329Y249455D01*
X626369Y249580D01*
X626429Y249690D01*
X626509Y249790D01*
X626609Y249870D01*
X626719Y249930D01*
X626844Y249970D01*
X626969Y249980D01*
G37*
G36*
G01X631693D02*
X631818Y249970D01*
X631943Y249930D01*
X632053Y249870D01*
X632153Y249790D01*
X632233Y249690D01*
X632293Y249580D01*
X632333Y249455D01*
X632343Y249330D01*
Y247205D01*
X632373Y247175D01*
X632398Y247140D01*
X632428Y247105D01*
X632448Y247070D01*
X632473Y247035D01*
X632513Y246955D01*
X632558Y246835D01*
X632568Y246795D01*
X632578Y246750D01*
X632583Y246710D01*
X632593Y246665D01*
Y246495D01*
X632583Y246450D01*
X632578Y246410D01*
X632568Y246365D01*
X632558Y246325D01*
X632513Y246205D01*
X632473Y246125D01*
X632448Y246090D01*
X632428Y246055D01*
X632398Y246020D01*
X632373Y245985D01*
X632343Y245955D01*
Y243530D01*
X632333Y243405D01*
X632293Y243280D01*
X632233Y243170D01*
X632153Y243070D01*
X632053Y242990D01*
X631943Y242930D01*
X631818Y242890D01*
X631693Y242880D01*
X631568Y242890D01*
X631443Y242930D01*
X631333Y242990D01*
X631233Y243070D01*
X631153Y243170D01*
X631093Y243280D01*
X631053Y243405D01*
X631043Y243530D01*
Y245960D01*
X631013Y245990D01*
X630913Y246130D01*
X630893Y246170D01*
X630878Y246205D01*
X630858Y246245D01*
X630843Y246285D01*
X630833Y246325D01*
X630818Y246370D01*
X630813Y246410D01*
X630803Y246450D01*
X630798Y246495D01*
Y246535D01*
X630793Y246580D01*
X630798Y246625D01*
Y246665D01*
X630803Y246710D01*
X630813Y246750D01*
X630818Y246790D01*
X630833Y246835D01*
X630843Y246875D01*
X630858Y246915D01*
X630878Y246955D01*
X630893Y246990D01*
X630913Y247030D01*
X631013Y247170D01*
X631043Y247200D01*
Y249330D01*
X631053Y249455D01*
X631093Y249580D01*
X631153Y249690D01*
X631233Y249790D01*
X631333Y249870D01*
X631443Y249930D01*
X631568Y249970D01*
X631693Y249980D01*
G37*
G36*
G01X636418D02*
X636543Y249970D01*
X636668Y249930D01*
X636778Y249870D01*
X636878Y249790D01*
X636958Y249690D01*
X637018Y249580D01*
X637058Y249455D01*
X637068Y249330D01*
Y247205D01*
X637098Y247175D01*
X637123Y247140D01*
X637153Y247105D01*
X637173Y247070D01*
X637198Y247035D01*
X637238Y246955D01*
X637283Y246835D01*
X637293Y246795D01*
X637303Y246750D01*
X637308Y246710D01*
X637318Y246665D01*
Y246495D01*
X637308Y246450D01*
X637303Y246410D01*
X637293Y246365D01*
X637283Y246325D01*
X637238Y246205D01*
X637198Y246125D01*
X637173Y246090D01*
X637153Y246055D01*
X637123Y246020D01*
X637098Y245985D01*
X637068Y245955D01*
Y243530D01*
X637058Y243405D01*
X637018Y243280D01*
X636958Y243170D01*
X636878Y243070D01*
X636778Y242990D01*
X636668Y242930D01*
X636543Y242890D01*
X636418Y242880D01*
X636293Y242890D01*
X636168Y242930D01*
X636058Y242990D01*
X635958Y243070D01*
X635878Y243170D01*
X635818Y243280D01*
X635778Y243405D01*
X635768Y243530D01*
Y245960D01*
X635738Y245990D01*
X635638Y246130D01*
X635618Y246170D01*
X635603Y246205D01*
X635583Y246245D01*
X635568Y246285D01*
X635558Y246325D01*
X635543Y246370D01*
X635538Y246410D01*
X635528Y246450D01*
X635523Y246495D01*
Y246535D01*
X635518Y246580D01*
X635523Y246625D01*
Y246665D01*
X635528Y246710D01*
X635538Y246750D01*
X635543Y246790D01*
X635558Y246835D01*
X635568Y246875D01*
X635583Y246915D01*
X635603Y246955D01*
X635618Y246990D01*
X635638Y247030D01*
X635738Y247170D01*
X635768Y247200D01*
Y249330D01*
X635778Y249455D01*
X635818Y249580D01*
X635878Y249690D01*
X635958Y249790D01*
X636058Y249870D01*
X636168Y249930D01*
X636293Y249970D01*
X636418Y249980D01*
G37*
G36*
G01X641142D02*
X641267Y249970D01*
X641392Y249930D01*
X641502Y249870D01*
X641602Y249790D01*
X641682Y249690D01*
X641742Y249580D01*
X641782Y249455D01*
X641792Y249330D01*
Y247205D01*
X641822Y247175D01*
X641847Y247140D01*
X641877Y247105D01*
X641897Y247070D01*
X641922Y247035D01*
X641962Y246955D01*
X642007Y246835D01*
X642017Y246795D01*
X642027Y246750D01*
X642032Y246710D01*
X642042Y246665D01*
Y246495D01*
X642032Y246450D01*
X642027Y246410D01*
X642017Y246365D01*
X642007Y246325D01*
X641962Y246205D01*
X641922Y246125D01*
X641897Y246090D01*
X641877Y246055D01*
X641847Y246020D01*
X641822Y245985D01*
X641792Y245955D01*
Y243530D01*
X641782Y243405D01*
X641742Y243280D01*
X641682Y243170D01*
X641602Y243070D01*
X641502Y242990D01*
X641392Y242930D01*
X641267Y242890D01*
X641142Y242880D01*
X641017Y242890D01*
X640892Y242930D01*
X640782Y242990D01*
X640682Y243070D01*
X640602Y243170D01*
X640542Y243280D01*
X640502Y243405D01*
X640492Y243530D01*
Y245960D01*
X640462Y245990D01*
X640362Y246130D01*
X640342Y246170D01*
X640327Y246205D01*
X640307Y246245D01*
X640292Y246285D01*
X640282Y246325D01*
X640267Y246370D01*
X640262Y246410D01*
X640252Y246450D01*
X640247Y246495D01*
Y246535D01*
X640242Y246580D01*
X640247Y246625D01*
Y246665D01*
X640252Y246710D01*
X640262Y246750D01*
X640267Y246790D01*
X640282Y246835D01*
X640292Y246875D01*
X640307Y246915D01*
X640327Y246955D01*
X640342Y246990D01*
X640362Y247030D01*
X640462Y247170D01*
X640492Y247200D01*
Y249330D01*
X640502Y249455D01*
X640542Y249580D01*
X640602Y249690D01*
X640682Y249790D01*
X640782Y249870D01*
X640892Y249930D01*
X641017Y249970D01*
X641142Y249980D01*
G37*
G36*
G01X645866D02*
X645991Y249970D01*
X646116Y249930D01*
X646226Y249870D01*
X646326Y249790D01*
X646406Y249690D01*
X646466Y249580D01*
X646506Y249455D01*
X646516Y249330D01*
Y247205D01*
X646546Y247175D01*
X646571Y247140D01*
X646601Y247105D01*
X646621Y247070D01*
X646646Y247035D01*
X646686Y246955D01*
X646731Y246835D01*
X646741Y246795D01*
X646751Y246750D01*
X646756Y246710D01*
X646766Y246665D01*
Y246495D01*
X646756Y246450D01*
X646751Y246410D01*
X646741Y246365D01*
X646731Y246325D01*
X646686Y246205D01*
X646646Y246125D01*
X646621Y246090D01*
X646601Y246055D01*
X646571Y246020D01*
X646546Y245985D01*
X646516Y245955D01*
Y243530D01*
X646506Y243405D01*
X646466Y243280D01*
X646406Y243170D01*
X646326Y243070D01*
X646226Y242990D01*
X646116Y242930D01*
X645991Y242890D01*
X645866Y242880D01*
X645741Y242890D01*
X645616Y242930D01*
X645506Y242990D01*
X645406Y243070D01*
X645326Y243170D01*
X645266Y243280D01*
X645226Y243405D01*
X645216Y243530D01*
Y245960D01*
X645186Y245990D01*
X645086Y246130D01*
X645066Y246170D01*
X645051Y246205D01*
X645031Y246245D01*
X645016Y246285D01*
X645006Y246325D01*
X644991Y246370D01*
X644986Y246410D01*
X644976Y246450D01*
X644971Y246495D01*
Y246535D01*
X644966Y246580D01*
X644971Y246625D01*
Y246665D01*
X644976Y246710D01*
X644986Y246750D01*
X644991Y246790D01*
X645006Y246835D01*
X645016Y246875D01*
X645031Y246915D01*
X645051Y246955D01*
X645066Y246990D01*
X645086Y247030D01*
X645186Y247170D01*
X645216Y247200D01*
Y249330D01*
X645226Y249455D01*
X645266Y249580D01*
X645326Y249690D01*
X645406Y249790D01*
X645506Y249870D01*
X645616Y249930D01*
X645741Y249970D01*
X645866Y249980D01*
G37*
G36*
G01X650591D02*
X650716Y249970D01*
X650841Y249930D01*
X650951Y249870D01*
X651051Y249790D01*
X651131Y249690D01*
X651191Y249580D01*
X651231Y249455D01*
X651241Y249330D01*
Y247205D01*
X651271Y247175D01*
X651296Y247140D01*
X651326Y247105D01*
X651346Y247070D01*
X651371Y247035D01*
X651411Y246955D01*
X651456Y246835D01*
X651466Y246795D01*
X651476Y246750D01*
X651481Y246710D01*
X651491Y246665D01*
Y246495D01*
X651481Y246450D01*
X651476Y246410D01*
X651466Y246365D01*
X651456Y246325D01*
X651411Y246205D01*
X651371Y246125D01*
X651346Y246090D01*
X651326Y246055D01*
X651296Y246020D01*
X651271Y245985D01*
X651241Y245955D01*
Y243530D01*
X651231Y243405D01*
X651191Y243280D01*
X651131Y243170D01*
X651051Y243070D01*
X650951Y242990D01*
X650841Y242930D01*
X650716Y242890D01*
X650591Y242880D01*
X650466Y242890D01*
X650341Y242930D01*
X650231Y242990D01*
X650131Y243070D01*
X650051Y243170D01*
X649991Y243280D01*
X649951Y243405D01*
X649941Y243530D01*
Y245960D01*
X649911Y245990D01*
X649811Y246130D01*
X649791Y246170D01*
X649776Y246205D01*
X649756Y246245D01*
X649741Y246285D01*
X649731Y246325D01*
X649716Y246370D01*
X649711Y246410D01*
X649701Y246450D01*
X649696Y246495D01*
Y246535D01*
X649691Y246580D01*
X649696Y246625D01*
Y246665D01*
X649701Y246710D01*
X649711Y246750D01*
X649716Y246790D01*
X649731Y246835D01*
X649741Y246875D01*
X649756Y246915D01*
X649776Y246955D01*
X649791Y246990D01*
X649811Y247030D01*
X649911Y247170D01*
X649941Y247200D01*
Y249330D01*
X649951Y249455D01*
X649991Y249580D01*
X650051Y249690D01*
X650131Y249790D01*
X650231Y249870D01*
X650341Y249930D01*
X650466Y249970D01*
X650591Y249980D01*
G37*
G36*
G01X664764D02*
X664889Y249970D01*
X665014Y249930D01*
X665124Y249870D01*
X665224Y249790D01*
X665304Y249690D01*
X665364Y249580D01*
X665404Y249455D01*
X665414Y249330D01*
Y247205D01*
X665444Y247175D01*
X665469Y247140D01*
X665499Y247105D01*
X665519Y247070D01*
X665544Y247035D01*
X665584Y246955D01*
X665629Y246835D01*
X665639Y246795D01*
X665649Y246750D01*
X665654Y246710D01*
X665664Y246665D01*
Y246495D01*
X665654Y246450D01*
X665649Y246410D01*
X665639Y246365D01*
X665629Y246325D01*
X665584Y246205D01*
X665544Y246125D01*
X665519Y246090D01*
X665499Y246055D01*
X665469Y246020D01*
X665444Y245985D01*
X665414Y245955D01*
Y243530D01*
X665404Y243405D01*
X665364Y243280D01*
X665304Y243170D01*
X665224Y243070D01*
X665124Y242990D01*
X665014Y242930D01*
X664889Y242890D01*
X664764Y242880D01*
X664639Y242890D01*
X664514Y242930D01*
X664404Y242990D01*
X664304Y243070D01*
X664224Y243170D01*
X664164Y243280D01*
X664124Y243405D01*
X664114Y243530D01*
Y245960D01*
X664084Y245990D01*
X663984Y246130D01*
X663964Y246170D01*
X663949Y246205D01*
X663929Y246245D01*
X663914Y246285D01*
X663904Y246325D01*
X663889Y246370D01*
X663884Y246410D01*
X663874Y246450D01*
X663869Y246495D01*
Y246535D01*
X663864Y246580D01*
X663869Y246625D01*
Y246665D01*
X663874Y246710D01*
X663884Y246750D01*
X663889Y246790D01*
X663904Y246835D01*
X663914Y246875D01*
X663929Y246915D01*
X663949Y246955D01*
X663964Y246990D01*
X663984Y247030D01*
X664084Y247170D01*
X664114Y247200D01*
Y249330D01*
X664124Y249455D01*
X664164Y249580D01*
X664224Y249690D01*
X664304Y249790D01*
X664404Y249870D01*
X664514Y249930D01*
X664639Y249970D01*
X664764Y249980D01*
G37*
G36*
G01X669488D02*
X669613Y249970D01*
X669738Y249930D01*
X669848Y249870D01*
X669948Y249790D01*
X670028Y249690D01*
X670088Y249580D01*
X670128Y249455D01*
X670138Y249330D01*
Y247205D01*
X670168Y247175D01*
X670193Y247140D01*
X670223Y247105D01*
X670243Y247070D01*
X670268Y247035D01*
X670308Y246955D01*
X670353Y246835D01*
X670363Y246795D01*
X670373Y246750D01*
X670378Y246710D01*
X670388Y246665D01*
Y246495D01*
X670378Y246450D01*
X670373Y246410D01*
X670363Y246365D01*
X670353Y246325D01*
X670308Y246205D01*
X670268Y246125D01*
X670243Y246090D01*
X670223Y246055D01*
X670193Y246020D01*
X670168Y245985D01*
X670138Y245955D01*
Y243530D01*
X670128Y243405D01*
X670088Y243280D01*
X670028Y243170D01*
X669948Y243070D01*
X669848Y242990D01*
X669738Y242930D01*
X669613Y242890D01*
X669488Y242880D01*
X669363Y242890D01*
X669238Y242930D01*
X669128Y242990D01*
X669028Y243070D01*
X668948Y243170D01*
X668888Y243280D01*
X668848Y243405D01*
X668838Y243530D01*
Y245960D01*
X668808Y245990D01*
X668708Y246130D01*
X668688Y246170D01*
X668673Y246205D01*
X668653Y246245D01*
X668638Y246285D01*
X668628Y246325D01*
X668613Y246370D01*
X668608Y246410D01*
X668598Y246450D01*
X668593Y246495D01*
Y246535D01*
X668588Y246580D01*
X668593Y246625D01*
Y246665D01*
X668598Y246710D01*
X668608Y246750D01*
X668613Y246790D01*
X668628Y246835D01*
X668638Y246875D01*
X668653Y246915D01*
X668673Y246955D01*
X668688Y246990D01*
X668708Y247030D01*
X668808Y247170D01*
X668838Y247200D01*
Y249330D01*
X668848Y249455D01*
X668888Y249580D01*
X668948Y249690D01*
X669028Y249790D01*
X669128Y249870D01*
X669238Y249930D01*
X669363Y249970D01*
X669488Y249980D01*
G37*
G36*
G01X674213D02*
X674338Y249970D01*
X674463Y249930D01*
X674573Y249870D01*
X674673Y249790D01*
X674753Y249690D01*
X674813Y249580D01*
X674853Y249455D01*
X674863Y249330D01*
Y247205D01*
X674893Y247175D01*
X674918Y247140D01*
X674948Y247105D01*
X674968Y247070D01*
X674993Y247035D01*
X675033Y246955D01*
X675078Y246835D01*
X675088Y246795D01*
X675098Y246750D01*
X675103Y246710D01*
X675113Y246665D01*
Y246495D01*
X675103Y246450D01*
X675098Y246410D01*
X675088Y246365D01*
X675078Y246325D01*
X675033Y246205D01*
X674993Y246125D01*
X674968Y246090D01*
X674948Y246055D01*
X674918Y246020D01*
X674893Y245985D01*
X674863Y245955D01*
Y243530D01*
X674853Y243405D01*
X674813Y243280D01*
X674753Y243170D01*
X674673Y243070D01*
X674573Y242990D01*
X674463Y242930D01*
X674338Y242890D01*
X674213Y242880D01*
X674088Y242890D01*
X673963Y242930D01*
X673853Y242990D01*
X673753Y243070D01*
X673673Y243170D01*
X673613Y243280D01*
X673573Y243405D01*
X673563Y243530D01*
Y245960D01*
X673533Y245990D01*
X673433Y246130D01*
X673413Y246170D01*
X673398Y246205D01*
X673378Y246245D01*
X673363Y246285D01*
X673353Y246325D01*
X673338Y246370D01*
X673333Y246410D01*
X673323Y246450D01*
X673318Y246495D01*
Y246535D01*
X673313Y246580D01*
X673318Y246625D01*
Y246665D01*
X673323Y246710D01*
X673333Y246750D01*
X673338Y246790D01*
X673353Y246835D01*
X673363Y246875D01*
X673378Y246915D01*
X673398Y246955D01*
X673413Y246990D01*
X673433Y247030D01*
X673533Y247170D01*
X673563Y247200D01*
Y249330D01*
X673573Y249455D01*
X673613Y249580D01*
X673673Y249690D01*
X673753Y249790D01*
X673853Y249870D01*
X673963Y249930D01*
X674088Y249970D01*
X674213Y249980D01*
G37*
G36*
G01X678937D02*
X679062Y249970D01*
X679187Y249930D01*
X679297Y249870D01*
X679397Y249790D01*
X679477Y249690D01*
X679537Y249580D01*
X679577Y249455D01*
X679587Y249330D01*
Y247205D01*
X679617Y247175D01*
X679642Y247140D01*
X679672Y247105D01*
X679692Y247070D01*
X679717Y247035D01*
X679757Y246955D01*
X679802Y246835D01*
X679812Y246795D01*
X679822Y246750D01*
X679827Y246710D01*
X679837Y246665D01*
Y246495D01*
X679827Y246450D01*
X679822Y246410D01*
X679812Y246365D01*
X679802Y246325D01*
X679757Y246205D01*
X679717Y246125D01*
X679692Y246090D01*
X679672Y246055D01*
X679642Y246020D01*
X679617Y245985D01*
X679587Y245955D01*
Y243530D01*
X679577Y243405D01*
X679537Y243280D01*
X679477Y243170D01*
X679397Y243070D01*
X679297Y242990D01*
X679187Y242930D01*
X679062Y242890D01*
X678937Y242880D01*
X678812Y242890D01*
X678687Y242930D01*
X678577Y242990D01*
X678477Y243070D01*
X678397Y243170D01*
X678337Y243280D01*
X678297Y243405D01*
X678287Y243530D01*
Y245960D01*
X678257Y245990D01*
X678157Y246130D01*
X678137Y246170D01*
X678122Y246205D01*
X678102Y246245D01*
X678087Y246285D01*
X678077Y246325D01*
X678062Y246370D01*
X678057Y246410D01*
X678047Y246450D01*
X678042Y246495D01*
Y246535D01*
X678037Y246580D01*
X678042Y246625D01*
Y246665D01*
X678047Y246710D01*
X678057Y246750D01*
X678062Y246790D01*
X678077Y246835D01*
X678087Y246875D01*
X678102Y246915D01*
X678122Y246955D01*
X678137Y246990D01*
X678157Y247030D01*
X678257Y247170D01*
X678287Y247200D01*
Y249330D01*
X678297Y249455D01*
X678337Y249580D01*
X678397Y249690D01*
X678477Y249790D01*
X678577Y249870D01*
X678687Y249930D01*
X678812Y249970D01*
X678937Y249980D01*
G37*
G36*
G01X683662D02*
X683787Y249970D01*
X683912Y249930D01*
X684022Y249870D01*
X684122Y249790D01*
X684202Y249690D01*
X684262Y249580D01*
X684302Y249455D01*
X684312Y249330D01*
Y247205D01*
X684342Y247175D01*
X684367Y247140D01*
X684397Y247105D01*
X684417Y247070D01*
X684442Y247035D01*
X684482Y246955D01*
X684527Y246835D01*
X684537Y246795D01*
X684547Y246750D01*
X684552Y246710D01*
X684562Y246665D01*
Y246495D01*
X684552Y246450D01*
X684547Y246410D01*
X684537Y246365D01*
X684527Y246325D01*
X684482Y246205D01*
X684442Y246125D01*
X684417Y246090D01*
X684397Y246055D01*
X684367Y246020D01*
X684342Y245985D01*
X684312Y245955D01*
Y243530D01*
X684302Y243405D01*
X684262Y243280D01*
X684202Y243170D01*
X684122Y243070D01*
X684022Y242990D01*
X683912Y242930D01*
X683787Y242890D01*
X683662Y242880D01*
X683537Y242890D01*
X683412Y242930D01*
X683302Y242990D01*
X683202Y243070D01*
X683122Y243170D01*
X683062Y243280D01*
X683022Y243405D01*
X683012Y243530D01*
Y245960D01*
X682982Y245990D01*
X682882Y246130D01*
X682862Y246170D01*
X682847Y246205D01*
X682827Y246245D01*
X682812Y246285D01*
X682802Y246325D01*
X682787Y246370D01*
X682782Y246410D01*
X682772Y246450D01*
X682767Y246495D01*
Y246535D01*
X682762Y246580D01*
X682767Y246625D01*
Y246665D01*
X682772Y246710D01*
X682782Y246750D01*
X682787Y246790D01*
X682802Y246835D01*
X682812Y246875D01*
X682827Y246915D01*
X682847Y246955D01*
X682862Y246990D01*
X682882Y247030D01*
X682982Y247170D01*
X683012Y247200D01*
Y249330D01*
X683022Y249455D01*
X683062Y249580D01*
X683122Y249690D01*
X683202Y249790D01*
X683302Y249870D01*
X683412Y249930D01*
X683537Y249970D01*
X683662Y249980D01*
G37*
G36*
G01X688386D02*
X688511Y249970D01*
X688636Y249930D01*
X688746Y249870D01*
X688846Y249790D01*
X688926Y249690D01*
X688986Y249580D01*
X689026Y249455D01*
X689036Y249330D01*
Y247205D01*
X689066Y247175D01*
X689091Y247140D01*
X689121Y247105D01*
X689141Y247070D01*
X689166Y247035D01*
X689206Y246955D01*
X689251Y246835D01*
X689261Y246795D01*
X689271Y246750D01*
X689276Y246710D01*
X689286Y246665D01*
Y246495D01*
X689276Y246450D01*
X689271Y246410D01*
X689261Y246365D01*
X689251Y246325D01*
X689206Y246205D01*
X689166Y246125D01*
X689141Y246090D01*
X689121Y246055D01*
X689091Y246020D01*
X689066Y245985D01*
X689036Y245955D01*
Y243530D01*
X689026Y243405D01*
X688986Y243280D01*
X688926Y243170D01*
X688846Y243070D01*
X688746Y242990D01*
X688636Y242930D01*
X688511Y242890D01*
X688386Y242880D01*
X688261Y242890D01*
X688136Y242930D01*
X688026Y242990D01*
X687926Y243070D01*
X687846Y243170D01*
X687786Y243280D01*
X687746Y243405D01*
X687736Y243530D01*
Y245960D01*
X687706Y245990D01*
X687606Y246130D01*
X687586Y246170D01*
X687571Y246205D01*
X687551Y246245D01*
X687536Y246285D01*
X687526Y246325D01*
X687511Y246370D01*
X687506Y246410D01*
X687496Y246450D01*
X687491Y246495D01*
Y246535D01*
X687486Y246580D01*
X687491Y246625D01*
Y246665D01*
X687496Y246710D01*
X687506Y246750D01*
X687511Y246790D01*
X687526Y246835D01*
X687536Y246875D01*
X687551Y246915D01*
X687571Y246955D01*
X687586Y246990D01*
X687606Y247030D01*
X687706Y247170D01*
X687736Y247200D01*
Y249330D01*
X687746Y249455D01*
X687786Y249580D01*
X687846Y249690D01*
X687926Y249790D01*
X688026Y249870D01*
X688136Y249930D01*
X688261Y249970D01*
X688386Y249980D01*
G37*
G36*
G01X693110D02*
X693235Y249970D01*
X693360Y249930D01*
X693470Y249870D01*
X693570Y249790D01*
X693650Y249690D01*
X693710Y249580D01*
X693750Y249455D01*
X693760Y249330D01*
Y247205D01*
X693790Y247175D01*
X693815Y247140D01*
X693845Y247105D01*
X693865Y247070D01*
X693890Y247035D01*
X693930Y246955D01*
X693975Y246835D01*
X693985Y246795D01*
X693995Y246750D01*
X694000Y246710D01*
X694010Y246665D01*
Y246495D01*
X694000Y246450D01*
X693995Y246410D01*
X693985Y246365D01*
X693975Y246325D01*
X693930Y246205D01*
X693890Y246125D01*
X693865Y246090D01*
X693845Y246055D01*
X693815Y246020D01*
X693790Y245985D01*
X693760Y245955D01*
Y243530D01*
X693750Y243405D01*
X693710Y243280D01*
X693650Y243170D01*
X693570Y243070D01*
X693470Y242990D01*
X693360Y242930D01*
X693235Y242890D01*
X693110Y242880D01*
X692985Y242890D01*
X692860Y242930D01*
X692750Y242990D01*
X692650Y243070D01*
X692570Y243170D01*
X692510Y243280D01*
X692470Y243405D01*
X692460Y243530D01*
Y245960D01*
X692430Y245990D01*
X692330Y246130D01*
X692310Y246170D01*
X692295Y246205D01*
X692275Y246245D01*
X692260Y246285D01*
X692250Y246325D01*
X692235Y246370D01*
X692230Y246410D01*
X692220Y246450D01*
X692215Y246495D01*
Y246535D01*
X692210Y246580D01*
X692215Y246625D01*
Y246665D01*
X692220Y246710D01*
X692230Y246750D01*
X692235Y246790D01*
X692250Y246835D01*
X692260Y246875D01*
X692275Y246915D01*
X692295Y246955D01*
X692310Y246990D01*
X692330Y247030D01*
X692430Y247170D01*
X692460Y247200D01*
Y249330D01*
X692470Y249455D01*
X692510Y249580D01*
X692570Y249690D01*
X692650Y249790D01*
X692750Y249870D01*
X692860Y249930D01*
X692985Y249970D01*
X693110Y249980D01*
G37*
G36*
G01X697835D02*
X697960Y249970D01*
X698085Y249930D01*
X698195Y249870D01*
X698295Y249790D01*
X698375Y249690D01*
X698435Y249580D01*
X698475Y249455D01*
X698485Y249330D01*
Y247205D01*
X698515Y247175D01*
X698540Y247140D01*
X698570Y247105D01*
X698590Y247070D01*
X698615Y247035D01*
X698655Y246955D01*
X698700Y246835D01*
X698710Y246795D01*
X698720Y246750D01*
X698725Y246710D01*
X698735Y246665D01*
Y246495D01*
X698725Y246450D01*
X698720Y246410D01*
X698710Y246365D01*
X698700Y246325D01*
X698655Y246205D01*
X698615Y246125D01*
X698590Y246090D01*
X698570Y246055D01*
X698540Y246020D01*
X698515Y245985D01*
X698485Y245955D01*
Y243530D01*
X698475Y243405D01*
X698435Y243280D01*
X698375Y243170D01*
X698295Y243070D01*
X698195Y242990D01*
X698085Y242930D01*
X697960Y242890D01*
X697835Y242880D01*
X697710Y242890D01*
X697585Y242930D01*
X697475Y242990D01*
X697375Y243070D01*
X697295Y243170D01*
X697235Y243280D01*
X697195Y243405D01*
X697185Y243530D01*
Y245960D01*
X697155Y245990D01*
X697055Y246130D01*
X697035Y246170D01*
X697020Y246205D01*
X697000Y246245D01*
X696985Y246285D01*
X696975Y246325D01*
X696960Y246370D01*
X696955Y246410D01*
X696945Y246450D01*
X696940Y246495D01*
Y246535D01*
X696935Y246580D01*
X696940Y246625D01*
Y246665D01*
X696945Y246710D01*
X696955Y246750D01*
X696960Y246790D01*
X696975Y246835D01*
X696985Y246875D01*
X697000Y246915D01*
X697020Y246955D01*
X697035Y246990D01*
X697055Y247030D01*
X697155Y247170D01*
X697185Y247200D01*
Y249330D01*
X697195Y249455D01*
X697235Y249580D01*
X697295Y249690D01*
X697375Y249790D01*
X697475Y249870D01*
X697585Y249930D01*
X697710Y249970D01*
X697835Y249980D01*
G37*
G36*
G01X702559D02*
X702684Y249970D01*
X702809Y249930D01*
X702919Y249870D01*
X703019Y249790D01*
X703099Y249690D01*
X703159Y249580D01*
X703199Y249455D01*
X703209Y249330D01*
Y247205D01*
X703239Y247175D01*
X703264Y247140D01*
X703294Y247105D01*
X703314Y247070D01*
X703339Y247035D01*
X703379Y246955D01*
X703424Y246835D01*
X703434Y246795D01*
X703444Y246750D01*
X703449Y246710D01*
X703459Y246665D01*
Y246495D01*
X703449Y246450D01*
X703444Y246410D01*
X703434Y246365D01*
X703424Y246325D01*
X703379Y246205D01*
X703339Y246125D01*
X703314Y246090D01*
X703294Y246055D01*
X703264Y246020D01*
X703239Y245985D01*
X703209Y245955D01*
Y243530D01*
X703199Y243405D01*
X703159Y243280D01*
X703099Y243170D01*
X703019Y243070D01*
X702919Y242990D01*
X702809Y242930D01*
X702684Y242890D01*
X702559Y242880D01*
X702434Y242890D01*
X702309Y242930D01*
X702199Y242990D01*
X702099Y243070D01*
X702019Y243170D01*
X701959Y243280D01*
X701919Y243405D01*
X701909Y243530D01*
Y245960D01*
X701879Y245990D01*
X701779Y246130D01*
X701759Y246170D01*
X701744Y246205D01*
X701724Y246245D01*
X701709Y246285D01*
X701699Y246325D01*
X701684Y246370D01*
X701679Y246410D01*
X701669Y246450D01*
X701664Y246495D01*
Y246535D01*
X701659Y246580D01*
X701664Y246625D01*
Y246665D01*
X701669Y246710D01*
X701679Y246750D01*
X701684Y246790D01*
X701699Y246835D01*
X701709Y246875D01*
X701724Y246915D01*
X701744Y246955D01*
X701759Y246990D01*
X701779Y247030D01*
X701879Y247170D01*
X701909Y247200D01*
Y249330D01*
X701919Y249455D01*
X701959Y249580D01*
X702019Y249690D01*
X702099Y249790D01*
X702199Y249870D01*
X702309Y249930D01*
X702434Y249970D01*
X702559Y249980D01*
G37*
G36*
G01X707284D02*
X707409Y249970D01*
X707534Y249930D01*
X707644Y249870D01*
X707744Y249790D01*
X707824Y249690D01*
X707884Y249580D01*
X707924Y249455D01*
X707934Y249330D01*
Y247205D01*
X707964Y247175D01*
X707989Y247140D01*
X708019Y247105D01*
X708039Y247070D01*
X708064Y247035D01*
X708104Y246955D01*
X708149Y246835D01*
X708159Y246795D01*
X708169Y246750D01*
X708174Y246710D01*
X708184Y246665D01*
Y246495D01*
X708174Y246450D01*
X708169Y246410D01*
X708159Y246365D01*
X708149Y246325D01*
X708104Y246205D01*
X708064Y246125D01*
X708039Y246090D01*
X708019Y246055D01*
X707989Y246020D01*
X707964Y245985D01*
X707934Y245955D01*
Y243530D01*
X707924Y243405D01*
X707884Y243280D01*
X707824Y243170D01*
X707744Y243070D01*
X707644Y242990D01*
X707534Y242930D01*
X707409Y242890D01*
X707284Y242880D01*
X707159Y242890D01*
X707034Y242930D01*
X706924Y242990D01*
X706824Y243070D01*
X706744Y243170D01*
X706684Y243280D01*
X706644Y243405D01*
X706634Y243530D01*
Y245960D01*
X706604Y245990D01*
X706504Y246130D01*
X706484Y246170D01*
X706469Y246205D01*
X706449Y246245D01*
X706434Y246285D01*
X706424Y246325D01*
X706409Y246370D01*
X706404Y246410D01*
X706394Y246450D01*
X706389Y246495D01*
Y246535D01*
X706384Y246580D01*
X706389Y246625D01*
Y246665D01*
X706394Y246710D01*
X706404Y246750D01*
X706409Y246790D01*
X706424Y246835D01*
X706434Y246875D01*
X706449Y246915D01*
X706469Y246955D01*
X706484Y246990D01*
X706504Y247030D01*
X706604Y247170D01*
X706634Y247200D01*
Y249330D01*
X706644Y249455D01*
X706684Y249580D01*
X706744Y249690D01*
X706824Y249790D01*
X706924Y249870D01*
X707034Y249930D01*
X707159Y249970D01*
X707284Y249980D01*
G37*
G36*
G01X712008D02*
X712133Y249970D01*
X712258Y249930D01*
X712368Y249870D01*
X712468Y249790D01*
X712548Y249690D01*
X712608Y249580D01*
X712648Y249455D01*
X712658Y249330D01*
Y247205D01*
X712688Y247175D01*
X712713Y247140D01*
X712743Y247105D01*
X712763Y247070D01*
X712788Y247035D01*
X712828Y246955D01*
X712873Y246835D01*
X712883Y246795D01*
X712893Y246750D01*
X712898Y246710D01*
X712908Y246665D01*
Y246495D01*
X712898Y246450D01*
X712893Y246410D01*
X712883Y246365D01*
X712873Y246325D01*
X712828Y246205D01*
X712788Y246125D01*
X712763Y246090D01*
X712743Y246055D01*
X712713Y246020D01*
X712688Y245985D01*
X712658Y245955D01*
Y243530D01*
X712648Y243405D01*
X712608Y243280D01*
X712548Y243170D01*
X712468Y243070D01*
X712368Y242990D01*
X712258Y242930D01*
X712133Y242890D01*
X712008Y242880D01*
X711883Y242890D01*
X711758Y242930D01*
X711648Y242990D01*
X711548Y243070D01*
X711468Y243170D01*
X711408Y243280D01*
X711368Y243405D01*
X711358Y243530D01*
Y245960D01*
X711328Y245990D01*
X711228Y246130D01*
X711208Y246170D01*
X711193Y246205D01*
X711173Y246245D01*
X711158Y246285D01*
X711148Y246325D01*
X711133Y246370D01*
X711128Y246410D01*
X711118Y246450D01*
X711113Y246495D01*
Y246535D01*
X711108Y246580D01*
X711113Y246625D01*
Y246665D01*
X711118Y246710D01*
X711128Y246750D01*
X711133Y246790D01*
X711148Y246835D01*
X711158Y246875D01*
X711173Y246915D01*
X711193Y246955D01*
X711208Y246990D01*
X711228Y247030D01*
X711328Y247170D01*
X711358Y247200D01*
Y249330D01*
X711368Y249455D01*
X711408Y249580D01*
X711468Y249690D01*
X711548Y249790D01*
X711648Y249870D01*
X711758Y249930D01*
X711883Y249970D01*
X712008Y249980D01*
G37*
G36*
G01X716733D02*
X716858Y249970D01*
X716983Y249930D01*
X717093Y249870D01*
X717193Y249790D01*
X717273Y249690D01*
X717333Y249580D01*
X717373Y249455D01*
X717383Y249330D01*
Y247205D01*
X717413Y247175D01*
X717438Y247140D01*
X717468Y247105D01*
X717488Y247070D01*
X717513Y247035D01*
X717553Y246955D01*
X717598Y246835D01*
X717608Y246795D01*
X717618Y246750D01*
X717623Y246710D01*
X717633Y246665D01*
Y246495D01*
X717623Y246450D01*
X717618Y246410D01*
X717608Y246365D01*
X717598Y246325D01*
X717553Y246205D01*
X717513Y246125D01*
X717488Y246090D01*
X717468Y246055D01*
X717438Y246020D01*
X717413Y245985D01*
X717383Y245955D01*
Y243530D01*
X717373Y243405D01*
X717333Y243280D01*
X717273Y243170D01*
X717193Y243070D01*
X717093Y242990D01*
X716983Y242930D01*
X716858Y242890D01*
X716733Y242880D01*
X716608Y242890D01*
X716483Y242930D01*
X716373Y242990D01*
X716273Y243070D01*
X716193Y243170D01*
X716133Y243280D01*
X716093Y243405D01*
X716083Y243530D01*
Y245960D01*
X716053Y245990D01*
X715953Y246130D01*
X715933Y246170D01*
X715918Y246205D01*
X715898Y246245D01*
X715883Y246285D01*
X715873Y246325D01*
X715858Y246370D01*
X715853Y246410D01*
X715843Y246450D01*
X715838Y246495D01*
Y246535D01*
X715833Y246580D01*
X715838Y246625D01*
Y246665D01*
X715843Y246710D01*
X715853Y246750D01*
X715858Y246790D01*
X715873Y246835D01*
X715883Y246875D01*
X715898Y246915D01*
X715918Y246955D01*
X715933Y246990D01*
X715953Y247030D01*
X716053Y247170D01*
X716083Y247200D01*
Y249330D01*
X716093Y249455D01*
X716133Y249580D01*
X716193Y249690D01*
X716273Y249790D01*
X716373Y249870D01*
X716483Y249930D01*
X716608Y249970D01*
X716733Y249980D01*
G37*
G36*
G01X721457D02*
X721582Y249970D01*
X721707Y249930D01*
X721817Y249870D01*
X721917Y249790D01*
X721997Y249690D01*
X722057Y249580D01*
X722097Y249455D01*
X722107Y249330D01*
Y247205D01*
X722137Y247175D01*
X722162Y247140D01*
X722192Y247105D01*
X722212Y247070D01*
X722237Y247035D01*
X722277Y246955D01*
X722322Y246835D01*
X722332Y246795D01*
X722342Y246750D01*
X722347Y246710D01*
X722357Y246665D01*
Y246495D01*
X722347Y246450D01*
X722342Y246410D01*
X722332Y246365D01*
X722322Y246325D01*
X722277Y246205D01*
X722237Y246125D01*
X722212Y246090D01*
X722192Y246055D01*
X722162Y246020D01*
X722137Y245985D01*
X722107Y245955D01*
Y243530D01*
X722097Y243405D01*
X722057Y243280D01*
X721997Y243170D01*
X721917Y243070D01*
X721817Y242990D01*
X721707Y242930D01*
X721582Y242890D01*
X721457Y242880D01*
X721332Y242890D01*
X721207Y242930D01*
X721097Y242990D01*
X720997Y243070D01*
X720917Y243170D01*
X720857Y243280D01*
X720817Y243405D01*
X720807Y243530D01*
Y245960D01*
X720777Y245990D01*
X720677Y246130D01*
X720657Y246170D01*
X720642Y246205D01*
X720622Y246245D01*
X720607Y246285D01*
X720597Y246325D01*
X720582Y246370D01*
X720577Y246410D01*
X720567Y246450D01*
X720562Y246495D01*
Y246535D01*
X720557Y246580D01*
X720562Y246625D01*
Y246665D01*
X720567Y246710D01*
X720577Y246750D01*
X720582Y246790D01*
X720597Y246835D01*
X720607Y246875D01*
X720622Y246915D01*
X720642Y246955D01*
X720657Y246990D01*
X720677Y247030D01*
X720777Y247170D01*
X720807Y247200D01*
Y249330D01*
X720817Y249455D01*
X720857Y249580D01*
X720917Y249690D01*
X720997Y249790D01*
X721097Y249870D01*
X721207Y249930D01*
X721332Y249970D01*
X721457Y249980D01*
G37*
G36*
G01X726181D02*
X726306Y249970D01*
X726431Y249930D01*
X726541Y249870D01*
X726641Y249790D01*
X726721Y249690D01*
X726781Y249580D01*
X726821Y249455D01*
X726831Y249330D01*
Y247205D01*
X726861Y247175D01*
X726886Y247140D01*
X726916Y247105D01*
X726936Y247070D01*
X726961Y247035D01*
X727001Y246955D01*
X727046Y246835D01*
X727056Y246795D01*
X727066Y246750D01*
X727071Y246710D01*
X727081Y246665D01*
Y246495D01*
X727071Y246450D01*
X727066Y246410D01*
X727056Y246365D01*
X727046Y246325D01*
X727001Y246205D01*
X726961Y246125D01*
X726936Y246090D01*
X726916Y246055D01*
X726886Y246020D01*
X726861Y245985D01*
X726831Y245955D01*
Y243530D01*
X726821Y243405D01*
X726781Y243280D01*
X726721Y243170D01*
X726641Y243070D01*
X726541Y242990D01*
X726431Y242930D01*
X726306Y242890D01*
X726181Y242880D01*
X726056Y242890D01*
X725931Y242930D01*
X725821Y242990D01*
X725721Y243070D01*
X725641Y243170D01*
X725581Y243280D01*
X725541Y243405D01*
X725531Y243530D01*
Y245960D01*
X725501Y245990D01*
X725401Y246130D01*
X725381Y246170D01*
X725366Y246205D01*
X725346Y246245D01*
X725331Y246285D01*
X725321Y246325D01*
X725306Y246370D01*
X725301Y246410D01*
X725291Y246450D01*
X725286Y246495D01*
Y246535D01*
X725281Y246580D01*
X725286Y246625D01*
Y246665D01*
X725291Y246710D01*
X725301Y246750D01*
X725306Y246790D01*
X725321Y246835D01*
X725331Y246875D01*
X725346Y246915D01*
X725366Y246955D01*
X725381Y246990D01*
X725401Y247030D01*
X725501Y247170D01*
X725531Y247200D01*
Y249330D01*
X725541Y249455D01*
X725581Y249580D01*
X725641Y249690D01*
X725721Y249790D01*
X725821Y249870D01*
X725931Y249930D01*
X726056Y249970D01*
X726181Y249980D01*
G37*
G36*
G01X730906D02*
X731031Y249970D01*
X731156Y249930D01*
X731266Y249870D01*
X731366Y249790D01*
X731446Y249690D01*
X731506Y249580D01*
X731546Y249455D01*
X731556Y249330D01*
Y247205D01*
X731586Y247175D01*
X731611Y247140D01*
X731641Y247105D01*
X731661Y247070D01*
X731686Y247035D01*
X731726Y246955D01*
X731771Y246835D01*
X731781Y246795D01*
X731791Y246750D01*
X731796Y246710D01*
X731806Y246665D01*
Y246495D01*
X731796Y246450D01*
X731791Y246410D01*
X731781Y246365D01*
X731771Y246325D01*
X731726Y246205D01*
X731686Y246125D01*
X731661Y246090D01*
X731641Y246055D01*
X731611Y246020D01*
X731586Y245985D01*
X731556Y245955D01*
Y243530D01*
X731546Y243405D01*
X731506Y243280D01*
X731446Y243170D01*
X731366Y243070D01*
X731266Y242990D01*
X731156Y242930D01*
X731031Y242890D01*
X730906Y242880D01*
X730781Y242890D01*
X730656Y242930D01*
X730546Y242990D01*
X730446Y243070D01*
X730366Y243170D01*
X730306Y243280D01*
X730266Y243405D01*
X730256Y243530D01*
Y245960D01*
X730226Y245990D01*
X730126Y246130D01*
X730106Y246170D01*
X730091Y246205D01*
X730071Y246245D01*
X730056Y246285D01*
X730046Y246325D01*
X730031Y246370D01*
X730026Y246410D01*
X730016Y246450D01*
X730011Y246495D01*
Y246535D01*
X730006Y246580D01*
X730011Y246625D01*
Y246665D01*
X730016Y246710D01*
X730026Y246750D01*
X730031Y246790D01*
X730046Y246835D01*
X730056Y246875D01*
X730071Y246915D01*
X730091Y246955D01*
X730106Y246990D01*
X730126Y247030D01*
X730226Y247170D01*
X730256Y247200D01*
Y249330D01*
X730266Y249455D01*
X730306Y249580D01*
X730366Y249690D01*
X730446Y249790D01*
X730546Y249870D01*
X730656Y249930D01*
X730781Y249970D01*
X730906Y249980D01*
G37*
G36*
G01X735630D02*
X735755Y249970D01*
X735880Y249930D01*
X735990Y249870D01*
X736090Y249790D01*
X736170Y249690D01*
X736230Y249580D01*
X736270Y249455D01*
X736280Y249330D01*
Y247205D01*
X736310Y247175D01*
X736335Y247140D01*
X736365Y247105D01*
X736385Y247070D01*
X736410Y247035D01*
X736450Y246955D01*
X736495Y246835D01*
X736505Y246795D01*
X736515Y246750D01*
X736520Y246710D01*
X736530Y246665D01*
Y246495D01*
X736520Y246450D01*
X736515Y246410D01*
X736505Y246365D01*
X736495Y246325D01*
X736450Y246205D01*
X736410Y246125D01*
X736385Y246090D01*
X736365Y246055D01*
X736335Y246020D01*
X736310Y245985D01*
X736280Y245955D01*
Y243530D01*
X736270Y243405D01*
X736230Y243280D01*
X736170Y243170D01*
X736090Y243070D01*
X735990Y242990D01*
X735880Y242930D01*
X735755Y242890D01*
X735630Y242880D01*
X735505Y242890D01*
X735380Y242930D01*
X735270Y242990D01*
X735170Y243070D01*
X735090Y243170D01*
X735030Y243280D01*
X734990Y243405D01*
X734980Y243530D01*
Y245960D01*
X734950Y245990D01*
X734850Y246130D01*
X734830Y246170D01*
X734815Y246205D01*
X734795Y246245D01*
X734780Y246285D01*
X734770Y246325D01*
X734755Y246370D01*
X734750Y246410D01*
X734740Y246450D01*
X734735Y246495D01*
Y246535D01*
X734730Y246580D01*
X734735Y246625D01*
Y246665D01*
X734740Y246710D01*
X734750Y246750D01*
X734755Y246790D01*
X734770Y246835D01*
X734780Y246875D01*
X734795Y246915D01*
X734815Y246955D01*
X734830Y246990D01*
X734850Y247030D01*
X734950Y247170D01*
X734980Y247200D01*
Y249330D01*
X734990Y249455D01*
X735030Y249580D01*
X735090Y249690D01*
X735170Y249790D01*
X735270Y249870D01*
X735380Y249930D01*
X735505Y249970D01*
X735630Y249980D01*
G37*
G36*
G01X740355D02*
X740480Y249970D01*
X740605Y249930D01*
X740715Y249870D01*
X740815Y249790D01*
X740895Y249690D01*
X740955Y249580D01*
X740995Y249455D01*
X741005Y249330D01*
Y247205D01*
X741035Y247175D01*
X741060Y247140D01*
X741090Y247105D01*
X741110Y247070D01*
X741135Y247035D01*
X741175Y246955D01*
X741220Y246835D01*
X741230Y246795D01*
X741240Y246750D01*
X741245Y246710D01*
X741255Y246665D01*
Y246495D01*
X741245Y246450D01*
X741240Y246410D01*
X741230Y246365D01*
X741220Y246325D01*
X741175Y246205D01*
X741135Y246125D01*
X741110Y246090D01*
X741090Y246055D01*
X741060Y246020D01*
X741035Y245985D01*
X741005Y245955D01*
Y243530D01*
X740995Y243405D01*
X740955Y243280D01*
X740895Y243170D01*
X740815Y243070D01*
X740715Y242990D01*
X740605Y242930D01*
X740480Y242890D01*
X740355Y242880D01*
X740230Y242890D01*
X740105Y242930D01*
X739995Y242990D01*
X739895Y243070D01*
X739815Y243170D01*
X739755Y243280D01*
X739715Y243405D01*
X739705Y243530D01*
Y245960D01*
X739675Y245990D01*
X739575Y246130D01*
X739555Y246170D01*
X739540Y246205D01*
X739520Y246245D01*
X739505Y246285D01*
X739495Y246325D01*
X739480Y246370D01*
X739475Y246410D01*
X739465Y246450D01*
X739460Y246495D01*
Y246535D01*
X739455Y246580D01*
X739460Y246625D01*
Y246665D01*
X739465Y246710D01*
X739475Y246750D01*
X739480Y246790D01*
X739495Y246835D01*
X739505Y246875D01*
X739520Y246915D01*
X739540Y246955D01*
X739555Y246990D01*
X739575Y247030D01*
X739675Y247170D01*
X739705Y247200D01*
Y249330D01*
X739715Y249455D01*
X739755Y249580D01*
X739815Y249690D01*
X739895Y249790D01*
X739995Y249870D01*
X740105Y249930D01*
X740230Y249970D01*
X740355Y249980D01*
G37*
G36*
G01X745079D02*
X745204Y249970D01*
X745329Y249930D01*
X745439Y249870D01*
X745539Y249790D01*
X745619Y249690D01*
X745679Y249580D01*
X745719Y249455D01*
X745729Y249330D01*
Y247205D01*
X745759Y247175D01*
X745784Y247140D01*
X745814Y247105D01*
X745834Y247070D01*
X745859Y247035D01*
X745899Y246955D01*
X745944Y246835D01*
X745954Y246795D01*
X745964Y246750D01*
X745969Y246710D01*
X745979Y246665D01*
Y246495D01*
X745969Y246450D01*
X745964Y246410D01*
X745954Y246365D01*
X745944Y246325D01*
X745899Y246205D01*
X745859Y246125D01*
X745834Y246090D01*
X745814Y246055D01*
X745784Y246020D01*
X745759Y245985D01*
X745729Y245955D01*
Y243530D01*
X745719Y243405D01*
X745679Y243280D01*
X745619Y243170D01*
X745539Y243070D01*
X745439Y242990D01*
X745329Y242930D01*
X745204Y242890D01*
X745079Y242880D01*
X744954Y242890D01*
X744829Y242930D01*
X744719Y242990D01*
X744619Y243070D01*
X744539Y243170D01*
X744479Y243280D01*
X744439Y243405D01*
X744429Y243530D01*
Y245960D01*
X744399Y245990D01*
X744299Y246130D01*
X744279Y246170D01*
X744264Y246205D01*
X744244Y246245D01*
X744229Y246285D01*
X744219Y246325D01*
X744204Y246370D01*
X744199Y246410D01*
X744189Y246450D01*
X744184Y246495D01*
Y246535D01*
X744179Y246580D01*
X744184Y246625D01*
Y246665D01*
X744189Y246710D01*
X744199Y246750D01*
X744204Y246790D01*
X744219Y246835D01*
X744229Y246875D01*
X744244Y246915D01*
X744264Y246955D01*
X744279Y246990D01*
X744299Y247030D01*
X744399Y247170D01*
X744429Y247200D01*
Y249330D01*
X744439Y249455D01*
X744479Y249580D01*
X744539Y249690D01*
X744619Y249790D01*
X744719Y249870D01*
X744829Y249930D01*
X744954Y249970D01*
X745079Y249980D01*
G37*
G54D88*
X336652Y102171D03*
X330252D03*
X335832Y206491D03*
X329432D03*
X354382Y102171D03*
X342312D03*
X347982D03*
X353562Y206491D03*
X347162D03*
X341502D03*
X360042Y102171D03*
X365702D03*
X371292Y206491D03*
X364892D03*
X359222D03*
X372102Y102171D03*
X377772D03*
X383432D03*
X376952Y206491D03*
X382622D03*
X389832Y102171D03*
X395502D03*
X401162D03*
X394682Y206491D03*
X389022D03*
X400342D03*
X407562Y102171D03*
X413222D03*
X412412Y206491D03*
X418072D03*
X406742D03*
X418892Y102171D03*
X425292D03*
X424472Y206491D03*
G36*
G01X501772Y249980D02*
X501897Y249970D01*
X502022Y249930D01*
X502132Y249870D01*
X502232Y249790D01*
X502312Y249690D01*
X502372Y249580D01*
X502412Y249455D01*
X502422Y249330D01*
Y248200D01*
X502452Y248170D01*
X502552Y248030D01*
X502572Y247990D01*
X502587Y247955D01*
X502607Y247915D01*
X502622Y247875D01*
X502632Y247835D01*
X502647Y247790D01*
X502652Y247750D01*
X502662Y247710D01*
X502667Y247665D01*
Y247625D01*
X502672Y247580D01*
X502667Y247535D01*
Y247495D01*
X502662Y247450D01*
X502652Y247410D01*
X502647Y247370D01*
X502632Y247325D01*
X502622Y247285D01*
X502607Y247245D01*
X502587Y247205D01*
X502572Y247170D01*
X502552Y247130D01*
X502452Y246990D01*
X502422Y246960D01*
Y243530D01*
X502412Y243405D01*
X502372Y243280D01*
X502312Y243170D01*
X502232Y243070D01*
X502132Y242990D01*
X502022Y242930D01*
X501897Y242890D01*
X501772Y242880D01*
X501647Y242890D01*
X501522Y242930D01*
X501412Y242990D01*
X501312Y243070D01*
X501232Y243170D01*
X501172Y243280D01*
X501132Y243405D01*
X501122Y243530D01*
Y246960D01*
X501092Y246990D01*
X500992Y247130D01*
X500972Y247170D01*
X500957Y247205D01*
X500937Y247245D01*
X500922Y247285D01*
X500912Y247325D01*
X500897Y247370D01*
X500892Y247410D01*
X500882Y247450D01*
X500877Y247495D01*
Y247535D01*
X500872Y247580D01*
X500877Y247625D01*
Y247665D01*
X500882Y247710D01*
X500892Y247750D01*
X500897Y247790D01*
X500912Y247835D01*
X500922Y247875D01*
X500937Y247915D01*
X500957Y247955D01*
X500972Y247990D01*
X500992Y248030D01*
X501092Y248170D01*
X501122Y248200D01*
Y249330D01*
X501132Y249455D01*
X501172Y249580D01*
X501232Y249690D01*
X501312Y249790D01*
X501412Y249870D01*
X501522Y249930D01*
X501647Y249970D01*
X501772Y249980D01*
G37*
G36*
G01X506496D02*
X506621Y249970D01*
X506746Y249930D01*
X506856Y249870D01*
X506956Y249790D01*
X507036Y249690D01*
X507096Y249580D01*
X507136Y249455D01*
X507146Y249330D01*
Y248200D01*
X507176Y248170D01*
X507276Y248030D01*
X507296Y247990D01*
X507311Y247955D01*
X507331Y247915D01*
X507346Y247875D01*
X507356Y247835D01*
X507371Y247790D01*
X507376Y247750D01*
X507386Y247710D01*
X507391Y247665D01*
Y247625D01*
X507396Y247580D01*
X507391Y247535D01*
Y247495D01*
X507386Y247450D01*
X507376Y247410D01*
X507371Y247370D01*
X507356Y247325D01*
X507346Y247285D01*
X507331Y247245D01*
X507311Y247205D01*
X507296Y247170D01*
X507276Y247130D01*
X507176Y246990D01*
X507146Y246960D01*
Y243530D01*
X507136Y243405D01*
X507096Y243280D01*
X507036Y243170D01*
X506956Y243070D01*
X506856Y242990D01*
X506746Y242930D01*
X506621Y242890D01*
X506496Y242880D01*
X506371Y242890D01*
X506246Y242930D01*
X506136Y242990D01*
X506036Y243070D01*
X505956Y243170D01*
X505896Y243280D01*
X505856Y243405D01*
X505846Y243530D01*
Y246960D01*
X505816Y246990D01*
X505716Y247130D01*
X505696Y247170D01*
X505681Y247205D01*
X505661Y247245D01*
X505646Y247285D01*
X505636Y247325D01*
X505621Y247370D01*
X505616Y247410D01*
X505606Y247450D01*
X505601Y247495D01*
Y247535D01*
X505596Y247580D01*
X505601Y247625D01*
Y247665D01*
X505606Y247710D01*
X505616Y247750D01*
X505621Y247790D01*
X505636Y247835D01*
X505646Y247875D01*
X505661Y247915D01*
X505681Y247955D01*
X505696Y247990D01*
X505716Y248030D01*
X505816Y248170D01*
X505846Y248200D01*
Y249330D01*
X505856Y249455D01*
X505896Y249580D01*
X505956Y249690D01*
X506036Y249790D01*
X506136Y249870D01*
X506246Y249930D01*
X506371Y249970D01*
X506496Y249980D01*
G37*
G36*
G01X511221D02*
X511346Y249970D01*
X511471Y249930D01*
X511581Y249870D01*
X511681Y249790D01*
X511761Y249690D01*
X511821Y249580D01*
X511861Y249455D01*
X511871Y249330D01*
Y248200D01*
X511901Y248170D01*
X512001Y248030D01*
X512021Y247990D01*
X512036Y247955D01*
X512056Y247915D01*
X512071Y247875D01*
X512081Y247835D01*
X512096Y247790D01*
X512101Y247750D01*
X512111Y247710D01*
X512116Y247665D01*
Y247625D01*
X512121Y247580D01*
X512116Y247535D01*
Y247495D01*
X512111Y247450D01*
X512101Y247410D01*
X512096Y247370D01*
X512081Y247325D01*
X512071Y247285D01*
X512056Y247245D01*
X512036Y247205D01*
X512021Y247170D01*
X512001Y247130D01*
X511901Y246990D01*
X511871Y246960D01*
Y243530D01*
X511861Y243405D01*
X511821Y243280D01*
X511761Y243170D01*
X511681Y243070D01*
X511581Y242990D01*
X511471Y242930D01*
X511346Y242890D01*
X511221Y242880D01*
X511096Y242890D01*
X510971Y242930D01*
X510861Y242990D01*
X510761Y243070D01*
X510681Y243170D01*
X510621Y243280D01*
X510581Y243405D01*
X510571Y243530D01*
Y246960D01*
X510541Y246990D01*
X510441Y247130D01*
X510421Y247170D01*
X510406Y247205D01*
X510386Y247245D01*
X510371Y247285D01*
X510361Y247325D01*
X510346Y247370D01*
X510341Y247410D01*
X510331Y247450D01*
X510326Y247495D01*
Y247535D01*
X510321Y247580D01*
X510326Y247625D01*
Y247665D01*
X510331Y247710D01*
X510341Y247750D01*
X510346Y247790D01*
X510361Y247835D01*
X510371Y247875D01*
X510386Y247915D01*
X510406Y247955D01*
X510421Y247990D01*
X510441Y248030D01*
X510541Y248170D01*
X510571Y248200D01*
Y249330D01*
X510581Y249455D01*
X510621Y249580D01*
X510681Y249690D01*
X510761Y249790D01*
X510861Y249870D01*
X510971Y249930D01*
X511096Y249970D01*
X511221Y249980D01*
G37*
G36*
G01X515945D02*
X516070Y249970D01*
X516195Y249930D01*
X516305Y249870D01*
X516405Y249790D01*
X516485Y249690D01*
X516545Y249580D01*
X516585Y249455D01*
X516595Y249330D01*
Y248200D01*
X516625Y248170D01*
X516725Y248030D01*
X516745Y247990D01*
X516760Y247955D01*
X516780Y247915D01*
X516795Y247875D01*
X516805Y247835D01*
X516820Y247790D01*
X516825Y247750D01*
X516835Y247710D01*
X516840Y247665D01*
Y247625D01*
X516845Y247580D01*
X516840Y247535D01*
Y247495D01*
X516835Y247450D01*
X516825Y247410D01*
X516820Y247370D01*
X516805Y247325D01*
X516795Y247285D01*
X516780Y247245D01*
X516760Y247205D01*
X516745Y247170D01*
X516725Y247130D01*
X516625Y246990D01*
X516595Y246960D01*
Y243530D01*
X516585Y243405D01*
X516545Y243280D01*
X516485Y243170D01*
X516405Y243070D01*
X516305Y242990D01*
X516195Y242930D01*
X516070Y242890D01*
X515945Y242880D01*
X515820Y242890D01*
X515695Y242930D01*
X515585Y242990D01*
X515485Y243070D01*
X515405Y243170D01*
X515345Y243280D01*
X515305Y243405D01*
X515295Y243530D01*
Y246960D01*
X515265Y246990D01*
X515165Y247130D01*
X515145Y247170D01*
X515130Y247205D01*
X515110Y247245D01*
X515095Y247285D01*
X515085Y247325D01*
X515070Y247370D01*
X515065Y247410D01*
X515055Y247450D01*
X515050Y247495D01*
Y247535D01*
X515045Y247580D01*
X515050Y247625D01*
Y247665D01*
X515055Y247710D01*
X515065Y247750D01*
X515070Y247790D01*
X515085Y247835D01*
X515095Y247875D01*
X515110Y247915D01*
X515130Y247955D01*
X515145Y247990D01*
X515165Y248030D01*
X515265Y248170D01*
X515295Y248200D01*
Y249330D01*
X515305Y249455D01*
X515345Y249580D01*
X515405Y249690D01*
X515485Y249790D01*
X515585Y249870D01*
X515695Y249930D01*
X515820Y249970D01*
X515945Y249980D01*
G37*
G36*
G01X520670D02*
X520795Y249970D01*
X520920Y249930D01*
X521030Y249870D01*
X521130Y249790D01*
X521210Y249690D01*
X521270Y249580D01*
X521310Y249455D01*
X521320Y249330D01*
Y248200D01*
X521350Y248170D01*
X521450Y248030D01*
X521470Y247990D01*
X521485Y247955D01*
X521505Y247915D01*
X521520Y247875D01*
X521530Y247835D01*
X521545Y247790D01*
X521550Y247750D01*
X521560Y247710D01*
X521565Y247665D01*
Y247625D01*
X521570Y247580D01*
X521565Y247535D01*
Y247495D01*
X521560Y247450D01*
X521550Y247410D01*
X521545Y247370D01*
X521530Y247325D01*
X521520Y247285D01*
X521505Y247245D01*
X521485Y247205D01*
X521470Y247170D01*
X521450Y247130D01*
X521350Y246990D01*
X521320Y246960D01*
Y243530D01*
X521310Y243405D01*
X521270Y243280D01*
X521210Y243170D01*
X521130Y243070D01*
X521030Y242990D01*
X520920Y242930D01*
X520795Y242890D01*
X520670Y242880D01*
X520545Y242890D01*
X520420Y242930D01*
X520310Y242990D01*
X520210Y243070D01*
X520130Y243170D01*
X520070Y243280D01*
X520030Y243405D01*
X520020Y243530D01*
Y246960D01*
X519990Y246990D01*
X519890Y247130D01*
X519870Y247170D01*
X519855Y247205D01*
X519835Y247245D01*
X519820Y247285D01*
X519810Y247325D01*
X519795Y247370D01*
X519790Y247410D01*
X519780Y247450D01*
X519775Y247495D01*
Y247535D01*
X519770Y247580D01*
X519775Y247625D01*
Y247665D01*
X519780Y247710D01*
X519790Y247750D01*
X519795Y247790D01*
X519810Y247835D01*
X519820Y247875D01*
X519835Y247915D01*
X519855Y247955D01*
X519870Y247990D01*
X519890Y248030D01*
X519990Y248170D01*
X520020Y248200D01*
Y249330D01*
X520030Y249455D01*
X520070Y249580D01*
X520130Y249690D01*
X520210Y249790D01*
X520310Y249870D01*
X520420Y249930D01*
X520545Y249970D01*
X520670Y249980D01*
G37*
G36*
G01X525394D02*
X525519Y249970D01*
X525644Y249930D01*
X525754Y249870D01*
X525854Y249790D01*
X525934Y249690D01*
X525994Y249580D01*
X526034Y249455D01*
X526044Y249330D01*
Y248200D01*
X526074Y248170D01*
X526174Y248030D01*
X526194Y247990D01*
X526209Y247955D01*
X526229Y247915D01*
X526244Y247875D01*
X526254Y247835D01*
X526269Y247790D01*
X526274Y247750D01*
X526284Y247710D01*
X526289Y247665D01*
Y247625D01*
X526294Y247580D01*
X526289Y247535D01*
Y247495D01*
X526284Y247450D01*
X526274Y247410D01*
X526269Y247370D01*
X526254Y247325D01*
X526244Y247285D01*
X526229Y247245D01*
X526209Y247205D01*
X526194Y247170D01*
X526174Y247130D01*
X526074Y246990D01*
X526044Y246960D01*
Y243530D01*
X526034Y243405D01*
X525994Y243280D01*
X525934Y243170D01*
X525854Y243070D01*
X525754Y242990D01*
X525644Y242930D01*
X525519Y242890D01*
X525394Y242880D01*
X525269Y242890D01*
X525144Y242930D01*
X525034Y242990D01*
X524934Y243070D01*
X524854Y243170D01*
X524794Y243280D01*
X524754Y243405D01*
X524744Y243530D01*
Y246960D01*
X524714Y246990D01*
X524614Y247130D01*
X524594Y247170D01*
X524579Y247205D01*
X524559Y247245D01*
X524544Y247285D01*
X524534Y247325D01*
X524519Y247370D01*
X524514Y247410D01*
X524504Y247450D01*
X524499Y247495D01*
Y247535D01*
X524494Y247580D01*
X524499Y247625D01*
Y247665D01*
X524504Y247710D01*
X524514Y247750D01*
X524519Y247790D01*
X524534Y247835D01*
X524544Y247875D01*
X524559Y247915D01*
X524579Y247955D01*
X524594Y247990D01*
X524614Y248030D01*
X524714Y248170D01*
X524744Y248200D01*
Y249330D01*
X524754Y249455D01*
X524794Y249580D01*
X524854Y249690D01*
X524934Y249790D01*
X525034Y249870D01*
X525144Y249930D01*
X525269Y249970D01*
X525394Y249980D01*
G37*
G36*
G01X530118D02*
X530243Y249970D01*
X530368Y249930D01*
X530478Y249870D01*
X530578Y249790D01*
X530658Y249690D01*
X530718Y249580D01*
X530758Y249455D01*
X530768Y249330D01*
Y248200D01*
X530798Y248170D01*
X530898Y248030D01*
X530918Y247990D01*
X530933Y247955D01*
X530953Y247915D01*
X530968Y247875D01*
X530978Y247835D01*
X530993Y247790D01*
X530998Y247750D01*
X531008Y247710D01*
X531013Y247665D01*
Y247625D01*
X531018Y247580D01*
X531013Y247535D01*
Y247495D01*
X531008Y247450D01*
X530998Y247410D01*
X530993Y247370D01*
X530978Y247325D01*
X530968Y247285D01*
X530953Y247245D01*
X530933Y247205D01*
X530918Y247170D01*
X530898Y247130D01*
X530798Y246990D01*
X530768Y246960D01*
Y243530D01*
X530758Y243405D01*
X530718Y243280D01*
X530658Y243170D01*
X530578Y243070D01*
X530478Y242990D01*
X530368Y242930D01*
X530243Y242890D01*
X530118Y242880D01*
X529993Y242890D01*
X529868Y242930D01*
X529758Y242990D01*
X529658Y243070D01*
X529578Y243170D01*
X529518Y243280D01*
X529478Y243405D01*
X529468Y243530D01*
Y246960D01*
X529438Y246990D01*
X529338Y247130D01*
X529318Y247170D01*
X529303Y247205D01*
X529283Y247245D01*
X529268Y247285D01*
X529258Y247325D01*
X529243Y247370D01*
X529238Y247410D01*
X529228Y247450D01*
X529223Y247495D01*
Y247535D01*
X529218Y247580D01*
X529223Y247625D01*
Y247665D01*
X529228Y247710D01*
X529238Y247750D01*
X529243Y247790D01*
X529258Y247835D01*
X529268Y247875D01*
X529283Y247915D01*
X529303Y247955D01*
X529318Y247990D01*
X529338Y248030D01*
X529438Y248170D01*
X529468Y248200D01*
Y249330D01*
X529478Y249455D01*
X529518Y249580D01*
X529578Y249690D01*
X529658Y249790D01*
X529758Y249870D01*
X529868Y249930D01*
X529993Y249970D01*
X530118Y249980D01*
G37*
G36*
G01X534843D02*
X534968Y249970D01*
X535093Y249930D01*
X535203Y249870D01*
X535303Y249790D01*
X535383Y249690D01*
X535443Y249580D01*
X535483Y249455D01*
X535493Y249330D01*
Y248200D01*
X535523Y248170D01*
X535623Y248030D01*
X535643Y247990D01*
X535658Y247955D01*
X535678Y247915D01*
X535693Y247875D01*
X535703Y247835D01*
X535718Y247790D01*
X535723Y247750D01*
X535733Y247710D01*
X535738Y247665D01*
Y247625D01*
X535743Y247580D01*
X535738Y247535D01*
Y247495D01*
X535733Y247450D01*
X535723Y247410D01*
X535718Y247370D01*
X535703Y247325D01*
X535693Y247285D01*
X535678Y247245D01*
X535658Y247205D01*
X535643Y247170D01*
X535623Y247130D01*
X535523Y246990D01*
X535493Y246960D01*
Y243530D01*
X535483Y243405D01*
X535443Y243280D01*
X535383Y243170D01*
X535303Y243070D01*
X535203Y242990D01*
X535093Y242930D01*
X534968Y242890D01*
X534843Y242880D01*
X534718Y242890D01*
X534593Y242930D01*
X534483Y242990D01*
X534383Y243070D01*
X534303Y243170D01*
X534243Y243280D01*
X534203Y243405D01*
X534193Y243530D01*
Y246960D01*
X534163Y246990D01*
X534063Y247130D01*
X534043Y247170D01*
X534028Y247205D01*
X534008Y247245D01*
X533993Y247285D01*
X533983Y247325D01*
X533968Y247370D01*
X533963Y247410D01*
X533953Y247450D01*
X533948Y247495D01*
Y247535D01*
X533943Y247580D01*
X533948Y247625D01*
Y247665D01*
X533953Y247710D01*
X533963Y247750D01*
X533968Y247790D01*
X533983Y247835D01*
X533993Y247875D01*
X534008Y247915D01*
X534028Y247955D01*
X534043Y247990D01*
X534063Y248030D01*
X534163Y248170D01*
X534193Y248200D01*
Y249330D01*
X534203Y249455D01*
X534243Y249580D01*
X534303Y249690D01*
X534383Y249790D01*
X534483Y249870D01*
X534593Y249930D01*
X534718Y249970D01*
X534843Y249980D01*
G37*
G36*
G01X539567D02*
X539692Y249970D01*
X539817Y249930D01*
X539927Y249870D01*
X540027Y249790D01*
X540107Y249690D01*
X540167Y249580D01*
X540207Y249455D01*
X540217Y249330D01*
Y248200D01*
X540247Y248170D01*
X540347Y248030D01*
X540367Y247990D01*
X540382Y247955D01*
X540402Y247915D01*
X540417Y247875D01*
X540427Y247835D01*
X540442Y247790D01*
X540447Y247750D01*
X540457Y247710D01*
X540462Y247665D01*
Y247625D01*
X540467Y247580D01*
X540462Y247535D01*
Y247495D01*
X540457Y247450D01*
X540447Y247410D01*
X540442Y247370D01*
X540427Y247325D01*
X540417Y247285D01*
X540402Y247245D01*
X540382Y247205D01*
X540367Y247170D01*
X540347Y247130D01*
X540247Y246990D01*
X540217Y246960D01*
Y243530D01*
X540207Y243405D01*
X540167Y243280D01*
X540107Y243170D01*
X540027Y243070D01*
X539927Y242990D01*
X539817Y242930D01*
X539692Y242890D01*
X539567Y242880D01*
X539442Y242890D01*
X539317Y242930D01*
X539207Y242990D01*
X539107Y243070D01*
X539027Y243170D01*
X538967Y243280D01*
X538927Y243405D01*
X538917Y243530D01*
Y246960D01*
X538887Y246990D01*
X538787Y247130D01*
X538767Y247170D01*
X538752Y247205D01*
X538732Y247245D01*
X538717Y247285D01*
X538707Y247325D01*
X538692Y247370D01*
X538687Y247410D01*
X538677Y247450D01*
X538672Y247495D01*
Y247535D01*
X538667Y247580D01*
X538672Y247625D01*
Y247665D01*
X538677Y247710D01*
X538687Y247750D01*
X538692Y247790D01*
X538707Y247835D01*
X538717Y247875D01*
X538732Y247915D01*
X538752Y247955D01*
X538767Y247990D01*
X538787Y248030D01*
X538887Y248170D01*
X538917Y248200D01*
Y249330D01*
X538927Y249455D01*
X538967Y249580D01*
X539027Y249690D01*
X539107Y249790D01*
X539207Y249870D01*
X539317Y249930D01*
X539442Y249970D01*
X539567Y249980D01*
G37*
G36*
G01X544292D02*
X544417Y249970D01*
X544542Y249930D01*
X544652Y249870D01*
X544752Y249790D01*
X544832Y249690D01*
X544892Y249580D01*
X544932Y249455D01*
X544942Y249330D01*
Y248200D01*
X544972Y248170D01*
X545072Y248030D01*
X545092Y247990D01*
X545107Y247955D01*
X545127Y247915D01*
X545142Y247875D01*
X545152Y247835D01*
X545167Y247790D01*
X545172Y247750D01*
X545182Y247710D01*
X545187Y247665D01*
Y247625D01*
X545192Y247580D01*
X545187Y247535D01*
Y247495D01*
X545182Y247450D01*
X545172Y247410D01*
X545167Y247370D01*
X545152Y247325D01*
X545142Y247285D01*
X545127Y247245D01*
X545107Y247205D01*
X545092Y247170D01*
X545072Y247130D01*
X544972Y246990D01*
X544942Y246960D01*
Y243530D01*
X544932Y243405D01*
X544892Y243280D01*
X544832Y243170D01*
X544752Y243070D01*
X544652Y242990D01*
X544542Y242930D01*
X544417Y242890D01*
X544292Y242880D01*
X544167Y242890D01*
X544042Y242930D01*
X543932Y242990D01*
X543832Y243070D01*
X543752Y243170D01*
X543692Y243280D01*
X543652Y243405D01*
X543642Y243530D01*
Y246960D01*
X543612Y246990D01*
X543512Y247130D01*
X543492Y247170D01*
X543477Y247205D01*
X543457Y247245D01*
X543442Y247285D01*
X543432Y247325D01*
X543417Y247370D01*
X543412Y247410D01*
X543402Y247450D01*
X543397Y247495D01*
Y247535D01*
X543392Y247580D01*
X543397Y247625D01*
Y247665D01*
X543402Y247710D01*
X543412Y247750D01*
X543417Y247790D01*
X543432Y247835D01*
X543442Y247875D01*
X543457Y247915D01*
X543477Y247955D01*
X543492Y247990D01*
X543512Y248030D01*
X543612Y248170D01*
X543642Y248200D01*
Y249330D01*
X543652Y249455D01*
X543692Y249580D01*
X543752Y249690D01*
X543832Y249790D01*
X543932Y249870D01*
X544042Y249930D01*
X544167Y249970D01*
X544292Y249980D01*
G37*
G36*
G01X549016D02*
X549141Y249970D01*
X549266Y249930D01*
X549376Y249870D01*
X549476Y249790D01*
X549556Y249690D01*
X549616Y249580D01*
X549656Y249455D01*
X549666Y249330D01*
Y248200D01*
X549696Y248170D01*
X549796Y248030D01*
X549816Y247990D01*
X549831Y247955D01*
X549851Y247915D01*
X549866Y247875D01*
X549876Y247835D01*
X549891Y247790D01*
X549896Y247750D01*
X549906Y247710D01*
X549911Y247665D01*
Y247625D01*
X549916Y247580D01*
X549911Y247535D01*
Y247495D01*
X549906Y247450D01*
X549896Y247410D01*
X549891Y247370D01*
X549876Y247325D01*
X549866Y247285D01*
X549851Y247245D01*
X549831Y247205D01*
X549816Y247170D01*
X549796Y247130D01*
X549696Y246990D01*
X549666Y246960D01*
Y243530D01*
X549656Y243405D01*
X549616Y243280D01*
X549556Y243170D01*
X549476Y243070D01*
X549376Y242990D01*
X549266Y242930D01*
X549141Y242890D01*
X549016Y242880D01*
X548891Y242890D01*
X548766Y242930D01*
X548656Y242990D01*
X548556Y243070D01*
X548476Y243170D01*
X548416Y243280D01*
X548376Y243405D01*
X548366Y243530D01*
Y246960D01*
X548336Y246990D01*
X548236Y247130D01*
X548216Y247170D01*
X548201Y247205D01*
X548181Y247245D01*
X548166Y247285D01*
X548156Y247325D01*
X548141Y247370D01*
X548136Y247410D01*
X548126Y247450D01*
X548121Y247495D01*
Y247535D01*
X548116Y247580D01*
X548121Y247625D01*
Y247665D01*
X548126Y247710D01*
X548136Y247750D01*
X548141Y247790D01*
X548156Y247835D01*
X548166Y247875D01*
X548181Y247915D01*
X548201Y247955D01*
X548216Y247990D01*
X548236Y248030D01*
X548336Y248170D01*
X548366Y248200D01*
Y249330D01*
X548376Y249455D01*
X548416Y249580D01*
X548476Y249690D01*
X548556Y249790D01*
X548656Y249870D01*
X548766Y249930D01*
X548891Y249970D01*
X549016Y249980D01*
G37*
G36*
G01X553740D02*
X553865Y249970D01*
X553990Y249930D01*
X554100Y249870D01*
X554200Y249790D01*
X554280Y249690D01*
X554340Y249580D01*
X554380Y249455D01*
X554390Y249330D01*
Y248200D01*
X554420Y248170D01*
X554520Y248030D01*
X554540Y247990D01*
X554555Y247955D01*
X554575Y247915D01*
X554590Y247875D01*
X554600Y247835D01*
X554615Y247790D01*
X554620Y247750D01*
X554630Y247710D01*
X554635Y247665D01*
Y247625D01*
X554640Y247580D01*
X554635Y247535D01*
Y247495D01*
X554630Y247450D01*
X554620Y247410D01*
X554615Y247370D01*
X554600Y247325D01*
X554590Y247285D01*
X554575Y247245D01*
X554555Y247205D01*
X554540Y247170D01*
X554520Y247130D01*
X554420Y246990D01*
X554390Y246960D01*
Y243530D01*
X554380Y243405D01*
X554340Y243280D01*
X554280Y243170D01*
X554200Y243070D01*
X554100Y242990D01*
X553990Y242930D01*
X553865Y242890D01*
X553740Y242880D01*
X553615Y242890D01*
X553490Y242930D01*
X553380Y242990D01*
X553280Y243070D01*
X553200Y243170D01*
X553140Y243280D01*
X553100Y243405D01*
X553090Y243530D01*
Y246960D01*
X553060Y246990D01*
X552960Y247130D01*
X552940Y247170D01*
X552925Y247205D01*
X552905Y247245D01*
X552890Y247285D01*
X552880Y247325D01*
X552865Y247370D01*
X552860Y247410D01*
X552850Y247450D01*
X552845Y247495D01*
Y247535D01*
X552840Y247580D01*
X552845Y247625D01*
Y247665D01*
X552850Y247710D01*
X552860Y247750D01*
X552865Y247790D01*
X552880Y247835D01*
X552890Y247875D01*
X552905Y247915D01*
X552925Y247955D01*
X552940Y247990D01*
X552960Y248030D01*
X553060Y248170D01*
X553090Y248200D01*
Y249330D01*
X553100Y249455D01*
X553140Y249580D01*
X553200Y249690D01*
X553280Y249790D01*
X553380Y249870D01*
X553490Y249930D01*
X553615Y249970D01*
X553740Y249980D01*
G37*
G36*
G01X558465D02*
X558590Y249970D01*
X558715Y249930D01*
X558825Y249870D01*
X558925Y249790D01*
X559005Y249690D01*
X559065Y249580D01*
X559105Y249455D01*
X559115Y249330D01*
Y248200D01*
X559145Y248170D01*
X559245Y248030D01*
X559265Y247990D01*
X559280Y247955D01*
X559300Y247915D01*
X559315Y247875D01*
X559325Y247835D01*
X559340Y247790D01*
X559345Y247750D01*
X559355Y247710D01*
X559360Y247665D01*
Y247625D01*
X559365Y247580D01*
X559360Y247535D01*
Y247495D01*
X559355Y247450D01*
X559345Y247410D01*
X559340Y247370D01*
X559325Y247325D01*
X559315Y247285D01*
X559300Y247245D01*
X559280Y247205D01*
X559265Y247170D01*
X559245Y247130D01*
X559145Y246990D01*
X559115Y246960D01*
Y243530D01*
X559105Y243405D01*
X559065Y243280D01*
X559005Y243170D01*
X558925Y243070D01*
X558825Y242990D01*
X558715Y242930D01*
X558590Y242890D01*
X558465Y242880D01*
X558340Y242890D01*
X558215Y242930D01*
X558105Y242990D01*
X558005Y243070D01*
X557925Y243170D01*
X557865Y243280D01*
X557825Y243405D01*
X557815Y243530D01*
Y246960D01*
X557785Y246990D01*
X557685Y247130D01*
X557665Y247170D01*
X557650Y247205D01*
X557630Y247245D01*
X557615Y247285D01*
X557605Y247325D01*
X557590Y247370D01*
X557585Y247410D01*
X557575Y247450D01*
X557570Y247495D01*
Y247535D01*
X557565Y247580D01*
X557570Y247625D01*
Y247665D01*
X557575Y247710D01*
X557585Y247750D01*
X557590Y247790D01*
X557605Y247835D01*
X557615Y247875D01*
X557630Y247915D01*
X557650Y247955D01*
X557665Y247990D01*
X557685Y248030D01*
X557785Y248170D01*
X557815Y248200D01*
Y249330D01*
X557825Y249455D01*
X557865Y249580D01*
X557925Y249690D01*
X558005Y249790D01*
X558105Y249870D01*
X558215Y249930D01*
X558340Y249970D01*
X558465Y249980D01*
G37*
G36*
G01X563189D02*
X563314Y249970D01*
X563439Y249930D01*
X563549Y249870D01*
X563649Y249790D01*
X563729Y249690D01*
X563789Y249580D01*
X563829Y249455D01*
X563839Y249330D01*
Y248200D01*
X563869Y248170D01*
X563969Y248030D01*
X563989Y247990D01*
X564004Y247955D01*
X564024Y247915D01*
X564039Y247875D01*
X564049Y247835D01*
X564064Y247790D01*
X564069Y247750D01*
X564079Y247710D01*
X564084Y247665D01*
Y247625D01*
X564089Y247580D01*
X564084Y247535D01*
Y247495D01*
X564079Y247450D01*
X564069Y247410D01*
X564064Y247370D01*
X564049Y247325D01*
X564039Y247285D01*
X564024Y247245D01*
X564004Y247205D01*
X563989Y247170D01*
X563969Y247130D01*
X563869Y246990D01*
X563839Y246960D01*
Y243530D01*
X563829Y243405D01*
X563789Y243280D01*
X563729Y243170D01*
X563649Y243070D01*
X563549Y242990D01*
X563439Y242930D01*
X563314Y242890D01*
X563189Y242880D01*
X563064Y242890D01*
X562939Y242930D01*
X562829Y242990D01*
X562729Y243070D01*
X562649Y243170D01*
X562589Y243280D01*
X562549Y243405D01*
X562539Y243530D01*
Y246960D01*
X562509Y246990D01*
X562409Y247130D01*
X562389Y247170D01*
X562374Y247205D01*
X562354Y247245D01*
X562339Y247285D01*
X562329Y247325D01*
X562314Y247370D01*
X562309Y247410D01*
X562299Y247450D01*
X562294Y247495D01*
Y247535D01*
X562289Y247580D01*
X562294Y247625D01*
Y247665D01*
X562299Y247710D01*
X562309Y247750D01*
X562314Y247790D01*
X562329Y247835D01*
X562339Y247875D01*
X562354Y247915D01*
X562374Y247955D01*
X562389Y247990D01*
X562409Y248030D01*
X562509Y248170D01*
X562539Y248200D01*
Y249330D01*
X562549Y249455D01*
X562589Y249580D01*
X562649Y249690D01*
X562729Y249790D01*
X562829Y249870D01*
X562939Y249930D01*
X563064Y249970D01*
X563189Y249980D01*
G37*
G36*
G01X567914D02*
X568039Y249970D01*
X568164Y249930D01*
X568274Y249870D01*
X568374Y249790D01*
X568454Y249690D01*
X568514Y249580D01*
X568554Y249455D01*
X568564Y249330D01*
Y248200D01*
X568594Y248170D01*
X568694Y248030D01*
X568714Y247990D01*
X568729Y247955D01*
X568749Y247915D01*
X568764Y247875D01*
X568774Y247835D01*
X568789Y247790D01*
X568794Y247750D01*
X568804Y247710D01*
X568809Y247665D01*
Y247625D01*
X568814Y247580D01*
X568809Y247535D01*
Y247495D01*
X568804Y247450D01*
X568794Y247410D01*
X568789Y247370D01*
X568774Y247325D01*
X568764Y247285D01*
X568749Y247245D01*
X568729Y247205D01*
X568714Y247170D01*
X568694Y247130D01*
X568594Y246990D01*
X568564Y246960D01*
Y243530D01*
X568554Y243405D01*
X568514Y243280D01*
X568454Y243170D01*
X568374Y243070D01*
X568274Y242990D01*
X568164Y242930D01*
X568039Y242890D01*
X567914Y242880D01*
X567789Y242890D01*
X567664Y242930D01*
X567554Y242990D01*
X567454Y243070D01*
X567374Y243170D01*
X567314Y243280D01*
X567274Y243405D01*
X567264Y243530D01*
Y246960D01*
X567234Y246990D01*
X567134Y247130D01*
X567114Y247170D01*
X567099Y247205D01*
X567079Y247245D01*
X567064Y247285D01*
X567054Y247325D01*
X567039Y247370D01*
X567034Y247410D01*
X567024Y247450D01*
X567019Y247495D01*
Y247535D01*
X567014Y247580D01*
X567019Y247625D01*
Y247665D01*
X567024Y247710D01*
X567034Y247750D01*
X567039Y247790D01*
X567054Y247835D01*
X567064Y247875D01*
X567079Y247915D01*
X567099Y247955D01*
X567114Y247990D01*
X567134Y248030D01*
X567234Y248170D01*
X567264Y248200D01*
Y249330D01*
X567274Y249455D01*
X567314Y249580D01*
X567374Y249690D01*
X567454Y249790D01*
X567554Y249870D01*
X567664Y249930D01*
X567789Y249970D01*
X567914Y249980D01*
G37*
G36*
G01X572638D02*
X572763Y249970D01*
X572888Y249930D01*
X572998Y249870D01*
X573098Y249790D01*
X573178Y249690D01*
X573238Y249580D01*
X573278Y249455D01*
X573288Y249330D01*
Y248200D01*
X573318Y248170D01*
X573418Y248030D01*
X573438Y247990D01*
X573453Y247955D01*
X573473Y247915D01*
X573488Y247875D01*
X573498Y247835D01*
X573513Y247790D01*
X573518Y247750D01*
X573528Y247710D01*
X573533Y247665D01*
Y247625D01*
X573538Y247580D01*
X573533Y247535D01*
Y247495D01*
X573528Y247450D01*
X573518Y247410D01*
X573513Y247370D01*
X573498Y247325D01*
X573488Y247285D01*
X573473Y247245D01*
X573453Y247205D01*
X573438Y247170D01*
X573418Y247130D01*
X573318Y246990D01*
X573288Y246960D01*
Y243530D01*
X573278Y243405D01*
X573238Y243280D01*
X573178Y243170D01*
X573098Y243070D01*
X572998Y242990D01*
X572888Y242930D01*
X572763Y242890D01*
X572638Y242880D01*
X572513Y242890D01*
X572388Y242930D01*
X572278Y242990D01*
X572178Y243070D01*
X572098Y243170D01*
X572038Y243280D01*
X571998Y243405D01*
X571988Y243530D01*
Y246960D01*
X571958Y246990D01*
X571858Y247130D01*
X571838Y247170D01*
X571823Y247205D01*
X571803Y247245D01*
X571788Y247285D01*
X571778Y247325D01*
X571763Y247370D01*
X571758Y247410D01*
X571748Y247450D01*
X571743Y247495D01*
Y247535D01*
X571738Y247580D01*
X571743Y247625D01*
Y247665D01*
X571748Y247710D01*
X571758Y247750D01*
X571763Y247790D01*
X571778Y247835D01*
X571788Y247875D01*
X571803Y247915D01*
X571823Y247955D01*
X571838Y247990D01*
X571858Y248030D01*
X571958Y248170D01*
X571988Y248200D01*
Y249330D01*
X571998Y249455D01*
X572038Y249580D01*
X572098Y249690D01*
X572178Y249790D01*
X572278Y249870D01*
X572388Y249930D01*
X572513Y249970D01*
X572638Y249980D01*
G37*
G36*
G01X577362D02*
X577487Y249970D01*
X577612Y249930D01*
X577722Y249870D01*
X577822Y249790D01*
X577902Y249690D01*
X577962Y249580D01*
X578002Y249455D01*
X578012Y249330D01*
Y248200D01*
X578042Y248170D01*
X578142Y248030D01*
X578162Y247990D01*
X578177Y247955D01*
X578197Y247915D01*
X578212Y247875D01*
X578222Y247835D01*
X578237Y247790D01*
X578242Y247750D01*
X578252Y247710D01*
X578257Y247665D01*
Y247625D01*
X578262Y247580D01*
X578257Y247535D01*
Y247495D01*
X578252Y247450D01*
X578242Y247410D01*
X578237Y247370D01*
X578222Y247325D01*
X578212Y247285D01*
X578197Y247245D01*
X578177Y247205D01*
X578162Y247170D01*
X578142Y247130D01*
X578042Y246990D01*
X578012Y246960D01*
Y243530D01*
X578002Y243405D01*
X577962Y243280D01*
X577902Y243170D01*
X577822Y243070D01*
X577722Y242990D01*
X577612Y242930D01*
X577487Y242890D01*
X577362Y242880D01*
X577237Y242890D01*
X577112Y242930D01*
X577002Y242990D01*
X576902Y243070D01*
X576822Y243170D01*
X576762Y243280D01*
X576722Y243405D01*
X576712Y243530D01*
Y246960D01*
X576682Y246990D01*
X576582Y247130D01*
X576562Y247170D01*
X576547Y247205D01*
X576527Y247245D01*
X576512Y247285D01*
X576502Y247325D01*
X576487Y247370D01*
X576482Y247410D01*
X576472Y247450D01*
X576467Y247495D01*
Y247535D01*
X576462Y247580D01*
X576467Y247625D01*
Y247665D01*
X576472Y247710D01*
X576482Y247750D01*
X576487Y247790D01*
X576502Y247835D01*
X576512Y247875D01*
X576527Y247915D01*
X576547Y247955D01*
X576562Y247990D01*
X576582Y248030D01*
X576682Y248170D01*
X576712Y248200D01*
Y249330D01*
X576722Y249455D01*
X576762Y249580D01*
X576822Y249690D01*
X576902Y249790D01*
X577002Y249870D01*
X577112Y249930D01*
X577237Y249970D01*
X577362Y249980D01*
G37*
G36*
G01X582087D02*
X582212Y249970D01*
X582337Y249930D01*
X582447Y249870D01*
X582547Y249790D01*
X582627Y249690D01*
X582687Y249580D01*
X582727Y249455D01*
X582737Y249330D01*
Y248200D01*
X582767Y248170D01*
X582867Y248030D01*
X582887Y247990D01*
X582902Y247955D01*
X582922Y247915D01*
X582937Y247875D01*
X582947Y247835D01*
X582962Y247790D01*
X582967Y247750D01*
X582977Y247710D01*
X582982Y247665D01*
Y247625D01*
X582987Y247580D01*
X582982Y247535D01*
Y247495D01*
X582977Y247450D01*
X582967Y247410D01*
X582962Y247370D01*
X582947Y247325D01*
X582937Y247285D01*
X582922Y247245D01*
X582902Y247205D01*
X582887Y247170D01*
X582867Y247130D01*
X582767Y246990D01*
X582737Y246960D01*
Y243530D01*
X582727Y243405D01*
X582687Y243280D01*
X582627Y243170D01*
X582547Y243070D01*
X582447Y242990D01*
X582337Y242930D01*
X582212Y242890D01*
X582087Y242880D01*
X581962Y242890D01*
X581837Y242930D01*
X581727Y242990D01*
X581627Y243070D01*
X581547Y243170D01*
X581487Y243280D01*
X581447Y243405D01*
X581437Y243530D01*
Y246960D01*
X581407Y246990D01*
X581307Y247130D01*
X581287Y247170D01*
X581272Y247205D01*
X581252Y247245D01*
X581237Y247285D01*
X581227Y247325D01*
X581212Y247370D01*
X581207Y247410D01*
X581197Y247450D01*
X581192Y247495D01*
Y247535D01*
X581187Y247580D01*
X581192Y247625D01*
Y247665D01*
X581197Y247710D01*
X581207Y247750D01*
X581212Y247790D01*
X581227Y247835D01*
X581237Y247875D01*
X581252Y247915D01*
X581272Y247955D01*
X581287Y247990D01*
X581307Y248030D01*
X581407Y248170D01*
X581437Y248200D01*
Y249330D01*
X581447Y249455D01*
X581487Y249580D01*
X581547Y249690D01*
X581627Y249790D01*
X581727Y249870D01*
X581837Y249930D01*
X581962Y249970D01*
X582087Y249980D01*
G37*
G36*
G01X586811D02*
X586936Y249970D01*
X587061Y249930D01*
X587171Y249870D01*
X587271Y249790D01*
X587351Y249690D01*
X587411Y249580D01*
X587451Y249455D01*
X587461Y249330D01*
Y248200D01*
X587491Y248170D01*
X587591Y248030D01*
X587611Y247990D01*
X587626Y247955D01*
X587646Y247915D01*
X587661Y247875D01*
X587671Y247835D01*
X587686Y247790D01*
X587691Y247750D01*
X587701Y247710D01*
X587706Y247665D01*
Y247625D01*
X587711Y247580D01*
X587706Y247535D01*
Y247495D01*
X587701Y247450D01*
X587691Y247410D01*
X587686Y247370D01*
X587671Y247325D01*
X587661Y247285D01*
X587646Y247245D01*
X587626Y247205D01*
X587611Y247170D01*
X587591Y247130D01*
X587491Y246990D01*
X587461Y246960D01*
Y243530D01*
X587451Y243405D01*
X587411Y243280D01*
X587351Y243170D01*
X587271Y243070D01*
X587171Y242990D01*
X587061Y242930D01*
X586936Y242890D01*
X586811Y242880D01*
X586686Y242890D01*
X586561Y242930D01*
X586451Y242990D01*
X586351Y243070D01*
X586271Y243170D01*
X586211Y243280D01*
X586171Y243405D01*
X586161Y243530D01*
Y246960D01*
X586131Y246990D01*
X586031Y247130D01*
X586011Y247170D01*
X585996Y247205D01*
X585976Y247245D01*
X585961Y247285D01*
X585951Y247325D01*
X585936Y247370D01*
X585931Y247410D01*
X585921Y247450D01*
X585916Y247495D01*
Y247535D01*
X585911Y247580D01*
X585916Y247625D01*
Y247665D01*
X585921Y247710D01*
X585931Y247750D01*
X585936Y247790D01*
X585951Y247835D01*
X585961Y247875D01*
X585976Y247915D01*
X585996Y247955D01*
X586011Y247990D01*
X586031Y248030D01*
X586131Y248170D01*
X586161Y248200D01*
Y249330D01*
X586171Y249455D01*
X586211Y249580D01*
X586271Y249690D01*
X586351Y249790D01*
X586451Y249870D01*
X586561Y249930D01*
X586686Y249970D01*
X586811Y249980D01*
G37*
G36*
G01X591536D02*
X591661Y249970D01*
X591786Y249930D01*
X591896Y249870D01*
X591996Y249790D01*
X592076Y249690D01*
X592136Y249580D01*
X592176Y249455D01*
X592186Y249330D01*
Y248200D01*
X592216Y248170D01*
X592316Y248030D01*
X592336Y247990D01*
X592351Y247955D01*
X592371Y247915D01*
X592386Y247875D01*
X592396Y247835D01*
X592411Y247790D01*
X592416Y247750D01*
X592426Y247710D01*
X592431Y247665D01*
Y247625D01*
X592436Y247580D01*
X592431Y247535D01*
Y247495D01*
X592426Y247450D01*
X592416Y247410D01*
X592411Y247370D01*
X592396Y247325D01*
X592386Y247285D01*
X592371Y247245D01*
X592351Y247205D01*
X592336Y247170D01*
X592316Y247130D01*
X592216Y246990D01*
X592186Y246960D01*
Y243530D01*
X592176Y243405D01*
X592136Y243280D01*
X592076Y243170D01*
X591996Y243070D01*
X591896Y242990D01*
X591786Y242930D01*
X591661Y242890D01*
X591536Y242880D01*
X591411Y242890D01*
X591286Y242930D01*
X591176Y242990D01*
X591076Y243070D01*
X590996Y243170D01*
X590936Y243280D01*
X590896Y243405D01*
X590886Y243530D01*
Y246960D01*
X590856Y246990D01*
X590756Y247130D01*
X590736Y247170D01*
X590721Y247205D01*
X590701Y247245D01*
X590686Y247285D01*
X590676Y247325D01*
X590661Y247370D01*
X590656Y247410D01*
X590646Y247450D01*
X590641Y247495D01*
Y247535D01*
X590636Y247580D01*
X590641Y247625D01*
Y247665D01*
X590646Y247710D01*
X590656Y247750D01*
X590661Y247790D01*
X590676Y247835D01*
X590686Y247875D01*
X590701Y247915D01*
X590721Y247955D01*
X590736Y247990D01*
X590756Y248030D01*
X590856Y248170D01*
X590886Y248200D01*
Y249330D01*
X590896Y249455D01*
X590936Y249580D01*
X590996Y249690D01*
X591076Y249790D01*
X591176Y249870D01*
X591286Y249930D01*
X591411Y249970D01*
X591536Y249980D01*
G37*
G36*
G01X596260D02*
X596385Y249970D01*
X596510Y249930D01*
X596620Y249870D01*
X596720Y249790D01*
X596800Y249690D01*
X596860Y249580D01*
X596900Y249455D01*
X596910Y249330D01*
Y248200D01*
X596940Y248170D01*
X597040Y248030D01*
X597060Y247990D01*
X597075Y247955D01*
X597095Y247915D01*
X597110Y247875D01*
X597120Y247835D01*
X597135Y247790D01*
X597140Y247750D01*
X597150Y247710D01*
X597155Y247665D01*
Y247625D01*
X597160Y247580D01*
X597155Y247535D01*
Y247495D01*
X597150Y247450D01*
X597140Y247410D01*
X597135Y247370D01*
X597120Y247325D01*
X597110Y247285D01*
X597095Y247245D01*
X597075Y247205D01*
X597060Y247170D01*
X597040Y247130D01*
X596940Y246990D01*
X596910Y246960D01*
Y243530D01*
X596900Y243405D01*
X596860Y243280D01*
X596800Y243170D01*
X596720Y243070D01*
X596620Y242990D01*
X596510Y242930D01*
X596385Y242890D01*
X596260Y242880D01*
X596135Y242890D01*
X596010Y242930D01*
X595900Y242990D01*
X595800Y243070D01*
X595720Y243170D01*
X595660Y243280D01*
X595620Y243405D01*
X595610Y243530D01*
Y246960D01*
X595580Y246990D01*
X595480Y247130D01*
X595460Y247170D01*
X595445Y247205D01*
X595425Y247245D01*
X595410Y247285D01*
X595400Y247325D01*
X595385Y247370D01*
X595380Y247410D01*
X595370Y247450D01*
X595365Y247495D01*
Y247535D01*
X595360Y247580D01*
X595365Y247625D01*
Y247665D01*
X595370Y247710D01*
X595380Y247750D01*
X595385Y247790D01*
X595400Y247835D01*
X595410Y247875D01*
X595425Y247915D01*
X595445Y247955D01*
X595460Y247990D01*
X595480Y248030D01*
X595580Y248170D01*
X595610Y248200D01*
Y249330D01*
X595620Y249455D01*
X595660Y249580D01*
X595720Y249690D01*
X595800Y249790D01*
X595900Y249870D01*
X596010Y249930D01*
X596135Y249970D01*
X596260Y249980D01*
G37*
G36*
G01X600985D02*
X601110Y249970D01*
X601235Y249930D01*
X601345Y249870D01*
X601445Y249790D01*
X601525Y249690D01*
X601585Y249580D01*
X601625Y249455D01*
X601635Y249330D01*
Y248200D01*
X601665Y248170D01*
X601765Y248030D01*
X601785Y247990D01*
X601800Y247955D01*
X601820Y247915D01*
X601835Y247875D01*
X601845Y247835D01*
X601860Y247790D01*
X601865Y247750D01*
X601875Y247710D01*
X601880Y247665D01*
Y247625D01*
X601885Y247580D01*
X601880Y247535D01*
Y247495D01*
X601875Y247450D01*
X601865Y247410D01*
X601860Y247370D01*
X601845Y247325D01*
X601835Y247285D01*
X601820Y247245D01*
X601800Y247205D01*
X601785Y247170D01*
X601765Y247130D01*
X601665Y246990D01*
X601635Y246960D01*
Y243530D01*
X601625Y243405D01*
X601585Y243280D01*
X601525Y243170D01*
X601445Y243070D01*
X601345Y242990D01*
X601235Y242930D01*
X601110Y242890D01*
X600985Y242880D01*
X600860Y242890D01*
X600735Y242930D01*
X600625Y242990D01*
X600525Y243070D01*
X600445Y243170D01*
X600385Y243280D01*
X600345Y243405D01*
X600335Y243530D01*
Y246960D01*
X600305Y246990D01*
X600205Y247130D01*
X600185Y247170D01*
X600170Y247205D01*
X600150Y247245D01*
X600135Y247285D01*
X600125Y247325D01*
X600110Y247370D01*
X600105Y247410D01*
X600095Y247450D01*
X600090Y247495D01*
Y247535D01*
X600085Y247580D01*
X600090Y247625D01*
Y247665D01*
X600095Y247710D01*
X600105Y247750D01*
X600110Y247790D01*
X600125Y247835D01*
X600135Y247875D01*
X600150Y247915D01*
X600170Y247955D01*
X600185Y247990D01*
X600205Y248030D01*
X600305Y248170D01*
X600335Y248200D01*
Y249330D01*
X600345Y249455D01*
X600385Y249580D01*
X600445Y249690D01*
X600525Y249790D01*
X600625Y249870D01*
X600735Y249930D01*
X600860Y249970D01*
X600985Y249980D01*
G37*
G36*
G01X605709D02*
X605834Y249970D01*
X605959Y249930D01*
X606069Y249870D01*
X606169Y249790D01*
X606249Y249690D01*
X606309Y249580D01*
X606349Y249455D01*
X606359Y249330D01*
Y248200D01*
X606389Y248170D01*
X606489Y248030D01*
X606509Y247990D01*
X606524Y247955D01*
X606544Y247915D01*
X606559Y247875D01*
X606569Y247835D01*
X606584Y247790D01*
X606589Y247750D01*
X606599Y247710D01*
X606604Y247665D01*
Y247625D01*
X606609Y247580D01*
X606604Y247535D01*
Y247495D01*
X606599Y247450D01*
X606589Y247410D01*
X606584Y247370D01*
X606569Y247325D01*
X606559Y247285D01*
X606544Y247245D01*
X606524Y247205D01*
X606509Y247170D01*
X606489Y247130D01*
X606389Y246990D01*
X606359Y246960D01*
Y243530D01*
X606349Y243405D01*
X606309Y243280D01*
X606249Y243170D01*
X606169Y243070D01*
X606069Y242990D01*
X605959Y242930D01*
X605834Y242890D01*
X605709Y242880D01*
X605584Y242890D01*
X605459Y242930D01*
X605349Y242990D01*
X605249Y243070D01*
X605169Y243170D01*
X605109Y243280D01*
X605069Y243405D01*
X605059Y243530D01*
Y246960D01*
X605029Y246990D01*
X604929Y247130D01*
X604909Y247170D01*
X604894Y247205D01*
X604874Y247245D01*
X604859Y247285D01*
X604849Y247325D01*
X604834Y247370D01*
X604829Y247410D01*
X604819Y247450D01*
X604814Y247495D01*
Y247535D01*
X604809Y247580D01*
X604814Y247625D01*
Y247665D01*
X604819Y247710D01*
X604829Y247750D01*
X604834Y247790D01*
X604849Y247835D01*
X604859Y247875D01*
X604874Y247915D01*
X604894Y247955D01*
X604909Y247990D01*
X604929Y248030D01*
X605029Y248170D01*
X605059Y248200D01*
Y249330D01*
X605069Y249455D01*
X605109Y249580D01*
X605169Y249690D01*
X605249Y249790D01*
X605349Y249870D01*
X605459Y249930D01*
X605584Y249970D01*
X605709Y249980D01*
G37*
G36*
G01X610433D02*
X610558Y249970D01*
X610683Y249930D01*
X610793Y249870D01*
X610893Y249790D01*
X610973Y249690D01*
X611033Y249580D01*
X611073Y249455D01*
X611083Y249330D01*
Y248200D01*
X611113Y248170D01*
X611213Y248030D01*
X611233Y247990D01*
X611248Y247955D01*
X611268Y247915D01*
X611283Y247875D01*
X611293Y247835D01*
X611308Y247790D01*
X611313Y247750D01*
X611323Y247710D01*
X611328Y247665D01*
Y247625D01*
X611333Y247580D01*
X611328Y247535D01*
Y247495D01*
X611323Y247450D01*
X611313Y247410D01*
X611308Y247370D01*
X611293Y247325D01*
X611283Y247285D01*
X611268Y247245D01*
X611248Y247205D01*
X611233Y247170D01*
X611213Y247130D01*
X611113Y246990D01*
X611083Y246960D01*
Y243530D01*
X611073Y243405D01*
X611033Y243280D01*
X610973Y243170D01*
X610893Y243070D01*
X610793Y242990D01*
X610683Y242930D01*
X610558Y242890D01*
X610433Y242880D01*
X610308Y242890D01*
X610183Y242930D01*
X610073Y242990D01*
X609973Y243070D01*
X609893Y243170D01*
X609833Y243280D01*
X609793Y243405D01*
X609783Y243530D01*
Y246960D01*
X609753Y246990D01*
X609653Y247130D01*
X609633Y247170D01*
X609618Y247205D01*
X609598Y247245D01*
X609583Y247285D01*
X609573Y247325D01*
X609558Y247370D01*
X609553Y247410D01*
X609543Y247450D01*
X609538Y247495D01*
Y247535D01*
X609533Y247580D01*
X609538Y247625D01*
Y247665D01*
X609543Y247710D01*
X609553Y247750D01*
X609558Y247790D01*
X609573Y247835D01*
X609583Y247875D01*
X609598Y247915D01*
X609618Y247955D01*
X609633Y247990D01*
X609653Y248030D01*
X609753Y248170D01*
X609783Y248200D01*
Y249330D01*
X609793Y249455D01*
X609833Y249580D01*
X609893Y249690D01*
X609973Y249790D01*
X610073Y249870D01*
X610183Y249930D01*
X610308Y249970D01*
X610433Y249980D01*
G37*
G36*
G01X615158D02*
X615283Y249970D01*
X615408Y249930D01*
X615518Y249870D01*
X615618Y249790D01*
X615698Y249690D01*
X615758Y249580D01*
X615798Y249455D01*
X615808Y249330D01*
Y248200D01*
X615838Y248170D01*
X615938Y248030D01*
X615958Y247990D01*
X615973Y247955D01*
X615993Y247915D01*
X616008Y247875D01*
X616018Y247835D01*
X616033Y247790D01*
X616038Y247750D01*
X616048Y247710D01*
X616053Y247665D01*
Y247625D01*
X616058Y247580D01*
X616053Y247535D01*
Y247495D01*
X616048Y247450D01*
X616038Y247410D01*
X616033Y247370D01*
X616018Y247325D01*
X616008Y247285D01*
X615993Y247245D01*
X615973Y247205D01*
X615958Y247170D01*
X615938Y247130D01*
X615838Y246990D01*
X615808Y246960D01*
Y243530D01*
X615798Y243405D01*
X615758Y243280D01*
X615698Y243170D01*
X615618Y243070D01*
X615518Y242990D01*
X615408Y242930D01*
X615283Y242890D01*
X615158Y242880D01*
X615033Y242890D01*
X614908Y242930D01*
X614798Y242990D01*
X614698Y243070D01*
X614618Y243170D01*
X614558Y243280D01*
X614518Y243405D01*
X614508Y243530D01*
Y246960D01*
X614478Y246990D01*
X614378Y247130D01*
X614358Y247170D01*
X614343Y247205D01*
X614323Y247245D01*
X614308Y247285D01*
X614298Y247325D01*
X614283Y247370D01*
X614278Y247410D01*
X614268Y247450D01*
X614263Y247495D01*
Y247535D01*
X614258Y247580D01*
X614263Y247625D01*
Y247665D01*
X614268Y247710D01*
X614278Y247750D01*
X614283Y247790D01*
X614298Y247835D01*
X614308Y247875D01*
X614323Y247915D01*
X614343Y247955D01*
X614358Y247990D01*
X614378Y248030D01*
X614478Y248170D01*
X614508Y248200D01*
Y249330D01*
X614518Y249455D01*
X614558Y249580D01*
X614618Y249690D01*
X614698Y249790D01*
X614798Y249870D01*
X614908Y249930D01*
X615033Y249970D01*
X615158Y249980D01*
G37*
G36*
G01X619882D02*
X620007Y249970D01*
X620132Y249930D01*
X620242Y249870D01*
X620342Y249790D01*
X620422Y249690D01*
X620482Y249580D01*
X620522Y249455D01*
X620532Y249330D01*
Y248200D01*
X620562Y248170D01*
X620662Y248030D01*
X620682Y247990D01*
X620697Y247955D01*
X620717Y247915D01*
X620732Y247875D01*
X620742Y247835D01*
X620757Y247790D01*
X620762Y247750D01*
X620772Y247710D01*
X620777Y247665D01*
Y247625D01*
X620782Y247580D01*
X620777Y247535D01*
Y247495D01*
X620772Y247450D01*
X620762Y247410D01*
X620757Y247370D01*
X620742Y247325D01*
X620732Y247285D01*
X620717Y247245D01*
X620697Y247205D01*
X620682Y247170D01*
X620662Y247130D01*
X620562Y246990D01*
X620532Y246960D01*
Y243530D01*
X620522Y243405D01*
X620482Y243280D01*
X620422Y243170D01*
X620342Y243070D01*
X620242Y242990D01*
X620132Y242930D01*
X620007Y242890D01*
X619882Y242880D01*
X619757Y242890D01*
X619632Y242930D01*
X619522Y242990D01*
X619422Y243070D01*
X619342Y243170D01*
X619282Y243280D01*
X619242Y243405D01*
X619232Y243530D01*
Y246960D01*
X619202Y246990D01*
X619102Y247130D01*
X619082Y247170D01*
X619067Y247205D01*
X619047Y247245D01*
X619032Y247285D01*
X619022Y247325D01*
X619007Y247370D01*
X619002Y247410D01*
X618992Y247450D01*
X618987Y247495D01*
Y247535D01*
X618982Y247580D01*
X618987Y247625D01*
Y247665D01*
X618992Y247710D01*
X619002Y247750D01*
X619007Y247790D01*
X619022Y247835D01*
X619032Y247875D01*
X619047Y247915D01*
X619067Y247955D01*
X619082Y247990D01*
X619102Y248030D01*
X619202Y248170D01*
X619232Y248200D01*
Y249330D01*
X619242Y249455D01*
X619282Y249580D01*
X619342Y249690D01*
X619422Y249790D01*
X619522Y249870D01*
X619632Y249930D01*
X619757Y249970D01*
X619882Y249980D01*
G37*
G36*
G01X624607D02*
X624732Y249970D01*
X624857Y249930D01*
X624967Y249870D01*
X625067Y249790D01*
X625147Y249690D01*
X625207Y249580D01*
X625247Y249455D01*
X625257Y249330D01*
Y248200D01*
X625287Y248170D01*
X625387Y248030D01*
X625407Y247990D01*
X625422Y247955D01*
X625442Y247915D01*
X625457Y247875D01*
X625467Y247835D01*
X625482Y247790D01*
X625487Y247750D01*
X625497Y247710D01*
X625502Y247665D01*
Y247625D01*
X625507Y247580D01*
X625502Y247535D01*
Y247495D01*
X625497Y247450D01*
X625487Y247410D01*
X625482Y247370D01*
X625467Y247325D01*
X625457Y247285D01*
X625442Y247245D01*
X625422Y247205D01*
X625407Y247170D01*
X625387Y247130D01*
X625287Y246990D01*
X625257Y246960D01*
Y243530D01*
X625247Y243405D01*
X625207Y243280D01*
X625147Y243170D01*
X625067Y243070D01*
X624967Y242990D01*
X624857Y242930D01*
X624732Y242890D01*
X624607Y242880D01*
X624482Y242890D01*
X624357Y242930D01*
X624247Y242990D01*
X624147Y243070D01*
X624067Y243170D01*
X624007Y243280D01*
X623967Y243405D01*
X623957Y243530D01*
Y246960D01*
X623927Y246990D01*
X623827Y247130D01*
X623807Y247170D01*
X623792Y247205D01*
X623772Y247245D01*
X623757Y247285D01*
X623747Y247325D01*
X623732Y247370D01*
X623727Y247410D01*
X623717Y247450D01*
X623712Y247495D01*
Y247535D01*
X623707Y247580D01*
X623712Y247625D01*
Y247665D01*
X623717Y247710D01*
X623727Y247750D01*
X623732Y247790D01*
X623747Y247835D01*
X623757Y247875D01*
X623772Y247915D01*
X623792Y247955D01*
X623807Y247990D01*
X623827Y248030D01*
X623927Y248170D01*
X623957Y248200D01*
Y249330D01*
X623967Y249455D01*
X624007Y249580D01*
X624067Y249690D01*
X624147Y249790D01*
X624247Y249870D01*
X624357Y249930D01*
X624482Y249970D01*
X624607Y249980D01*
G37*
G36*
G01X629331D02*
X629456Y249970D01*
X629581Y249930D01*
X629691Y249870D01*
X629791Y249790D01*
X629871Y249690D01*
X629931Y249580D01*
X629971Y249455D01*
X629981Y249330D01*
Y248200D01*
X630011Y248170D01*
X630111Y248030D01*
X630131Y247990D01*
X630146Y247955D01*
X630166Y247915D01*
X630181Y247875D01*
X630191Y247835D01*
X630206Y247790D01*
X630211Y247750D01*
X630221Y247710D01*
X630226Y247665D01*
Y247625D01*
X630231Y247580D01*
X630226Y247535D01*
Y247495D01*
X630221Y247450D01*
X630211Y247410D01*
X630206Y247370D01*
X630191Y247325D01*
X630181Y247285D01*
X630166Y247245D01*
X630146Y247205D01*
X630131Y247170D01*
X630111Y247130D01*
X630011Y246990D01*
X629981Y246960D01*
Y243530D01*
X629971Y243405D01*
X629931Y243280D01*
X629871Y243170D01*
X629791Y243070D01*
X629691Y242990D01*
X629581Y242930D01*
X629456Y242890D01*
X629331Y242880D01*
X629206Y242890D01*
X629081Y242930D01*
X628971Y242990D01*
X628871Y243070D01*
X628791Y243170D01*
X628731Y243280D01*
X628691Y243405D01*
X628681Y243530D01*
Y246960D01*
X628651Y246990D01*
X628551Y247130D01*
X628531Y247170D01*
X628516Y247205D01*
X628496Y247245D01*
X628481Y247285D01*
X628471Y247325D01*
X628456Y247370D01*
X628451Y247410D01*
X628441Y247450D01*
X628436Y247495D01*
Y247535D01*
X628431Y247580D01*
X628436Y247625D01*
Y247665D01*
X628441Y247710D01*
X628451Y247750D01*
X628456Y247790D01*
X628471Y247835D01*
X628481Y247875D01*
X628496Y247915D01*
X628516Y247955D01*
X628531Y247990D01*
X628551Y248030D01*
X628651Y248170D01*
X628681Y248200D01*
Y249330D01*
X628691Y249455D01*
X628731Y249580D01*
X628791Y249690D01*
X628871Y249790D01*
X628971Y249870D01*
X629081Y249930D01*
X629206Y249970D01*
X629331Y249980D01*
G37*
G36*
G01X634055D02*
X634180Y249970D01*
X634305Y249930D01*
X634415Y249870D01*
X634515Y249790D01*
X634595Y249690D01*
X634655Y249580D01*
X634695Y249455D01*
X634705Y249330D01*
Y248200D01*
X634735Y248170D01*
X634835Y248030D01*
X634855Y247990D01*
X634870Y247955D01*
X634890Y247915D01*
X634905Y247875D01*
X634915Y247835D01*
X634930Y247790D01*
X634935Y247750D01*
X634945Y247710D01*
X634950Y247665D01*
Y247625D01*
X634955Y247580D01*
X634950Y247535D01*
Y247495D01*
X634945Y247450D01*
X634935Y247410D01*
X634930Y247370D01*
X634915Y247325D01*
X634905Y247285D01*
X634890Y247245D01*
X634870Y247205D01*
X634855Y247170D01*
X634835Y247130D01*
X634735Y246990D01*
X634705Y246960D01*
Y243530D01*
X634695Y243405D01*
X634655Y243280D01*
X634595Y243170D01*
X634515Y243070D01*
X634415Y242990D01*
X634305Y242930D01*
X634180Y242890D01*
X634055Y242880D01*
X633930Y242890D01*
X633805Y242930D01*
X633695Y242990D01*
X633595Y243070D01*
X633515Y243170D01*
X633455Y243280D01*
X633415Y243405D01*
X633405Y243530D01*
Y246960D01*
X633375Y246990D01*
X633275Y247130D01*
X633255Y247170D01*
X633240Y247205D01*
X633220Y247245D01*
X633205Y247285D01*
X633195Y247325D01*
X633180Y247370D01*
X633175Y247410D01*
X633165Y247450D01*
X633160Y247495D01*
Y247535D01*
X633155Y247580D01*
X633160Y247625D01*
Y247665D01*
X633165Y247710D01*
X633175Y247750D01*
X633180Y247790D01*
X633195Y247835D01*
X633205Y247875D01*
X633220Y247915D01*
X633240Y247955D01*
X633255Y247990D01*
X633275Y248030D01*
X633375Y248170D01*
X633405Y248200D01*
Y249330D01*
X633415Y249455D01*
X633455Y249580D01*
X633515Y249690D01*
X633595Y249790D01*
X633695Y249870D01*
X633805Y249930D01*
X633930Y249970D01*
X634055Y249980D01*
G37*
G36*
G01X638780D02*
X638905Y249970D01*
X639030Y249930D01*
X639140Y249870D01*
X639240Y249790D01*
X639320Y249690D01*
X639380Y249580D01*
X639420Y249455D01*
X639430Y249330D01*
Y248200D01*
X639460Y248170D01*
X639560Y248030D01*
X639580Y247990D01*
X639595Y247955D01*
X639615Y247915D01*
X639630Y247875D01*
X639640Y247835D01*
X639655Y247790D01*
X639660Y247750D01*
X639670Y247710D01*
X639675Y247665D01*
Y247625D01*
X639680Y247580D01*
X639675Y247535D01*
Y247495D01*
X639670Y247450D01*
X639660Y247410D01*
X639655Y247370D01*
X639640Y247325D01*
X639630Y247285D01*
X639615Y247245D01*
X639595Y247205D01*
X639580Y247170D01*
X639560Y247130D01*
X639460Y246990D01*
X639430Y246960D01*
Y243530D01*
X639420Y243405D01*
X639380Y243280D01*
X639320Y243170D01*
X639240Y243070D01*
X639140Y242990D01*
X639030Y242930D01*
X638905Y242890D01*
X638780Y242880D01*
X638655Y242890D01*
X638530Y242930D01*
X638420Y242990D01*
X638320Y243070D01*
X638240Y243170D01*
X638180Y243280D01*
X638140Y243405D01*
X638130Y243530D01*
Y246960D01*
X638100Y246990D01*
X638000Y247130D01*
X637980Y247170D01*
X637965Y247205D01*
X637945Y247245D01*
X637930Y247285D01*
X637920Y247325D01*
X637905Y247370D01*
X637900Y247410D01*
X637890Y247450D01*
X637885Y247495D01*
Y247535D01*
X637880Y247580D01*
X637885Y247625D01*
Y247665D01*
X637890Y247710D01*
X637900Y247750D01*
X637905Y247790D01*
X637920Y247835D01*
X637930Y247875D01*
X637945Y247915D01*
X637965Y247955D01*
X637980Y247990D01*
X638000Y248030D01*
X638100Y248170D01*
X638130Y248200D01*
Y249330D01*
X638140Y249455D01*
X638180Y249580D01*
X638240Y249690D01*
X638320Y249790D01*
X638420Y249870D01*
X638530Y249930D01*
X638655Y249970D01*
X638780Y249980D01*
G37*
G36*
G01X643504D02*
X643629Y249970D01*
X643754Y249930D01*
X643864Y249870D01*
X643964Y249790D01*
X644044Y249690D01*
X644104Y249580D01*
X644144Y249455D01*
X644154Y249330D01*
Y248200D01*
X644184Y248170D01*
X644284Y248030D01*
X644304Y247990D01*
X644319Y247955D01*
X644339Y247915D01*
X644354Y247875D01*
X644364Y247835D01*
X644379Y247790D01*
X644384Y247750D01*
X644394Y247710D01*
X644399Y247665D01*
Y247625D01*
X644404Y247580D01*
X644399Y247535D01*
Y247495D01*
X644394Y247450D01*
X644384Y247410D01*
X644379Y247370D01*
X644364Y247325D01*
X644354Y247285D01*
X644339Y247245D01*
X644319Y247205D01*
X644304Y247170D01*
X644284Y247130D01*
X644184Y246990D01*
X644154Y246960D01*
Y243530D01*
X644144Y243405D01*
X644104Y243280D01*
X644044Y243170D01*
X643964Y243070D01*
X643864Y242990D01*
X643754Y242930D01*
X643629Y242890D01*
X643504Y242880D01*
X643379Y242890D01*
X643254Y242930D01*
X643144Y242990D01*
X643044Y243070D01*
X642964Y243170D01*
X642904Y243280D01*
X642864Y243405D01*
X642854Y243530D01*
Y246960D01*
X642824Y246990D01*
X642724Y247130D01*
X642704Y247170D01*
X642689Y247205D01*
X642669Y247245D01*
X642654Y247285D01*
X642644Y247325D01*
X642629Y247370D01*
X642624Y247410D01*
X642614Y247450D01*
X642609Y247495D01*
Y247535D01*
X642604Y247580D01*
X642609Y247625D01*
Y247665D01*
X642614Y247710D01*
X642624Y247750D01*
X642629Y247790D01*
X642644Y247835D01*
X642654Y247875D01*
X642669Y247915D01*
X642689Y247955D01*
X642704Y247990D01*
X642724Y248030D01*
X642824Y248170D01*
X642854Y248200D01*
Y249330D01*
X642864Y249455D01*
X642904Y249580D01*
X642964Y249690D01*
X643044Y249790D01*
X643144Y249870D01*
X643254Y249930D01*
X643379Y249970D01*
X643504Y249980D01*
G37*
G36*
G01X648229D02*
X648354Y249970D01*
X648479Y249930D01*
X648589Y249870D01*
X648689Y249790D01*
X648769Y249690D01*
X648829Y249580D01*
X648869Y249455D01*
X648879Y249330D01*
Y248200D01*
X648909Y248170D01*
X649009Y248030D01*
X649029Y247990D01*
X649044Y247955D01*
X649064Y247915D01*
X649079Y247875D01*
X649089Y247835D01*
X649104Y247790D01*
X649109Y247750D01*
X649119Y247710D01*
X649124Y247665D01*
Y247625D01*
X649129Y247580D01*
X649124Y247535D01*
Y247495D01*
X649119Y247450D01*
X649109Y247410D01*
X649104Y247370D01*
X649089Y247325D01*
X649079Y247285D01*
X649064Y247245D01*
X649044Y247205D01*
X649029Y247170D01*
X649009Y247130D01*
X648909Y246990D01*
X648879Y246960D01*
Y243530D01*
X648869Y243405D01*
X648829Y243280D01*
X648769Y243170D01*
X648689Y243070D01*
X648589Y242990D01*
X648479Y242930D01*
X648354Y242890D01*
X648229Y242880D01*
X648104Y242890D01*
X647979Y242930D01*
X647869Y242990D01*
X647769Y243070D01*
X647689Y243170D01*
X647629Y243280D01*
X647589Y243405D01*
X647579Y243530D01*
Y246960D01*
X647549Y246990D01*
X647449Y247130D01*
X647429Y247170D01*
X647414Y247205D01*
X647394Y247245D01*
X647379Y247285D01*
X647369Y247325D01*
X647354Y247370D01*
X647349Y247410D01*
X647339Y247450D01*
X647334Y247495D01*
Y247535D01*
X647329Y247580D01*
X647334Y247625D01*
Y247665D01*
X647339Y247710D01*
X647349Y247750D01*
X647354Y247790D01*
X647369Y247835D01*
X647379Y247875D01*
X647394Y247915D01*
X647414Y247955D01*
X647429Y247990D01*
X647449Y248030D01*
X647549Y248170D01*
X647579Y248200D01*
Y249330D01*
X647589Y249455D01*
X647629Y249580D01*
X647689Y249690D01*
X647769Y249790D01*
X647869Y249870D01*
X647979Y249930D01*
X648104Y249970D01*
X648229Y249980D01*
G37*
G36*
G01X652953D02*
X653078Y249970D01*
X653203Y249930D01*
X653313Y249870D01*
X653413Y249790D01*
X653493Y249690D01*
X653553Y249580D01*
X653593Y249455D01*
X653603Y249330D01*
Y248200D01*
X653633Y248170D01*
X653733Y248030D01*
X653753Y247990D01*
X653768Y247955D01*
X653788Y247915D01*
X653803Y247875D01*
X653813Y247835D01*
X653828Y247790D01*
X653833Y247750D01*
X653843Y247710D01*
X653848Y247665D01*
Y247625D01*
X653853Y247580D01*
X653848Y247535D01*
Y247495D01*
X653843Y247450D01*
X653833Y247410D01*
X653828Y247370D01*
X653813Y247325D01*
X653803Y247285D01*
X653788Y247245D01*
X653768Y247205D01*
X653753Y247170D01*
X653733Y247130D01*
X653633Y246990D01*
X653603Y246960D01*
Y243530D01*
X653593Y243405D01*
X653553Y243280D01*
X653493Y243170D01*
X653413Y243070D01*
X653313Y242990D01*
X653203Y242930D01*
X653078Y242890D01*
X652953Y242880D01*
X652828Y242890D01*
X652703Y242930D01*
X652593Y242990D01*
X652493Y243070D01*
X652413Y243170D01*
X652353Y243280D01*
X652313Y243405D01*
X652303Y243530D01*
Y246960D01*
X652273Y246990D01*
X652173Y247130D01*
X652153Y247170D01*
X652138Y247205D01*
X652118Y247245D01*
X652103Y247285D01*
X652093Y247325D01*
X652078Y247370D01*
X652073Y247410D01*
X652063Y247450D01*
X652058Y247495D01*
Y247535D01*
X652053Y247580D01*
X652058Y247625D01*
Y247665D01*
X652063Y247710D01*
X652073Y247750D01*
X652078Y247790D01*
X652093Y247835D01*
X652103Y247875D01*
X652118Y247915D01*
X652138Y247955D01*
X652153Y247990D01*
X652173Y248030D01*
X652273Y248170D01*
X652303Y248200D01*
Y249330D01*
X652313Y249455D01*
X652353Y249580D01*
X652413Y249690D01*
X652493Y249790D01*
X652593Y249870D01*
X652703Y249930D01*
X652828Y249970D01*
X652953Y249980D01*
G37*
G36*
G01X667126D02*
X667251Y249970D01*
X667376Y249930D01*
X667486Y249870D01*
X667586Y249790D01*
X667666Y249690D01*
X667726Y249580D01*
X667766Y249455D01*
X667776Y249330D01*
Y248200D01*
X667806Y248170D01*
X667906Y248030D01*
X667926Y247990D01*
X667941Y247955D01*
X667961Y247915D01*
X667976Y247875D01*
X667986Y247835D01*
X668001Y247790D01*
X668006Y247750D01*
X668016Y247710D01*
X668021Y247665D01*
Y247625D01*
X668026Y247580D01*
X668021Y247535D01*
Y247495D01*
X668016Y247450D01*
X668006Y247410D01*
X668001Y247370D01*
X667986Y247325D01*
X667976Y247285D01*
X667961Y247245D01*
X667941Y247205D01*
X667926Y247170D01*
X667906Y247130D01*
X667806Y246990D01*
X667776Y246960D01*
Y243530D01*
X667766Y243405D01*
X667726Y243280D01*
X667666Y243170D01*
X667586Y243070D01*
X667486Y242990D01*
X667376Y242930D01*
X667251Y242890D01*
X667126Y242880D01*
X667001Y242890D01*
X666876Y242930D01*
X666766Y242990D01*
X666666Y243070D01*
X666586Y243170D01*
X666526Y243280D01*
X666486Y243405D01*
X666476Y243530D01*
Y246960D01*
X666446Y246990D01*
X666346Y247130D01*
X666326Y247170D01*
X666311Y247205D01*
X666291Y247245D01*
X666276Y247285D01*
X666266Y247325D01*
X666251Y247370D01*
X666246Y247410D01*
X666236Y247450D01*
X666231Y247495D01*
Y247535D01*
X666226Y247580D01*
X666231Y247625D01*
Y247665D01*
X666236Y247710D01*
X666246Y247750D01*
X666251Y247790D01*
X666266Y247835D01*
X666276Y247875D01*
X666291Y247915D01*
X666311Y247955D01*
X666326Y247990D01*
X666346Y248030D01*
X666446Y248170D01*
X666476Y248200D01*
Y249330D01*
X666486Y249455D01*
X666526Y249580D01*
X666586Y249690D01*
X666666Y249790D01*
X666766Y249870D01*
X666876Y249930D01*
X667001Y249970D01*
X667126Y249980D01*
G37*
G36*
G01X671851D02*
X671976Y249970D01*
X672101Y249930D01*
X672211Y249870D01*
X672311Y249790D01*
X672391Y249690D01*
X672451Y249580D01*
X672491Y249455D01*
X672501Y249330D01*
Y248200D01*
X672531Y248170D01*
X672631Y248030D01*
X672651Y247990D01*
X672666Y247955D01*
X672686Y247915D01*
X672701Y247875D01*
X672711Y247835D01*
X672726Y247790D01*
X672731Y247750D01*
X672741Y247710D01*
X672746Y247665D01*
Y247625D01*
X672751Y247580D01*
X672746Y247535D01*
Y247495D01*
X672741Y247450D01*
X672731Y247410D01*
X672726Y247370D01*
X672711Y247325D01*
X672701Y247285D01*
X672686Y247245D01*
X672666Y247205D01*
X672651Y247170D01*
X672631Y247130D01*
X672531Y246990D01*
X672501Y246960D01*
Y243530D01*
X672491Y243405D01*
X672451Y243280D01*
X672391Y243170D01*
X672311Y243070D01*
X672211Y242990D01*
X672101Y242930D01*
X671976Y242890D01*
X671851Y242880D01*
X671726Y242890D01*
X671601Y242930D01*
X671491Y242990D01*
X671391Y243070D01*
X671311Y243170D01*
X671251Y243280D01*
X671211Y243405D01*
X671201Y243530D01*
Y246960D01*
X671171Y246990D01*
X671071Y247130D01*
X671051Y247170D01*
X671036Y247205D01*
X671016Y247245D01*
X671001Y247285D01*
X670991Y247325D01*
X670976Y247370D01*
X670971Y247410D01*
X670961Y247450D01*
X670956Y247495D01*
Y247535D01*
X670951Y247580D01*
X670956Y247625D01*
Y247665D01*
X670961Y247710D01*
X670971Y247750D01*
X670976Y247790D01*
X670991Y247835D01*
X671001Y247875D01*
X671016Y247915D01*
X671036Y247955D01*
X671051Y247990D01*
X671071Y248030D01*
X671171Y248170D01*
X671201Y248200D01*
Y249330D01*
X671211Y249455D01*
X671251Y249580D01*
X671311Y249690D01*
X671391Y249790D01*
X671491Y249870D01*
X671601Y249930D01*
X671726Y249970D01*
X671851Y249980D01*
G37*
G36*
G01X676575D02*
X676700Y249970D01*
X676825Y249930D01*
X676935Y249870D01*
X677035Y249790D01*
X677115Y249690D01*
X677175Y249580D01*
X677215Y249455D01*
X677225Y249330D01*
Y248200D01*
X677255Y248170D01*
X677355Y248030D01*
X677375Y247990D01*
X677390Y247955D01*
X677410Y247915D01*
X677425Y247875D01*
X677435Y247835D01*
X677450Y247790D01*
X677455Y247750D01*
X677465Y247710D01*
X677470Y247665D01*
Y247625D01*
X677475Y247580D01*
X677470Y247535D01*
Y247495D01*
X677465Y247450D01*
X677455Y247410D01*
X677450Y247370D01*
X677435Y247325D01*
X677425Y247285D01*
X677410Y247245D01*
X677390Y247205D01*
X677375Y247170D01*
X677355Y247130D01*
X677255Y246990D01*
X677225Y246960D01*
Y243530D01*
X677215Y243405D01*
X677175Y243280D01*
X677115Y243170D01*
X677035Y243070D01*
X676935Y242990D01*
X676825Y242930D01*
X676700Y242890D01*
X676575Y242880D01*
X676450Y242890D01*
X676325Y242930D01*
X676215Y242990D01*
X676115Y243070D01*
X676035Y243170D01*
X675975Y243280D01*
X675935Y243405D01*
X675925Y243530D01*
Y246960D01*
X675895Y246990D01*
X675795Y247130D01*
X675775Y247170D01*
X675760Y247205D01*
X675740Y247245D01*
X675725Y247285D01*
X675715Y247325D01*
X675700Y247370D01*
X675695Y247410D01*
X675685Y247450D01*
X675680Y247495D01*
Y247535D01*
X675675Y247580D01*
X675680Y247625D01*
Y247665D01*
X675685Y247710D01*
X675695Y247750D01*
X675700Y247790D01*
X675715Y247835D01*
X675725Y247875D01*
X675740Y247915D01*
X675760Y247955D01*
X675775Y247990D01*
X675795Y248030D01*
X675895Y248170D01*
X675925Y248200D01*
Y249330D01*
X675935Y249455D01*
X675975Y249580D01*
X676035Y249690D01*
X676115Y249790D01*
X676215Y249870D01*
X676325Y249930D01*
X676450Y249970D01*
X676575Y249980D01*
G37*
G36*
G01X681299D02*
X681424Y249970D01*
X681549Y249930D01*
X681659Y249870D01*
X681759Y249790D01*
X681839Y249690D01*
X681899Y249580D01*
X681939Y249455D01*
X681949Y249330D01*
Y248200D01*
X681979Y248170D01*
X682079Y248030D01*
X682099Y247990D01*
X682114Y247955D01*
X682134Y247915D01*
X682149Y247875D01*
X682159Y247835D01*
X682174Y247790D01*
X682179Y247750D01*
X682189Y247710D01*
X682194Y247665D01*
Y247625D01*
X682199Y247580D01*
X682194Y247535D01*
Y247495D01*
X682189Y247450D01*
X682179Y247410D01*
X682174Y247370D01*
X682159Y247325D01*
X682149Y247285D01*
X682134Y247245D01*
X682114Y247205D01*
X682099Y247170D01*
X682079Y247130D01*
X681979Y246990D01*
X681949Y246960D01*
Y243530D01*
X681939Y243405D01*
X681899Y243280D01*
X681839Y243170D01*
X681759Y243070D01*
X681659Y242990D01*
X681549Y242930D01*
X681424Y242890D01*
X681299Y242880D01*
X681174Y242890D01*
X681049Y242930D01*
X680939Y242990D01*
X680839Y243070D01*
X680759Y243170D01*
X680699Y243280D01*
X680659Y243405D01*
X680649Y243530D01*
Y246960D01*
X680619Y246990D01*
X680519Y247130D01*
X680499Y247170D01*
X680484Y247205D01*
X680464Y247245D01*
X680449Y247285D01*
X680439Y247325D01*
X680424Y247370D01*
X680419Y247410D01*
X680409Y247450D01*
X680404Y247495D01*
Y247535D01*
X680399Y247580D01*
X680404Y247625D01*
Y247665D01*
X680409Y247710D01*
X680419Y247750D01*
X680424Y247790D01*
X680439Y247835D01*
X680449Y247875D01*
X680464Y247915D01*
X680484Y247955D01*
X680499Y247990D01*
X680519Y248030D01*
X680619Y248170D01*
X680649Y248200D01*
Y249330D01*
X680659Y249455D01*
X680699Y249580D01*
X680759Y249690D01*
X680839Y249790D01*
X680939Y249870D01*
X681049Y249930D01*
X681174Y249970D01*
X681299Y249980D01*
G37*
G36*
G01X686024D02*
X686149Y249970D01*
X686274Y249930D01*
X686384Y249870D01*
X686484Y249790D01*
X686564Y249690D01*
X686624Y249580D01*
X686664Y249455D01*
X686674Y249330D01*
Y248200D01*
X686704Y248170D01*
X686804Y248030D01*
X686824Y247990D01*
X686839Y247955D01*
X686859Y247915D01*
X686874Y247875D01*
X686884Y247835D01*
X686899Y247790D01*
X686904Y247750D01*
X686914Y247710D01*
X686919Y247665D01*
Y247625D01*
X686924Y247580D01*
X686919Y247535D01*
Y247495D01*
X686914Y247450D01*
X686904Y247410D01*
X686899Y247370D01*
X686884Y247325D01*
X686874Y247285D01*
X686859Y247245D01*
X686839Y247205D01*
X686824Y247170D01*
X686804Y247130D01*
X686704Y246990D01*
X686674Y246960D01*
Y243530D01*
X686664Y243405D01*
X686624Y243280D01*
X686564Y243170D01*
X686484Y243070D01*
X686384Y242990D01*
X686274Y242930D01*
X686149Y242890D01*
X686024Y242880D01*
X685899Y242890D01*
X685774Y242930D01*
X685664Y242990D01*
X685564Y243070D01*
X685484Y243170D01*
X685424Y243280D01*
X685384Y243405D01*
X685374Y243530D01*
Y246960D01*
X685344Y246990D01*
X685244Y247130D01*
X685224Y247170D01*
X685209Y247205D01*
X685189Y247245D01*
X685174Y247285D01*
X685164Y247325D01*
X685149Y247370D01*
X685144Y247410D01*
X685134Y247450D01*
X685129Y247495D01*
Y247535D01*
X685124Y247580D01*
X685129Y247625D01*
Y247665D01*
X685134Y247710D01*
X685144Y247750D01*
X685149Y247790D01*
X685164Y247835D01*
X685174Y247875D01*
X685189Y247915D01*
X685209Y247955D01*
X685224Y247990D01*
X685244Y248030D01*
X685344Y248170D01*
X685374Y248200D01*
Y249330D01*
X685384Y249455D01*
X685424Y249580D01*
X685484Y249690D01*
X685564Y249790D01*
X685664Y249870D01*
X685774Y249930D01*
X685899Y249970D01*
X686024Y249980D01*
G37*
G36*
G01X690748D02*
X690873Y249970D01*
X690998Y249930D01*
X691108Y249870D01*
X691208Y249790D01*
X691288Y249690D01*
X691348Y249580D01*
X691388Y249455D01*
X691398Y249330D01*
Y248200D01*
X691428Y248170D01*
X691528Y248030D01*
X691548Y247990D01*
X691563Y247955D01*
X691583Y247915D01*
X691598Y247875D01*
X691608Y247835D01*
X691623Y247790D01*
X691628Y247750D01*
X691638Y247710D01*
X691643Y247665D01*
Y247625D01*
X691648Y247580D01*
X691643Y247535D01*
Y247495D01*
X691638Y247450D01*
X691628Y247410D01*
X691623Y247370D01*
X691608Y247325D01*
X691598Y247285D01*
X691583Y247245D01*
X691563Y247205D01*
X691548Y247170D01*
X691528Y247130D01*
X691428Y246990D01*
X691398Y246960D01*
Y243530D01*
X691388Y243405D01*
X691348Y243280D01*
X691288Y243170D01*
X691208Y243070D01*
X691108Y242990D01*
X690998Y242930D01*
X690873Y242890D01*
X690748Y242880D01*
X690623Y242890D01*
X690498Y242930D01*
X690388Y242990D01*
X690288Y243070D01*
X690208Y243170D01*
X690148Y243280D01*
X690108Y243405D01*
X690098Y243530D01*
Y246960D01*
X690068Y246990D01*
X689968Y247130D01*
X689948Y247170D01*
X689933Y247205D01*
X689913Y247245D01*
X689898Y247285D01*
X689888Y247325D01*
X689873Y247370D01*
X689868Y247410D01*
X689858Y247450D01*
X689853Y247495D01*
Y247535D01*
X689848Y247580D01*
X689853Y247625D01*
Y247665D01*
X689858Y247710D01*
X689868Y247750D01*
X689873Y247790D01*
X689888Y247835D01*
X689898Y247875D01*
X689913Y247915D01*
X689933Y247955D01*
X689948Y247990D01*
X689968Y248030D01*
X690068Y248170D01*
X690098Y248200D01*
Y249330D01*
X690108Y249455D01*
X690148Y249580D01*
X690208Y249690D01*
X690288Y249790D01*
X690388Y249870D01*
X690498Y249930D01*
X690623Y249970D01*
X690748Y249980D01*
G37*
G36*
G01X695473D02*
X695598Y249970D01*
X695723Y249930D01*
X695833Y249870D01*
X695933Y249790D01*
X696013Y249690D01*
X696073Y249580D01*
X696113Y249455D01*
X696123Y249330D01*
Y248200D01*
X696153Y248170D01*
X696253Y248030D01*
X696273Y247990D01*
X696288Y247955D01*
X696308Y247915D01*
X696323Y247875D01*
X696333Y247835D01*
X696348Y247790D01*
X696353Y247750D01*
X696363Y247710D01*
X696368Y247665D01*
Y247625D01*
X696373Y247580D01*
X696368Y247535D01*
Y247495D01*
X696363Y247450D01*
X696353Y247410D01*
X696348Y247370D01*
X696333Y247325D01*
X696323Y247285D01*
X696308Y247245D01*
X696288Y247205D01*
X696273Y247170D01*
X696253Y247130D01*
X696153Y246990D01*
X696123Y246960D01*
Y243530D01*
X696113Y243405D01*
X696073Y243280D01*
X696013Y243170D01*
X695933Y243070D01*
X695833Y242990D01*
X695723Y242930D01*
X695598Y242890D01*
X695473Y242880D01*
X695348Y242890D01*
X695223Y242930D01*
X695113Y242990D01*
X695013Y243070D01*
X694933Y243170D01*
X694873Y243280D01*
X694833Y243405D01*
X694823Y243530D01*
Y246960D01*
X694793Y246990D01*
X694693Y247130D01*
X694673Y247170D01*
X694658Y247205D01*
X694638Y247245D01*
X694623Y247285D01*
X694613Y247325D01*
X694598Y247370D01*
X694593Y247410D01*
X694583Y247450D01*
X694578Y247495D01*
Y247535D01*
X694573Y247580D01*
X694578Y247625D01*
Y247665D01*
X694583Y247710D01*
X694593Y247750D01*
X694598Y247790D01*
X694613Y247835D01*
X694623Y247875D01*
X694638Y247915D01*
X694658Y247955D01*
X694673Y247990D01*
X694693Y248030D01*
X694793Y248170D01*
X694823Y248200D01*
Y249330D01*
X694833Y249455D01*
X694873Y249580D01*
X694933Y249690D01*
X695013Y249790D01*
X695113Y249870D01*
X695223Y249930D01*
X695348Y249970D01*
X695473Y249980D01*
G37*
G36*
G01X700197D02*
X700322Y249970D01*
X700447Y249930D01*
X700557Y249870D01*
X700657Y249790D01*
X700737Y249690D01*
X700797Y249580D01*
X700837Y249455D01*
X700847Y249330D01*
Y248200D01*
X700877Y248170D01*
X700977Y248030D01*
X700997Y247990D01*
X701012Y247955D01*
X701032Y247915D01*
X701047Y247875D01*
X701057Y247835D01*
X701072Y247790D01*
X701077Y247750D01*
X701087Y247710D01*
X701092Y247665D01*
Y247625D01*
X701097Y247580D01*
X701092Y247535D01*
Y247495D01*
X701087Y247450D01*
X701077Y247410D01*
X701072Y247370D01*
X701057Y247325D01*
X701047Y247285D01*
X701032Y247245D01*
X701012Y247205D01*
X700997Y247170D01*
X700977Y247130D01*
X700877Y246990D01*
X700847Y246960D01*
Y243530D01*
X700837Y243405D01*
X700797Y243280D01*
X700737Y243170D01*
X700657Y243070D01*
X700557Y242990D01*
X700447Y242930D01*
X700322Y242890D01*
X700197Y242880D01*
X700072Y242890D01*
X699947Y242930D01*
X699837Y242990D01*
X699737Y243070D01*
X699657Y243170D01*
X699597Y243280D01*
X699557Y243405D01*
X699547Y243530D01*
Y246960D01*
X699517Y246990D01*
X699417Y247130D01*
X699397Y247170D01*
X699382Y247205D01*
X699362Y247245D01*
X699347Y247285D01*
X699337Y247325D01*
X699322Y247370D01*
X699317Y247410D01*
X699307Y247450D01*
X699302Y247495D01*
Y247535D01*
X699297Y247580D01*
X699302Y247625D01*
Y247665D01*
X699307Y247710D01*
X699317Y247750D01*
X699322Y247790D01*
X699337Y247835D01*
X699347Y247875D01*
X699362Y247915D01*
X699382Y247955D01*
X699397Y247990D01*
X699417Y248030D01*
X699517Y248170D01*
X699547Y248200D01*
Y249330D01*
X699557Y249455D01*
X699597Y249580D01*
X699657Y249690D01*
X699737Y249790D01*
X699837Y249870D01*
X699947Y249930D01*
X700072Y249970D01*
X700197Y249980D01*
G37*
G36*
G01X704922D02*
X705047Y249970D01*
X705172Y249930D01*
X705282Y249870D01*
X705382Y249790D01*
X705462Y249690D01*
X705522Y249580D01*
X705562Y249455D01*
X705572Y249330D01*
Y248200D01*
X705602Y248170D01*
X705702Y248030D01*
X705722Y247990D01*
X705737Y247955D01*
X705757Y247915D01*
X705772Y247875D01*
X705782Y247835D01*
X705797Y247790D01*
X705802Y247750D01*
X705812Y247710D01*
X705817Y247665D01*
Y247625D01*
X705822Y247580D01*
X705817Y247535D01*
Y247495D01*
X705812Y247450D01*
X705802Y247410D01*
X705797Y247370D01*
X705782Y247325D01*
X705772Y247285D01*
X705757Y247245D01*
X705737Y247205D01*
X705722Y247170D01*
X705702Y247130D01*
X705602Y246990D01*
X705572Y246960D01*
Y243530D01*
X705562Y243405D01*
X705522Y243280D01*
X705462Y243170D01*
X705382Y243070D01*
X705282Y242990D01*
X705172Y242930D01*
X705047Y242890D01*
X704922Y242880D01*
X704797Y242890D01*
X704672Y242930D01*
X704562Y242990D01*
X704462Y243070D01*
X704382Y243170D01*
X704322Y243280D01*
X704282Y243405D01*
X704272Y243530D01*
Y246960D01*
X704242Y246990D01*
X704142Y247130D01*
X704122Y247170D01*
X704107Y247205D01*
X704087Y247245D01*
X704072Y247285D01*
X704062Y247325D01*
X704047Y247370D01*
X704042Y247410D01*
X704032Y247450D01*
X704027Y247495D01*
Y247535D01*
X704022Y247580D01*
X704027Y247625D01*
Y247665D01*
X704032Y247710D01*
X704042Y247750D01*
X704047Y247790D01*
X704062Y247835D01*
X704072Y247875D01*
X704087Y247915D01*
X704107Y247955D01*
X704122Y247990D01*
X704142Y248030D01*
X704242Y248170D01*
X704272Y248200D01*
Y249330D01*
X704282Y249455D01*
X704322Y249580D01*
X704382Y249690D01*
X704462Y249790D01*
X704562Y249870D01*
X704672Y249930D01*
X704797Y249970D01*
X704922Y249980D01*
G37*
G36*
G01X709646D02*
X709771Y249970D01*
X709896Y249930D01*
X710006Y249870D01*
X710106Y249790D01*
X710186Y249690D01*
X710246Y249580D01*
X710286Y249455D01*
X710296Y249330D01*
Y248200D01*
X710326Y248170D01*
X710426Y248030D01*
X710446Y247990D01*
X710461Y247955D01*
X710481Y247915D01*
X710496Y247875D01*
X710506Y247835D01*
X710521Y247790D01*
X710526Y247750D01*
X710536Y247710D01*
X710541Y247665D01*
Y247625D01*
X710546Y247580D01*
X710541Y247535D01*
Y247495D01*
X710536Y247450D01*
X710526Y247410D01*
X710521Y247370D01*
X710506Y247325D01*
X710496Y247285D01*
X710481Y247245D01*
X710461Y247205D01*
X710446Y247170D01*
X710426Y247130D01*
X710326Y246990D01*
X710296Y246960D01*
Y243530D01*
X710286Y243405D01*
X710246Y243280D01*
X710186Y243170D01*
X710106Y243070D01*
X710006Y242990D01*
X709896Y242930D01*
X709771Y242890D01*
X709646Y242880D01*
X709521Y242890D01*
X709396Y242930D01*
X709286Y242990D01*
X709186Y243070D01*
X709106Y243170D01*
X709046Y243280D01*
X709006Y243405D01*
X708996Y243530D01*
Y246960D01*
X708966Y246990D01*
X708866Y247130D01*
X708846Y247170D01*
X708831Y247205D01*
X708811Y247245D01*
X708796Y247285D01*
X708786Y247325D01*
X708771Y247370D01*
X708766Y247410D01*
X708756Y247450D01*
X708751Y247495D01*
Y247535D01*
X708746Y247580D01*
X708751Y247625D01*
Y247665D01*
X708756Y247710D01*
X708766Y247750D01*
X708771Y247790D01*
X708786Y247835D01*
X708796Y247875D01*
X708811Y247915D01*
X708831Y247955D01*
X708846Y247990D01*
X708866Y248030D01*
X708966Y248170D01*
X708996Y248200D01*
Y249330D01*
X709006Y249455D01*
X709046Y249580D01*
X709106Y249690D01*
X709186Y249790D01*
X709286Y249870D01*
X709396Y249930D01*
X709521Y249970D01*
X709646Y249980D01*
G37*
G36*
G01X714370D02*
X714495Y249970D01*
X714620Y249930D01*
X714730Y249870D01*
X714830Y249790D01*
X714910Y249690D01*
X714970Y249580D01*
X715010Y249455D01*
X715020Y249330D01*
Y248200D01*
X715050Y248170D01*
X715150Y248030D01*
X715170Y247990D01*
X715185Y247955D01*
X715205Y247915D01*
X715220Y247875D01*
X715230Y247835D01*
X715245Y247790D01*
X715250Y247750D01*
X715260Y247710D01*
X715265Y247665D01*
Y247625D01*
X715270Y247580D01*
X715265Y247535D01*
Y247495D01*
X715260Y247450D01*
X715250Y247410D01*
X715245Y247370D01*
X715230Y247325D01*
X715220Y247285D01*
X715205Y247245D01*
X715185Y247205D01*
X715170Y247170D01*
X715150Y247130D01*
X715050Y246990D01*
X715020Y246960D01*
Y243530D01*
X715010Y243405D01*
X714970Y243280D01*
X714910Y243170D01*
X714830Y243070D01*
X714730Y242990D01*
X714620Y242930D01*
X714495Y242890D01*
X714370Y242880D01*
X714245Y242890D01*
X714120Y242930D01*
X714010Y242990D01*
X713910Y243070D01*
X713830Y243170D01*
X713770Y243280D01*
X713730Y243405D01*
X713720Y243530D01*
Y246960D01*
X713690Y246990D01*
X713590Y247130D01*
X713570Y247170D01*
X713555Y247205D01*
X713535Y247245D01*
X713520Y247285D01*
X713510Y247325D01*
X713495Y247370D01*
X713490Y247410D01*
X713480Y247450D01*
X713475Y247495D01*
Y247535D01*
X713470Y247580D01*
X713475Y247625D01*
Y247665D01*
X713480Y247710D01*
X713490Y247750D01*
X713495Y247790D01*
X713510Y247835D01*
X713520Y247875D01*
X713535Y247915D01*
X713555Y247955D01*
X713570Y247990D01*
X713590Y248030D01*
X713690Y248170D01*
X713720Y248200D01*
Y249330D01*
X713730Y249455D01*
X713770Y249580D01*
X713830Y249690D01*
X713910Y249790D01*
X714010Y249870D01*
X714120Y249930D01*
X714245Y249970D01*
X714370Y249980D01*
G37*
G36*
G01X719095D02*
X719220Y249970D01*
X719345Y249930D01*
X719455Y249870D01*
X719555Y249790D01*
X719635Y249690D01*
X719695Y249580D01*
X719735Y249455D01*
X719745Y249330D01*
Y248200D01*
X719775Y248170D01*
X719875Y248030D01*
X719895Y247990D01*
X719910Y247955D01*
X719930Y247915D01*
X719945Y247875D01*
X719955Y247835D01*
X719970Y247790D01*
X719975Y247750D01*
X719985Y247710D01*
X719990Y247665D01*
Y247625D01*
X719995Y247580D01*
X719990Y247535D01*
Y247495D01*
X719985Y247450D01*
X719975Y247410D01*
X719970Y247370D01*
X719955Y247325D01*
X719945Y247285D01*
X719930Y247245D01*
X719910Y247205D01*
X719895Y247170D01*
X719875Y247130D01*
X719775Y246990D01*
X719745Y246960D01*
Y243530D01*
X719735Y243405D01*
X719695Y243280D01*
X719635Y243170D01*
X719555Y243070D01*
X719455Y242990D01*
X719345Y242930D01*
X719220Y242890D01*
X719095Y242880D01*
X718970Y242890D01*
X718845Y242930D01*
X718735Y242990D01*
X718635Y243070D01*
X718555Y243170D01*
X718495Y243280D01*
X718455Y243405D01*
X718445Y243530D01*
Y246960D01*
X718415Y246990D01*
X718315Y247130D01*
X718295Y247170D01*
X718280Y247205D01*
X718260Y247245D01*
X718245Y247285D01*
X718235Y247325D01*
X718220Y247370D01*
X718215Y247410D01*
X718205Y247450D01*
X718200Y247495D01*
Y247535D01*
X718195Y247580D01*
X718200Y247625D01*
Y247665D01*
X718205Y247710D01*
X718215Y247750D01*
X718220Y247790D01*
X718235Y247835D01*
X718245Y247875D01*
X718260Y247915D01*
X718280Y247955D01*
X718295Y247990D01*
X718315Y248030D01*
X718415Y248170D01*
X718445Y248200D01*
Y249330D01*
X718455Y249455D01*
X718495Y249580D01*
X718555Y249690D01*
X718635Y249790D01*
X718735Y249870D01*
X718845Y249930D01*
X718970Y249970D01*
X719095Y249980D01*
G37*
G36*
G01X723819D02*
X723944Y249970D01*
X724069Y249930D01*
X724179Y249870D01*
X724279Y249790D01*
X724359Y249690D01*
X724419Y249580D01*
X724459Y249455D01*
X724469Y249330D01*
Y248200D01*
X724499Y248170D01*
X724599Y248030D01*
X724619Y247990D01*
X724634Y247955D01*
X724654Y247915D01*
X724669Y247875D01*
X724679Y247835D01*
X724694Y247790D01*
X724699Y247750D01*
X724709Y247710D01*
X724714Y247665D01*
Y247625D01*
X724719Y247580D01*
X724714Y247535D01*
Y247495D01*
X724709Y247450D01*
X724699Y247410D01*
X724694Y247370D01*
X724679Y247325D01*
X724669Y247285D01*
X724654Y247245D01*
X724634Y247205D01*
X724619Y247170D01*
X724599Y247130D01*
X724499Y246990D01*
X724469Y246960D01*
Y243530D01*
X724459Y243405D01*
X724419Y243280D01*
X724359Y243170D01*
X724279Y243070D01*
X724179Y242990D01*
X724069Y242930D01*
X723944Y242890D01*
X723819Y242880D01*
X723694Y242890D01*
X723569Y242930D01*
X723459Y242990D01*
X723359Y243070D01*
X723279Y243170D01*
X723219Y243280D01*
X723179Y243405D01*
X723169Y243530D01*
Y246960D01*
X723139Y246990D01*
X723039Y247130D01*
X723019Y247170D01*
X723004Y247205D01*
X722984Y247245D01*
X722969Y247285D01*
X722959Y247325D01*
X722944Y247370D01*
X722939Y247410D01*
X722929Y247450D01*
X722924Y247495D01*
Y247535D01*
X722919Y247580D01*
X722924Y247625D01*
Y247665D01*
X722929Y247710D01*
X722939Y247750D01*
X722944Y247790D01*
X722959Y247835D01*
X722969Y247875D01*
X722984Y247915D01*
X723004Y247955D01*
X723019Y247990D01*
X723039Y248030D01*
X723139Y248170D01*
X723169Y248200D01*
Y249330D01*
X723179Y249455D01*
X723219Y249580D01*
X723279Y249690D01*
X723359Y249790D01*
X723459Y249870D01*
X723569Y249930D01*
X723694Y249970D01*
X723819Y249980D01*
G37*
G36*
G01X728544D02*
X728669Y249970D01*
X728794Y249930D01*
X728904Y249870D01*
X729004Y249790D01*
X729084Y249690D01*
X729144Y249580D01*
X729184Y249455D01*
X729194Y249330D01*
Y248200D01*
X729224Y248170D01*
X729324Y248030D01*
X729344Y247990D01*
X729359Y247955D01*
X729379Y247915D01*
X729394Y247875D01*
X729404Y247835D01*
X729419Y247790D01*
X729424Y247750D01*
X729434Y247710D01*
X729439Y247665D01*
Y247625D01*
X729444Y247580D01*
X729439Y247535D01*
Y247495D01*
X729434Y247450D01*
X729424Y247410D01*
X729419Y247370D01*
X729404Y247325D01*
X729394Y247285D01*
X729379Y247245D01*
X729359Y247205D01*
X729344Y247170D01*
X729324Y247130D01*
X729224Y246990D01*
X729194Y246960D01*
Y243530D01*
X729184Y243405D01*
X729144Y243280D01*
X729084Y243170D01*
X729004Y243070D01*
X728904Y242990D01*
X728794Y242930D01*
X728669Y242890D01*
X728544Y242880D01*
X728419Y242890D01*
X728294Y242930D01*
X728184Y242990D01*
X728084Y243070D01*
X728004Y243170D01*
X727944Y243280D01*
X727904Y243405D01*
X727894Y243530D01*
Y246960D01*
X727864Y246990D01*
X727764Y247130D01*
X727744Y247170D01*
X727729Y247205D01*
X727709Y247245D01*
X727694Y247285D01*
X727684Y247325D01*
X727669Y247370D01*
X727664Y247410D01*
X727654Y247450D01*
X727649Y247495D01*
Y247535D01*
X727644Y247580D01*
X727649Y247625D01*
Y247665D01*
X727654Y247710D01*
X727664Y247750D01*
X727669Y247790D01*
X727684Y247835D01*
X727694Y247875D01*
X727709Y247915D01*
X727729Y247955D01*
X727744Y247990D01*
X727764Y248030D01*
X727864Y248170D01*
X727894Y248200D01*
Y249330D01*
X727904Y249455D01*
X727944Y249580D01*
X728004Y249690D01*
X728084Y249790D01*
X728184Y249870D01*
X728294Y249930D01*
X728419Y249970D01*
X728544Y249980D01*
G37*
G36*
G01X733268D02*
X733393Y249970D01*
X733518Y249930D01*
X733628Y249870D01*
X733728Y249790D01*
X733808Y249690D01*
X733868Y249580D01*
X733908Y249455D01*
X733918Y249330D01*
Y248200D01*
X733948Y248170D01*
X734048Y248030D01*
X734068Y247990D01*
X734083Y247955D01*
X734103Y247915D01*
X734118Y247875D01*
X734128Y247835D01*
X734143Y247790D01*
X734148Y247750D01*
X734158Y247710D01*
X734163Y247665D01*
Y247625D01*
X734168Y247580D01*
X734163Y247535D01*
Y247495D01*
X734158Y247450D01*
X734148Y247410D01*
X734143Y247370D01*
X734128Y247325D01*
X734118Y247285D01*
X734103Y247245D01*
X734083Y247205D01*
X734068Y247170D01*
X734048Y247130D01*
X733948Y246990D01*
X733918Y246960D01*
Y243530D01*
X733908Y243405D01*
X733868Y243280D01*
X733808Y243170D01*
X733728Y243070D01*
X733628Y242990D01*
X733518Y242930D01*
X733393Y242890D01*
X733268Y242880D01*
X733143Y242890D01*
X733018Y242930D01*
X732908Y242990D01*
X732808Y243070D01*
X732728Y243170D01*
X732668Y243280D01*
X732628Y243405D01*
X732618Y243530D01*
Y246960D01*
X732588Y246990D01*
X732488Y247130D01*
X732468Y247170D01*
X732453Y247205D01*
X732433Y247245D01*
X732418Y247285D01*
X732408Y247325D01*
X732393Y247370D01*
X732388Y247410D01*
X732378Y247450D01*
X732373Y247495D01*
Y247535D01*
X732368Y247580D01*
X732373Y247625D01*
Y247665D01*
X732378Y247710D01*
X732388Y247750D01*
X732393Y247790D01*
X732408Y247835D01*
X732418Y247875D01*
X732433Y247915D01*
X732453Y247955D01*
X732468Y247990D01*
X732488Y248030D01*
X732588Y248170D01*
X732618Y248200D01*
Y249330D01*
X732628Y249455D01*
X732668Y249580D01*
X732728Y249690D01*
X732808Y249790D01*
X732908Y249870D01*
X733018Y249930D01*
X733143Y249970D01*
X733268Y249980D01*
G37*
G36*
G01X737992D02*
X738117Y249970D01*
X738242Y249930D01*
X738352Y249870D01*
X738452Y249790D01*
X738532Y249690D01*
X738592Y249580D01*
X738632Y249455D01*
X738642Y249330D01*
Y248200D01*
X738672Y248170D01*
X738772Y248030D01*
X738792Y247990D01*
X738807Y247955D01*
X738827Y247915D01*
X738842Y247875D01*
X738852Y247835D01*
X738867Y247790D01*
X738872Y247750D01*
X738882Y247710D01*
X738887Y247665D01*
Y247625D01*
X738892Y247580D01*
X738887Y247535D01*
Y247495D01*
X738882Y247450D01*
X738872Y247410D01*
X738867Y247370D01*
X738852Y247325D01*
X738842Y247285D01*
X738827Y247245D01*
X738807Y247205D01*
X738792Y247170D01*
X738772Y247130D01*
X738672Y246990D01*
X738642Y246960D01*
Y243530D01*
X738632Y243405D01*
X738592Y243280D01*
X738532Y243170D01*
X738452Y243070D01*
X738352Y242990D01*
X738242Y242930D01*
X738117Y242890D01*
X737992Y242880D01*
X737867Y242890D01*
X737742Y242930D01*
X737632Y242990D01*
X737532Y243070D01*
X737452Y243170D01*
X737392Y243280D01*
X737352Y243405D01*
X737342Y243530D01*
Y246960D01*
X737312Y246990D01*
X737212Y247130D01*
X737192Y247170D01*
X737177Y247205D01*
X737157Y247245D01*
X737142Y247285D01*
X737132Y247325D01*
X737117Y247370D01*
X737112Y247410D01*
X737102Y247450D01*
X737097Y247495D01*
Y247535D01*
X737092Y247580D01*
X737097Y247625D01*
Y247665D01*
X737102Y247710D01*
X737112Y247750D01*
X737117Y247790D01*
X737132Y247835D01*
X737142Y247875D01*
X737157Y247915D01*
X737177Y247955D01*
X737192Y247990D01*
X737212Y248030D01*
X737312Y248170D01*
X737342Y248200D01*
Y249330D01*
X737352Y249455D01*
X737392Y249580D01*
X737452Y249690D01*
X737532Y249790D01*
X737632Y249870D01*
X737742Y249930D01*
X737867Y249970D01*
X737992Y249980D01*
G37*
G36*
G01X742717D02*
X742842Y249970D01*
X742967Y249930D01*
X743077Y249870D01*
X743177Y249790D01*
X743257Y249690D01*
X743317Y249580D01*
X743357Y249455D01*
X743367Y249330D01*
Y248200D01*
X743397Y248170D01*
X743497Y248030D01*
X743517Y247990D01*
X743532Y247955D01*
X743552Y247915D01*
X743567Y247875D01*
X743577Y247835D01*
X743592Y247790D01*
X743597Y247750D01*
X743607Y247710D01*
X743612Y247665D01*
Y247625D01*
X743617Y247580D01*
X743612Y247535D01*
Y247495D01*
X743607Y247450D01*
X743597Y247410D01*
X743592Y247370D01*
X743577Y247325D01*
X743567Y247285D01*
X743552Y247245D01*
X743532Y247205D01*
X743517Y247170D01*
X743497Y247130D01*
X743397Y246990D01*
X743367Y246960D01*
Y243530D01*
X743357Y243405D01*
X743317Y243280D01*
X743257Y243170D01*
X743177Y243070D01*
X743077Y242990D01*
X742967Y242930D01*
X742842Y242890D01*
X742717Y242880D01*
X742592Y242890D01*
X742467Y242930D01*
X742357Y242990D01*
X742257Y243070D01*
X742177Y243170D01*
X742117Y243280D01*
X742077Y243405D01*
X742067Y243530D01*
Y246960D01*
X742037Y246990D01*
X741937Y247130D01*
X741917Y247170D01*
X741902Y247205D01*
X741882Y247245D01*
X741867Y247285D01*
X741857Y247325D01*
X741842Y247370D01*
X741837Y247410D01*
X741827Y247450D01*
X741822Y247495D01*
Y247535D01*
X741817Y247580D01*
X741822Y247625D01*
Y247665D01*
X741827Y247710D01*
X741837Y247750D01*
X741842Y247790D01*
X741857Y247835D01*
X741867Y247875D01*
X741882Y247915D01*
X741902Y247955D01*
X741917Y247990D01*
X741937Y248030D01*
X742037Y248170D01*
X742067Y248200D01*
Y249330D01*
X742077Y249455D01*
X742117Y249580D01*
X742177Y249690D01*
X742257Y249790D01*
X742357Y249870D01*
X742467Y249930D01*
X742592Y249970D01*
X742717Y249980D01*
G37*
G36*
G01X747441D02*
X747566Y249970D01*
X747691Y249930D01*
X747801Y249870D01*
X747901Y249790D01*
X747981Y249690D01*
X748041Y249580D01*
X748081Y249455D01*
X748091Y249330D01*
Y248200D01*
X748121Y248170D01*
X748221Y248030D01*
X748241Y247990D01*
X748256Y247955D01*
X748276Y247915D01*
X748291Y247875D01*
X748301Y247835D01*
X748316Y247790D01*
X748321Y247750D01*
X748331Y247710D01*
X748336Y247665D01*
Y247625D01*
X748341Y247580D01*
X748336Y247535D01*
Y247495D01*
X748331Y247450D01*
X748321Y247410D01*
X748316Y247370D01*
X748301Y247325D01*
X748291Y247285D01*
X748276Y247245D01*
X748256Y247205D01*
X748241Y247170D01*
X748221Y247130D01*
X748121Y246990D01*
X748091Y246960D01*
Y243530D01*
X748081Y243405D01*
X748041Y243280D01*
X747981Y243170D01*
X747901Y243070D01*
X747801Y242990D01*
X747691Y242930D01*
X747566Y242890D01*
X747441Y242880D01*
X747316Y242890D01*
X747191Y242930D01*
X747081Y242990D01*
X746981Y243070D01*
X746901Y243170D01*
X746841Y243280D01*
X746801Y243405D01*
X746791Y243530D01*
Y246960D01*
X746761Y246990D01*
X746661Y247130D01*
X746641Y247170D01*
X746626Y247205D01*
X746606Y247245D01*
X746591Y247285D01*
X746581Y247325D01*
X746566Y247370D01*
X746561Y247410D01*
X746551Y247450D01*
X746546Y247495D01*
Y247535D01*
X746541Y247580D01*
X746546Y247625D01*
Y247665D01*
X746551Y247710D01*
X746561Y247750D01*
X746566Y247790D01*
X746581Y247835D01*
X746591Y247875D01*
X746606Y247915D01*
X746626Y247955D01*
X746641Y247990D01*
X746661Y248030D01*
X746761Y248170D01*
X746791Y248200D01*
Y249330D01*
X746801Y249455D01*
X746841Y249580D01*
X746901Y249690D01*
X746981Y249790D01*
X747081Y249870D01*
X747191Y249930D01*
X747316Y249970D01*
X747441Y249980D01*
G37*
G54D89*
G01X171000Y196600D02*
Y193600D01*
G01D02*
Y189240D01*
X170760Y189000D01*
G01X177200Y130575D02*
Y129824D01*
X178800Y128224D01*
Y127700D01*
G01X187000Y209500D02*
Y207950D01*
X188400Y206550D01*
G01X197600Y88800D02*
X198300Y89500D01*
X202200D01*
G01X190651Y210150D02*
Y208801D01*
X188400Y206550D01*
G01X303500Y195400D02*
X299400Y199500D01*
X291500D01*
X290000Y198000D01*
Y195700D01*
G01D02*
X287700D01*
X286300Y194300D01*
Y191885D01*
G01X415200Y81500D02*
Y84700D01*
X414300Y85600D01*
G01X443400Y148900D02*
X444050Y148250D01*
X444160D01*
X452410Y140000D01*
X457863D01*
G01X465500Y140363D02*
X465137Y140000D01*
X457863D01*
X353742Y135431D03*
Y148031D03*
Y151181D03*
Y138581D03*
Y141731D03*
Y144881D03*
Y166931D03*
Y160631D03*
Y157481D03*
Y154331D03*
Y163781D03*
Y170081D03*
Y173231D03*
X369482Y135431D03*
X369882Y132671D03*
X356882Y135431D03*
X360042D03*
X366342D03*
X363182D03*
X356882Y132671D03*
X366342D03*
X369482Y148031D03*
Y151181D03*
Y138581D03*
Y144881D03*
Y141731D03*
X356882Y148031D03*
Y151181D03*
X360042Y148031D03*
X366342D03*
X363182D03*
X360042Y151181D03*
X366342D03*
X363182D03*
X356882Y138581D03*
X360042D03*
X366342D03*
X363182D03*
X356882Y144881D03*
Y141731D03*
X360042Y144881D03*
Y141731D03*
X366342Y144881D03*
Y141731D03*
X363182Y144881D03*
Y141731D03*
X369482Y166931D03*
Y154331D03*
Y157481D03*
Y160631D03*
Y163781D03*
X356882Y166931D03*
X360042D03*
X366342D03*
X363182D03*
X356882Y154331D03*
Y157481D03*
Y160631D03*
X360042Y154331D03*
Y157481D03*
Y160631D03*
X366342Y154331D03*
Y157481D03*
Y160631D03*
X363182Y154331D03*
Y157481D03*
Y160631D03*
X356882Y163781D03*
X360042D03*
X366342D03*
X363182D03*
X369482Y170081D03*
Y173231D03*
X369092Y175991D03*
X356882Y170081D03*
X360042D03*
X366342D03*
X363182D03*
X356882Y173231D03*
X360042D03*
X366342D03*
X363182D03*
X356882Y175991D03*
X366342D03*
X372642Y135431D03*
X375782D03*
X378942D03*
X382082D03*
Y132671D03*
X372642D03*
X385242Y135431D03*
X385632Y132671D03*
X372642Y148031D03*
X375782D03*
X372642Y151181D03*
X375782D03*
X378942Y148031D03*
Y151181D03*
X382082Y148031D03*
Y151181D03*
X385242Y148031D03*
Y151181D03*
X372642Y138581D03*
X375782D03*
X378942D03*
X372642Y144881D03*
Y141731D03*
X375782D03*
Y144881D03*
X378942Y141731D03*
Y144881D03*
X382082Y138581D03*
Y144881D03*
Y141731D03*
X385242Y138581D03*
Y144881D03*
Y141731D03*
X372642Y166931D03*
X375782D03*
X378942D03*
X382082D03*
X385242D03*
X372642Y154331D03*
Y157481D03*
Y160631D03*
X375782D03*
Y157481D03*
Y154331D03*
X378942Y160631D03*
Y157481D03*
Y154331D03*
X382082D03*
Y157481D03*
Y160631D03*
X372642Y163781D03*
X375782D03*
X378942D03*
X382082D03*
X385242Y154331D03*
Y157481D03*
Y160631D03*
Y163781D03*
X372642Y170081D03*
X375782D03*
X378942D03*
X372642Y173231D03*
X375782D03*
X378942D03*
X382082Y170081D03*
Y173231D03*
X372642Y175991D03*
X382082D03*
X385242Y170081D03*
Y173231D03*
X384842Y175991D03*
X394682Y135431D03*
X391542D03*
X388382D03*
X397842D03*
Y132671D03*
X388382D03*
X400982Y135431D03*
X394682Y148031D03*
X391542D03*
X388382D03*
X394682Y151181D03*
X391542D03*
X388382D03*
X397842Y148031D03*
Y151181D03*
X400982Y148031D03*
Y151181D03*
X394682Y138581D03*
X391542D03*
X388382D03*
X397842D03*
X394682Y144881D03*
Y141731D03*
X391542Y144881D03*
Y141731D03*
X388382Y144881D03*
Y141731D03*
X397842Y144881D03*
Y141731D03*
X400982Y138581D03*
Y144881D03*
Y141731D03*
X394682Y166931D03*
X391542D03*
X388382D03*
X397842D03*
X400982D03*
X394682Y154331D03*
Y157481D03*
Y160631D03*
X391542Y154331D03*
Y157481D03*
Y160631D03*
X388382Y154331D03*
Y157481D03*
Y160631D03*
X397842Y154331D03*
Y157481D03*
Y160631D03*
X394682Y163781D03*
X391542D03*
X388382D03*
X397842D03*
X400982Y154331D03*
Y157481D03*
Y160631D03*
Y163781D03*
X394682Y170081D03*
X391542D03*
X388382D03*
X397842D03*
X388382Y173231D03*
X394682D03*
X391542D03*
X397842D03*
X388382Y175991D03*
X397842D03*
X400982Y170081D03*
Y173231D03*
G36*
G01X500591Y282316D02*
X500716Y282306D01*
X500841Y282266D01*
X500951Y282206D01*
X501051Y282126D01*
X501131Y282026D01*
X501191Y281916D01*
X501231Y281791D01*
X501241Y281666D01*
Y279236D01*
X501271Y279206D01*
X501371Y279066D01*
X501391Y279026D01*
X501406Y278991D01*
X501426Y278951D01*
X501441Y278911D01*
X501451Y278871D01*
X501466Y278826D01*
X501471Y278786D01*
X501481Y278746D01*
X501486Y278701D01*
Y278661D01*
X501491Y278616D01*
X501486Y278571D01*
Y278531D01*
X501481Y278486D01*
X501471Y278446D01*
X501466Y278406D01*
X501451Y278361D01*
X501441Y278321D01*
X501426Y278281D01*
X501406Y278241D01*
X501391Y278206D01*
X501371Y278166D01*
X501271Y278026D01*
X501241Y277996D01*
Y275866D01*
X501231Y275741D01*
X501191Y275616D01*
X501131Y275506D01*
X501051Y275406D01*
X500951Y275326D01*
X500841Y275266D01*
X500716Y275226D01*
X500591Y275216D01*
X500466Y275226D01*
X500341Y275266D01*
X500231Y275326D01*
X500131Y275406D01*
X500051Y275506D01*
X499991Y275616D01*
X499951Y275741D01*
X499941Y275866D01*
Y277991D01*
X499911Y278021D01*
X499886Y278056D01*
X499856Y278091D01*
X499836Y278126D01*
X499811Y278161D01*
X499771Y278241D01*
X499726Y278361D01*
X499716Y278401D01*
X499706Y278446D01*
X499701Y278486D01*
X499691Y278531D01*
Y278701D01*
X499701Y278746D01*
X499706Y278786D01*
X499716Y278831D01*
X499726Y278871D01*
X499771Y278991D01*
X499811Y279071D01*
X499836Y279106D01*
X499856Y279141D01*
X499886Y279176D01*
X499911Y279211D01*
X499941Y279241D01*
Y281666D01*
X499951Y281791D01*
X499991Y281916D01*
X500051Y282026D01*
X500131Y282126D01*
X500231Y282206D01*
X500341Y282266D01*
X500466Y282306D01*
X500591Y282316D01*
G37*
G36*
G01X505315D02*
X505440Y282306D01*
X505565Y282266D01*
X505675Y282206D01*
X505775Y282126D01*
X505855Y282026D01*
X505915Y281916D01*
X505955Y281791D01*
X505965Y281666D01*
Y279236D01*
X505995Y279206D01*
X506095Y279066D01*
X506115Y279026D01*
X506130Y278991D01*
X506150Y278951D01*
X506165Y278911D01*
X506175Y278871D01*
X506190Y278826D01*
X506195Y278786D01*
X506205Y278746D01*
X506210Y278701D01*
Y278661D01*
X506215Y278616D01*
X506210Y278571D01*
Y278531D01*
X506205Y278486D01*
X506195Y278446D01*
X506190Y278406D01*
X506175Y278361D01*
X506165Y278321D01*
X506150Y278281D01*
X506130Y278241D01*
X506115Y278206D01*
X506095Y278166D01*
X505995Y278026D01*
X505965Y277996D01*
Y275866D01*
X505955Y275741D01*
X505915Y275616D01*
X505855Y275506D01*
X505775Y275406D01*
X505675Y275326D01*
X505565Y275266D01*
X505440Y275226D01*
X505315Y275216D01*
X505190Y275226D01*
X505065Y275266D01*
X504955Y275326D01*
X504855Y275406D01*
X504775Y275506D01*
X504715Y275616D01*
X504675Y275741D01*
X504665Y275866D01*
Y277991D01*
X504635Y278021D01*
X504610Y278056D01*
X504580Y278091D01*
X504560Y278126D01*
X504535Y278161D01*
X504495Y278241D01*
X504450Y278361D01*
X504440Y278401D01*
X504430Y278446D01*
X504425Y278486D01*
X504415Y278531D01*
Y278701D01*
X504425Y278746D01*
X504430Y278786D01*
X504440Y278831D01*
X504450Y278871D01*
X504495Y278991D01*
X504535Y279071D01*
X504560Y279106D01*
X504580Y279141D01*
X504610Y279176D01*
X504635Y279211D01*
X504665Y279241D01*
Y281666D01*
X504675Y281791D01*
X504715Y281916D01*
X504775Y282026D01*
X504855Y282126D01*
X504955Y282206D01*
X505065Y282266D01*
X505190Y282306D01*
X505315Y282316D01*
G37*
G36*
G01X510040D02*
X510165Y282306D01*
X510290Y282266D01*
X510400Y282206D01*
X510500Y282126D01*
X510580Y282026D01*
X510640Y281916D01*
X510680Y281791D01*
X510690Y281666D01*
Y279236D01*
X510720Y279206D01*
X510820Y279066D01*
X510840Y279026D01*
X510855Y278991D01*
X510875Y278951D01*
X510890Y278911D01*
X510900Y278871D01*
X510915Y278826D01*
X510920Y278786D01*
X510930Y278746D01*
X510935Y278701D01*
Y278661D01*
X510940Y278616D01*
X510935Y278571D01*
Y278531D01*
X510930Y278486D01*
X510920Y278446D01*
X510915Y278406D01*
X510900Y278361D01*
X510890Y278321D01*
X510875Y278281D01*
X510855Y278241D01*
X510840Y278206D01*
X510820Y278166D01*
X510720Y278026D01*
X510690Y277996D01*
Y275866D01*
X510680Y275741D01*
X510640Y275616D01*
X510580Y275506D01*
X510500Y275406D01*
X510400Y275326D01*
X510290Y275266D01*
X510165Y275226D01*
X510040Y275216D01*
X509915Y275226D01*
X509790Y275266D01*
X509680Y275326D01*
X509580Y275406D01*
X509500Y275506D01*
X509440Y275616D01*
X509400Y275741D01*
X509390Y275866D01*
Y277991D01*
X509360Y278021D01*
X509335Y278056D01*
X509305Y278091D01*
X509285Y278126D01*
X509260Y278161D01*
X509220Y278241D01*
X509175Y278361D01*
X509165Y278401D01*
X509155Y278446D01*
X509150Y278486D01*
X509140Y278531D01*
Y278701D01*
X509150Y278746D01*
X509155Y278786D01*
X509165Y278831D01*
X509175Y278871D01*
X509220Y278991D01*
X509260Y279071D01*
X509285Y279106D01*
X509305Y279141D01*
X509335Y279176D01*
X509360Y279211D01*
X509390Y279241D01*
Y281666D01*
X509400Y281791D01*
X509440Y281916D01*
X509500Y282026D01*
X509580Y282126D01*
X509680Y282206D01*
X509790Y282266D01*
X509915Y282306D01*
X510040Y282316D01*
G37*
G36*
G01X514764D02*
X514889Y282306D01*
X515014Y282266D01*
X515124Y282206D01*
X515224Y282126D01*
X515304Y282026D01*
X515364Y281916D01*
X515404Y281791D01*
X515414Y281666D01*
Y279236D01*
X515444Y279206D01*
X515544Y279066D01*
X515564Y279026D01*
X515579Y278991D01*
X515599Y278951D01*
X515614Y278911D01*
X515624Y278871D01*
X515639Y278826D01*
X515644Y278786D01*
X515654Y278746D01*
X515659Y278701D01*
Y278661D01*
X515664Y278616D01*
X515659Y278571D01*
Y278531D01*
X515654Y278486D01*
X515644Y278446D01*
X515639Y278406D01*
X515624Y278361D01*
X515614Y278321D01*
X515599Y278281D01*
X515579Y278241D01*
X515564Y278206D01*
X515544Y278166D01*
X515444Y278026D01*
X515414Y277996D01*
Y275866D01*
X515404Y275741D01*
X515364Y275616D01*
X515304Y275506D01*
X515224Y275406D01*
X515124Y275326D01*
X515014Y275266D01*
X514889Y275226D01*
X514764Y275216D01*
X514639Y275226D01*
X514514Y275266D01*
X514404Y275326D01*
X514304Y275406D01*
X514224Y275506D01*
X514164Y275616D01*
X514124Y275741D01*
X514114Y275866D01*
Y277991D01*
X514084Y278021D01*
X514059Y278056D01*
X514029Y278091D01*
X514009Y278126D01*
X513984Y278161D01*
X513944Y278241D01*
X513899Y278361D01*
X513889Y278401D01*
X513879Y278446D01*
X513874Y278486D01*
X513864Y278531D01*
Y278701D01*
X513874Y278746D01*
X513879Y278786D01*
X513889Y278831D01*
X513899Y278871D01*
X513944Y278991D01*
X513984Y279071D01*
X514009Y279106D01*
X514029Y279141D01*
X514059Y279176D01*
X514084Y279211D01*
X514114Y279241D01*
Y281666D01*
X514124Y281791D01*
X514164Y281916D01*
X514224Y282026D01*
X514304Y282126D01*
X514404Y282206D01*
X514514Y282266D01*
X514639Y282306D01*
X514764Y282316D01*
G37*
G36*
G01X519488D02*
X519613Y282306D01*
X519738Y282266D01*
X519848Y282206D01*
X519948Y282126D01*
X520028Y282026D01*
X520088Y281916D01*
X520128Y281791D01*
X520138Y281666D01*
Y279236D01*
X520168Y279206D01*
X520268Y279066D01*
X520288Y279026D01*
X520303Y278991D01*
X520323Y278951D01*
X520338Y278911D01*
X520348Y278871D01*
X520363Y278826D01*
X520368Y278786D01*
X520378Y278746D01*
X520383Y278701D01*
Y278661D01*
X520388Y278616D01*
X520383Y278571D01*
Y278531D01*
X520378Y278486D01*
X520368Y278446D01*
X520363Y278406D01*
X520348Y278361D01*
X520338Y278321D01*
X520323Y278281D01*
X520303Y278241D01*
X520288Y278206D01*
X520268Y278166D01*
X520168Y278026D01*
X520138Y277996D01*
Y275866D01*
X520128Y275741D01*
X520088Y275616D01*
X520028Y275506D01*
X519948Y275406D01*
X519848Y275326D01*
X519738Y275266D01*
X519613Y275226D01*
X519488Y275216D01*
X519363Y275226D01*
X519238Y275266D01*
X519128Y275326D01*
X519028Y275406D01*
X518948Y275506D01*
X518888Y275616D01*
X518848Y275741D01*
X518838Y275866D01*
Y277991D01*
X518808Y278021D01*
X518783Y278056D01*
X518753Y278091D01*
X518733Y278126D01*
X518708Y278161D01*
X518668Y278241D01*
X518623Y278361D01*
X518613Y278401D01*
X518603Y278446D01*
X518598Y278486D01*
X518588Y278531D01*
Y278701D01*
X518598Y278746D01*
X518603Y278786D01*
X518613Y278831D01*
X518623Y278871D01*
X518668Y278991D01*
X518708Y279071D01*
X518733Y279106D01*
X518753Y279141D01*
X518783Y279176D01*
X518808Y279211D01*
X518838Y279241D01*
Y281666D01*
X518848Y281791D01*
X518888Y281916D01*
X518948Y282026D01*
X519028Y282126D01*
X519128Y282206D01*
X519238Y282266D01*
X519363Y282306D01*
X519488Y282316D01*
G37*
G36*
G01X524213D02*
X524338Y282306D01*
X524463Y282266D01*
X524573Y282206D01*
X524673Y282126D01*
X524753Y282026D01*
X524813Y281916D01*
X524853Y281791D01*
X524863Y281666D01*
Y279236D01*
X524893Y279206D01*
X524993Y279066D01*
X525013Y279026D01*
X525028Y278991D01*
X525048Y278951D01*
X525063Y278911D01*
X525073Y278871D01*
X525088Y278826D01*
X525093Y278786D01*
X525103Y278746D01*
X525108Y278701D01*
Y278661D01*
X525113Y278616D01*
X525108Y278571D01*
Y278531D01*
X525103Y278486D01*
X525093Y278446D01*
X525088Y278406D01*
X525073Y278361D01*
X525063Y278321D01*
X525048Y278281D01*
X525028Y278241D01*
X525013Y278206D01*
X524993Y278166D01*
X524893Y278026D01*
X524863Y277996D01*
Y275866D01*
X524853Y275741D01*
X524813Y275616D01*
X524753Y275506D01*
X524673Y275406D01*
X524573Y275326D01*
X524463Y275266D01*
X524338Y275226D01*
X524213Y275216D01*
X524088Y275226D01*
X523963Y275266D01*
X523853Y275326D01*
X523753Y275406D01*
X523673Y275506D01*
X523613Y275616D01*
X523573Y275741D01*
X523563Y275866D01*
Y277991D01*
X523533Y278021D01*
X523508Y278056D01*
X523478Y278091D01*
X523458Y278126D01*
X523433Y278161D01*
X523393Y278241D01*
X523348Y278361D01*
X523338Y278401D01*
X523328Y278446D01*
X523323Y278486D01*
X523313Y278531D01*
Y278701D01*
X523323Y278746D01*
X523328Y278786D01*
X523338Y278831D01*
X523348Y278871D01*
X523393Y278991D01*
X523433Y279071D01*
X523458Y279106D01*
X523478Y279141D01*
X523508Y279176D01*
X523533Y279211D01*
X523563Y279241D01*
Y281666D01*
X523573Y281791D01*
X523613Y281916D01*
X523673Y282026D01*
X523753Y282126D01*
X523853Y282206D01*
X523963Y282266D01*
X524088Y282306D01*
X524213Y282316D01*
G37*
G36*
G01X528937D02*
X529062Y282306D01*
X529187Y282266D01*
X529297Y282206D01*
X529397Y282126D01*
X529477Y282026D01*
X529537Y281916D01*
X529577Y281791D01*
X529587Y281666D01*
Y279236D01*
X529617Y279206D01*
X529717Y279066D01*
X529737Y279026D01*
X529752Y278991D01*
X529772Y278951D01*
X529787Y278911D01*
X529797Y278871D01*
X529812Y278826D01*
X529817Y278786D01*
X529827Y278746D01*
X529832Y278701D01*
Y278661D01*
X529837Y278616D01*
X529832Y278571D01*
Y278531D01*
X529827Y278486D01*
X529817Y278446D01*
X529812Y278406D01*
X529797Y278361D01*
X529787Y278321D01*
X529772Y278281D01*
X529752Y278241D01*
X529737Y278206D01*
X529717Y278166D01*
X529617Y278026D01*
X529587Y277996D01*
Y275866D01*
X529577Y275741D01*
X529537Y275616D01*
X529477Y275506D01*
X529397Y275406D01*
X529297Y275326D01*
X529187Y275266D01*
X529062Y275226D01*
X528937Y275216D01*
X528812Y275226D01*
X528687Y275266D01*
X528577Y275326D01*
X528477Y275406D01*
X528397Y275506D01*
X528337Y275616D01*
X528297Y275741D01*
X528287Y275866D01*
Y277991D01*
X528257Y278021D01*
X528232Y278056D01*
X528202Y278091D01*
X528182Y278126D01*
X528157Y278161D01*
X528117Y278241D01*
X528072Y278361D01*
X528062Y278401D01*
X528052Y278446D01*
X528047Y278486D01*
X528037Y278531D01*
Y278701D01*
X528047Y278746D01*
X528052Y278786D01*
X528062Y278831D01*
X528072Y278871D01*
X528117Y278991D01*
X528157Y279071D01*
X528182Y279106D01*
X528202Y279141D01*
X528232Y279176D01*
X528257Y279211D01*
X528287Y279241D01*
Y281666D01*
X528297Y281791D01*
X528337Y281916D01*
X528397Y282026D01*
X528477Y282126D01*
X528577Y282206D01*
X528687Y282266D01*
X528812Y282306D01*
X528937Y282316D01*
G37*
G36*
G01X533662D02*
X533787Y282306D01*
X533912Y282266D01*
X534022Y282206D01*
X534122Y282126D01*
X534202Y282026D01*
X534262Y281916D01*
X534302Y281791D01*
X534312Y281666D01*
Y279236D01*
X534342Y279206D01*
X534442Y279066D01*
X534462Y279026D01*
X534477Y278991D01*
X534497Y278951D01*
X534512Y278911D01*
X534522Y278871D01*
X534537Y278826D01*
X534542Y278786D01*
X534552Y278746D01*
X534557Y278701D01*
Y278661D01*
X534562Y278616D01*
X534557Y278571D01*
Y278531D01*
X534552Y278486D01*
X534542Y278446D01*
X534537Y278406D01*
X534522Y278361D01*
X534512Y278321D01*
X534497Y278281D01*
X534477Y278241D01*
X534462Y278206D01*
X534442Y278166D01*
X534342Y278026D01*
X534312Y277996D01*
Y275866D01*
X534302Y275741D01*
X534262Y275616D01*
X534202Y275506D01*
X534122Y275406D01*
X534022Y275326D01*
X533912Y275266D01*
X533787Y275226D01*
X533662Y275216D01*
X533537Y275226D01*
X533412Y275266D01*
X533302Y275326D01*
X533202Y275406D01*
X533122Y275506D01*
X533062Y275616D01*
X533022Y275741D01*
X533012Y275866D01*
Y277991D01*
X532982Y278021D01*
X532957Y278056D01*
X532927Y278091D01*
X532907Y278126D01*
X532882Y278161D01*
X532842Y278241D01*
X532797Y278361D01*
X532787Y278401D01*
X532777Y278446D01*
X532772Y278486D01*
X532762Y278531D01*
Y278701D01*
X532772Y278746D01*
X532777Y278786D01*
X532787Y278831D01*
X532797Y278871D01*
X532842Y278991D01*
X532882Y279071D01*
X532907Y279106D01*
X532927Y279141D01*
X532957Y279176D01*
X532982Y279211D01*
X533012Y279241D01*
Y281666D01*
X533022Y281791D01*
X533062Y281916D01*
X533122Y282026D01*
X533202Y282126D01*
X533302Y282206D01*
X533412Y282266D01*
X533537Y282306D01*
X533662Y282316D01*
G37*
G36*
G01X538386D02*
X538511Y282306D01*
X538636Y282266D01*
X538746Y282206D01*
X538846Y282126D01*
X538926Y282026D01*
X538986Y281916D01*
X539026Y281791D01*
X539036Y281666D01*
Y279236D01*
X539066Y279206D01*
X539166Y279066D01*
X539186Y279026D01*
X539201Y278991D01*
X539221Y278951D01*
X539236Y278911D01*
X539246Y278871D01*
X539261Y278826D01*
X539266Y278786D01*
X539276Y278746D01*
X539281Y278701D01*
Y278661D01*
X539286Y278616D01*
X539281Y278571D01*
Y278531D01*
X539276Y278486D01*
X539266Y278446D01*
X539261Y278406D01*
X539246Y278361D01*
X539236Y278321D01*
X539221Y278281D01*
X539201Y278241D01*
X539186Y278206D01*
X539166Y278166D01*
X539066Y278026D01*
X539036Y277996D01*
Y275866D01*
X539026Y275741D01*
X538986Y275616D01*
X538926Y275506D01*
X538846Y275406D01*
X538746Y275326D01*
X538636Y275266D01*
X538511Y275226D01*
X538386Y275216D01*
X538261Y275226D01*
X538136Y275266D01*
X538026Y275326D01*
X537926Y275406D01*
X537846Y275506D01*
X537786Y275616D01*
X537746Y275741D01*
X537736Y275866D01*
Y277991D01*
X537706Y278021D01*
X537681Y278056D01*
X537651Y278091D01*
X537631Y278126D01*
X537606Y278161D01*
X537566Y278241D01*
X537521Y278361D01*
X537511Y278401D01*
X537501Y278446D01*
X537496Y278486D01*
X537486Y278531D01*
Y278701D01*
X537496Y278746D01*
X537501Y278786D01*
X537511Y278831D01*
X537521Y278871D01*
X537566Y278991D01*
X537606Y279071D01*
X537631Y279106D01*
X537651Y279141D01*
X537681Y279176D01*
X537706Y279211D01*
X537736Y279241D01*
Y281666D01*
X537746Y281791D01*
X537786Y281916D01*
X537846Y282026D01*
X537926Y282126D01*
X538026Y282206D01*
X538136Y282266D01*
X538261Y282306D01*
X538386Y282316D01*
G37*
G36*
G01X543110D02*
X543235Y282306D01*
X543360Y282266D01*
X543470Y282206D01*
X543570Y282126D01*
X543650Y282026D01*
X543710Y281916D01*
X543750Y281791D01*
X543760Y281666D01*
Y279236D01*
X543790Y279206D01*
X543890Y279066D01*
X543910Y279026D01*
X543925Y278991D01*
X543945Y278951D01*
X543960Y278911D01*
X543970Y278871D01*
X543985Y278826D01*
X543990Y278786D01*
X544000Y278746D01*
X544005Y278701D01*
Y278661D01*
X544010Y278616D01*
X544005Y278571D01*
Y278531D01*
X544000Y278486D01*
X543990Y278446D01*
X543985Y278406D01*
X543970Y278361D01*
X543960Y278321D01*
X543945Y278281D01*
X543925Y278241D01*
X543910Y278206D01*
X543890Y278166D01*
X543790Y278026D01*
X543760Y277996D01*
Y275866D01*
X543750Y275741D01*
X543710Y275616D01*
X543650Y275506D01*
X543570Y275406D01*
X543470Y275326D01*
X543360Y275266D01*
X543235Y275226D01*
X543110Y275216D01*
X542985Y275226D01*
X542860Y275266D01*
X542750Y275326D01*
X542650Y275406D01*
X542570Y275506D01*
X542510Y275616D01*
X542470Y275741D01*
X542460Y275866D01*
Y277991D01*
X542430Y278021D01*
X542405Y278056D01*
X542375Y278091D01*
X542355Y278126D01*
X542330Y278161D01*
X542290Y278241D01*
X542245Y278361D01*
X542235Y278401D01*
X542225Y278446D01*
X542220Y278486D01*
X542210Y278531D01*
Y278701D01*
X542220Y278746D01*
X542225Y278786D01*
X542235Y278831D01*
X542245Y278871D01*
X542290Y278991D01*
X542330Y279071D01*
X542355Y279106D01*
X542375Y279141D01*
X542405Y279176D01*
X542430Y279211D01*
X542460Y279241D01*
Y281666D01*
X542470Y281791D01*
X542510Y281916D01*
X542570Y282026D01*
X542650Y282126D01*
X542750Y282206D01*
X542860Y282266D01*
X542985Y282306D01*
X543110Y282316D01*
G37*
G36*
G01X547835D02*
X547960Y282306D01*
X548085Y282266D01*
X548195Y282206D01*
X548295Y282126D01*
X548375Y282026D01*
X548435Y281916D01*
X548475Y281791D01*
X548485Y281666D01*
Y279236D01*
X548515Y279206D01*
X548615Y279066D01*
X548635Y279026D01*
X548650Y278991D01*
X548670Y278951D01*
X548685Y278911D01*
X548695Y278871D01*
X548710Y278826D01*
X548715Y278786D01*
X548725Y278746D01*
X548730Y278701D01*
Y278661D01*
X548735Y278616D01*
X548730Y278571D01*
Y278531D01*
X548725Y278486D01*
X548715Y278446D01*
X548710Y278406D01*
X548695Y278361D01*
X548685Y278321D01*
X548670Y278281D01*
X548650Y278241D01*
X548635Y278206D01*
X548615Y278166D01*
X548515Y278026D01*
X548485Y277996D01*
Y275866D01*
X548475Y275741D01*
X548435Y275616D01*
X548375Y275506D01*
X548295Y275406D01*
X548195Y275326D01*
X548085Y275266D01*
X547960Y275226D01*
X547835Y275216D01*
X547710Y275226D01*
X547585Y275266D01*
X547475Y275326D01*
X547375Y275406D01*
X547295Y275506D01*
X547235Y275616D01*
X547195Y275741D01*
X547185Y275866D01*
Y277991D01*
X547155Y278021D01*
X547130Y278056D01*
X547100Y278091D01*
X547080Y278126D01*
X547055Y278161D01*
X547015Y278241D01*
X546970Y278361D01*
X546960Y278401D01*
X546950Y278446D01*
X546945Y278486D01*
X546935Y278531D01*
Y278701D01*
X546945Y278746D01*
X546950Y278786D01*
X546960Y278831D01*
X546970Y278871D01*
X547015Y278991D01*
X547055Y279071D01*
X547080Y279106D01*
X547100Y279141D01*
X547130Y279176D01*
X547155Y279211D01*
X547185Y279241D01*
Y281666D01*
X547195Y281791D01*
X547235Y281916D01*
X547295Y282026D01*
X547375Y282126D01*
X547475Y282206D01*
X547585Y282266D01*
X547710Y282306D01*
X547835Y282316D01*
G37*
G36*
G01X552559D02*
X552684Y282306D01*
X552809Y282266D01*
X552919Y282206D01*
X553019Y282126D01*
X553099Y282026D01*
X553159Y281916D01*
X553199Y281791D01*
X553209Y281666D01*
Y279236D01*
X553239Y279206D01*
X553339Y279066D01*
X553359Y279026D01*
X553374Y278991D01*
X553394Y278951D01*
X553409Y278911D01*
X553419Y278871D01*
X553434Y278826D01*
X553439Y278786D01*
X553449Y278746D01*
X553454Y278701D01*
Y278661D01*
X553459Y278616D01*
X553454Y278571D01*
Y278531D01*
X553449Y278486D01*
X553439Y278446D01*
X553434Y278406D01*
X553419Y278361D01*
X553409Y278321D01*
X553394Y278281D01*
X553374Y278241D01*
X553359Y278206D01*
X553339Y278166D01*
X553239Y278026D01*
X553209Y277996D01*
Y275866D01*
X553199Y275741D01*
X553159Y275616D01*
X553099Y275506D01*
X553019Y275406D01*
X552919Y275326D01*
X552809Y275266D01*
X552684Y275226D01*
X552559Y275216D01*
X552434Y275226D01*
X552309Y275266D01*
X552199Y275326D01*
X552099Y275406D01*
X552019Y275506D01*
X551959Y275616D01*
X551919Y275741D01*
X551909Y275866D01*
Y277991D01*
X551879Y278021D01*
X551854Y278056D01*
X551824Y278091D01*
X551804Y278126D01*
X551779Y278161D01*
X551739Y278241D01*
X551694Y278361D01*
X551684Y278401D01*
X551674Y278446D01*
X551669Y278486D01*
X551659Y278531D01*
Y278701D01*
X551669Y278746D01*
X551674Y278786D01*
X551684Y278831D01*
X551694Y278871D01*
X551739Y278991D01*
X551779Y279071D01*
X551804Y279106D01*
X551824Y279141D01*
X551854Y279176D01*
X551879Y279211D01*
X551909Y279241D01*
Y281666D01*
X551919Y281791D01*
X551959Y281916D01*
X552019Y282026D01*
X552099Y282126D01*
X552199Y282206D01*
X552309Y282266D01*
X552434Y282306D01*
X552559Y282316D01*
G37*
G36*
G01X557284D02*
X557409Y282306D01*
X557534Y282266D01*
X557644Y282206D01*
X557744Y282126D01*
X557824Y282026D01*
X557884Y281916D01*
X557924Y281791D01*
X557934Y281666D01*
Y279236D01*
X557964Y279206D01*
X558064Y279066D01*
X558084Y279026D01*
X558099Y278991D01*
X558119Y278951D01*
X558134Y278911D01*
X558144Y278871D01*
X558159Y278826D01*
X558164Y278786D01*
X558174Y278746D01*
X558179Y278701D01*
Y278661D01*
X558184Y278616D01*
X558179Y278571D01*
Y278531D01*
X558174Y278486D01*
X558164Y278446D01*
X558159Y278406D01*
X558144Y278361D01*
X558134Y278321D01*
X558119Y278281D01*
X558099Y278241D01*
X558084Y278206D01*
X558064Y278166D01*
X557964Y278026D01*
X557934Y277996D01*
Y275866D01*
X557924Y275741D01*
X557884Y275616D01*
X557824Y275506D01*
X557744Y275406D01*
X557644Y275326D01*
X557534Y275266D01*
X557409Y275226D01*
X557284Y275216D01*
X557159Y275226D01*
X557034Y275266D01*
X556924Y275326D01*
X556824Y275406D01*
X556744Y275506D01*
X556684Y275616D01*
X556644Y275741D01*
X556634Y275866D01*
Y277991D01*
X556604Y278021D01*
X556579Y278056D01*
X556549Y278091D01*
X556529Y278126D01*
X556504Y278161D01*
X556464Y278241D01*
X556419Y278361D01*
X556409Y278401D01*
X556399Y278446D01*
X556394Y278486D01*
X556384Y278531D01*
Y278701D01*
X556394Y278746D01*
X556399Y278786D01*
X556409Y278831D01*
X556419Y278871D01*
X556464Y278991D01*
X556504Y279071D01*
X556529Y279106D01*
X556549Y279141D01*
X556579Y279176D01*
X556604Y279211D01*
X556634Y279241D01*
Y281666D01*
X556644Y281791D01*
X556684Y281916D01*
X556744Y282026D01*
X556824Y282126D01*
X556924Y282206D01*
X557034Y282266D01*
X557159Y282306D01*
X557284Y282316D01*
G37*
G36*
G01X562008D02*
X562133Y282306D01*
X562258Y282266D01*
X562368Y282206D01*
X562468Y282126D01*
X562548Y282026D01*
X562608Y281916D01*
X562648Y281791D01*
X562658Y281666D01*
Y279236D01*
X562688Y279206D01*
X562788Y279066D01*
X562808Y279026D01*
X562823Y278991D01*
X562843Y278951D01*
X562858Y278911D01*
X562868Y278871D01*
X562883Y278826D01*
X562888Y278786D01*
X562898Y278746D01*
X562903Y278701D01*
Y278661D01*
X562908Y278616D01*
X562903Y278571D01*
Y278531D01*
X562898Y278486D01*
X562888Y278446D01*
X562883Y278406D01*
X562868Y278361D01*
X562858Y278321D01*
X562843Y278281D01*
X562823Y278241D01*
X562808Y278206D01*
X562788Y278166D01*
X562688Y278026D01*
X562658Y277996D01*
Y275866D01*
X562648Y275741D01*
X562608Y275616D01*
X562548Y275506D01*
X562468Y275406D01*
X562368Y275326D01*
X562258Y275266D01*
X562133Y275226D01*
X562008Y275216D01*
X561883Y275226D01*
X561758Y275266D01*
X561648Y275326D01*
X561548Y275406D01*
X561468Y275506D01*
X561408Y275616D01*
X561368Y275741D01*
X561358Y275866D01*
Y277991D01*
X561328Y278021D01*
X561303Y278056D01*
X561273Y278091D01*
X561253Y278126D01*
X561228Y278161D01*
X561188Y278241D01*
X561143Y278361D01*
X561133Y278401D01*
X561123Y278446D01*
X561118Y278486D01*
X561108Y278531D01*
Y278701D01*
X561118Y278746D01*
X561123Y278786D01*
X561133Y278831D01*
X561143Y278871D01*
X561188Y278991D01*
X561228Y279071D01*
X561253Y279106D01*
X561273Y279141D01*
X561303Y279176D01*
X561328Y279211D01*
X561358Y279241D01*
Y281666D01*
X561368Y281791D01*
X561408Y281916D01*
X561468Y282026D01*
X561548Y282126D01*
X561648Y282206D01*
X561758Y282266D01*
X561883Y282306D01*
X562008Y282316D01*
G37*
G36*
G01X566733D02*
X566858Y282306D01*
X566983Y282266D01*
X567093Y282206D01*
X567193Y282126D01*
X567273Y282026D01*
X567333Y281916D01*
X567373Y281791D01*
X567383Y281666D01*
Y279236D01*
X567413Y279206D01*
X567513Y279066D01*
X567533Y279026D01*
X567548Y278991D01*
X567568Y278951D01*
X567583Y278911D01*
X567593Y278871D01*
X567608Y278826D01*
X567613Y278786D01*
X567623Y278746D01*
X567628Y278701D01*
Y278661D01*
X567633Y278616D01*
X567628Y278571D01*
Y278531D01*
X567623Y278486D01*
X567613Y278446D01*
X567608Y278406D01*
X567593Y278361D01*
X567583Y278321D01*
X567568Y278281D01*
X567548Y278241D01*
X567533Y278206D01*
X567513Y278166D01*
X567413Y278026D01*
X567383Y277996D01*
Y275866D01*
X567373Y275741D01*
X567333Y275616D01*
X567273Y275506D01*
X567193Y275406D01*
X567093Y275326D01*
X566983Y275266D01*
X566858Y275226D01*
X566733Y275216D01*
X566608Y275226D01*
X566483Y275266D01*
X566373Y275326D01*
X566273Y275406D01*
X566193Y275506D01*
X566133Y275616D01*
X566093Y275741D01*
X566083Y275866D01*
Y277991D01*
X566053Y278021D01*
X566028Y278056D01*
X565998Y278091D01*
X565978Y278126D01*
X565953Y278161D01*
X565913Y278241D01*
X565868Y278361D01*
X565858Y278401D01*
X565848Y278446D01*
X565843Y278486D01*
X565833Y278531D01*
Y278701D01*
X565843Y278746D01*
X565848Y278786D01*
X565858Y278831D01*
X565868Y278871D01*
X565913Y278991D01*
X565953Y279071D01*
X565978Y279106D01*
X565998Y279141D01*
X566028Y279176D01*
X566053Y279211D01*
X566083Y279241D01*
Y281666D01*
X566093Y281791D01*
X566133Y281916D01*
X566193Y282026D01*
X566273Y282126D01*
X566373Y282206D01*
X566483Y282266D01*
X566608Y282306D01*
X566733Y282316D01*
G37*
G36*
G01X571457D02*
X571582Y282306D01*
X571707Y282266D01*
X571817Y282206D01*
X571917Y282126D01*
X571997Y282026D01*
X572057Y281916D01*
X572097Y281791D01*
X572107Y281666D01*
Y279236D01*
X572137Y279206D01*
X572237Y279066D01*
X572257Y279026D01*
X572272Y278991D01*
X572292Y278951D01*
X572307Y278911D01*
X572317Y278871D01*
X572332Y278826D01*
X572337Y278786D01*
X572347Y278746D01*
X572352Y278701D01*
Y278661D01*
X572357Y278616D01*
X572352Y278571D01*
Y278531D01*
X572347Y278486D01*
X572337Y278446D01*
X572332Y278406D01*
X572317Y278361D01*
X572307Y278321D01*
X572292Y278281D01*
X572272Y278241D01*
X572257Y278206D01*
X572237Y278166D01*
X572137Y278026D01*
X572107Y277996D01*
Y275866D01*
X572097Y275741D01*
X572057Y275616D01*
X571997Y275506D01*
X571917Y275406D01*
X571817Y275326D01*
X571707Y275266D01*
X571582Y275226D01*
X571457Y275216D01*
X571332Y275226D01*
X571207Y275266D01*
X571097Y275326D01*
X570997Y275406D01*
X570917Y275506D01*
X570857Y275616D01*
X570817Y275741D01*
X570807Y275866D01*
Y277991D01*
X570777Y278021D01*
X570752Y278056D01*
X570722Y278091D01*
X570702Y278126D01*
X570677Y278161D01*
X570637Y278241D01*
X570592Y278361D01*
X570582Y278401D01*
X570572Y278446D01*
X570567Y278486D01*
X570557Y278531D01*
Y278701D01*
X570567Y278746D01*
X570572Y278786D01*
X570582Y278831D01*
X570592Y278871D01*
X570637Y278991D01*
X570677Y279071D01*
X570702Y279106D01*
X570722Y279141D01*
X570752Y279176D01*
X570777Y279211D01*
X570807Y279241D01*
Y281666D01*
X570817Y281791D01*
X570857Y281916D01*
X570917Y282026D01*
X570997Y282126D01*
X571097Y282206D01*
X571207Y282266D01*
X571332Y282306D01*
X571457Y282316D01*
G37*
G36*
G01X576181D02*
X576306Y282306D01*
X576431Y282266D01*
X576541Y282206D01*
X576641Y282126D01*
X576721Y282026D01*
X576781Y281916D01*
X576821Y281791D01*
X576831Y281666D01*
Y279236D01*
X576861Y279206D01*
X576961Y279066D01*
X576981Y279026D01*
X576996Y278991D01*
X577016Y278951D01*
X577031Y278911D01*
X577041Y278871D01*
X577056Y278826D01*
X577061Y278786D01*
X577071Y278746D01*
X577076Y278701D01*
Y278661D01*
X577081Y278616D01*
X577076Y278571D01*
Y278531D01*
X577071Y278486D01*
X577061Y278446D01*
X577056Y278406D01*
X577041Y278361D01*
X577031Y278321D01*
X577016Y278281D01*
X576996Y278241D01*
X576981Y278206D01*
X576961Y278166D01*
X576861Y278026D01*
X576831Y277996D01*
Y275866D01*
X576821Y275741D01*
X576781Y275616D01*
X576721Y275506D01*
X576641Y275406D01*
X576541Y275326D01*
X576431Y275266D01*
X576306Y275226D01*
X576181Y275216D01*
X576056Y275226D01*
X575931Y275266D01*
X575821Y275326D01*
X575721Y275406D01*
X575641Y275506D01*
X575581Y275616D01*
X575541Y275741D01*
X575531Y275866D01*
Y277991D01*
X575501Y278021D01*
X575476Y278056D01*
X575446Y278091D01*
X575426Y278126D01*
X575401Y278161D01*
X575361Y278241D01*
X575316Y278361D01*
X575306Y278401D01*
X575296Y278446D01*
X575291Y278486D01*
X575281Y278531D01*
Y278701D01*
X575291Y278746D01*
X575296Y278786D01*
X575306Y278831D01*
X575316Y278871D01*
X575361Y278991D01*
X575401Y279071D01*
X575426Y279106D01*
X575446Y279141D01*
X575476Y279176D01*
X575501Y279211D01*
X575531Y279241D01*
Y281666D01*
X575541Y281791D01*
X575581Y281916D01*
X575641Y282026D01*
X575721Y282126D01*
X575821Y282206D01*
X575931Y282266D01*
X576056Y282306D01*
X576181Y282316D01*
G37*
G36*
G01X580906D02*
X581031Y282306D01*
X581156Y282266D01*
X581266Y282206D01*
X581366Y282126D01*
X581446Y282026D01*
X581506Y281916D01*
X581546Y281791D01*
X581556Y281666D01*
Y279236D01*
X581586Y279206D01*
X581686Y279066D01*
X581706Y279026D01*
X581721Y278991D01*
X581741Y278951D01*
X581756Y278911D01*
X581766Y278871D01*
X581781Y278826D01*
X581786Y278786D01*
X581796Y278746D01*
X581801Y278701D01*
Y278661D01*
X581806Y278616D01*
X581801Y278571D01*
Y278531D01*
X581796Y278486D01*
X581786Y278446D01*
X581781Y278406D01*
X581766Y278361D01*
X581756Y278321D01*
X581741Y278281D01*
X581721Y278241D01*
X581706Y278206D01*
X581686Y278166D01*
X581586Y278026D01*
X581556Y277996D01*
Y275866D01*
X581546Y275741D01*
X581506Y275616D01*
X581446Y275506D01*
X581366Y275406D01*
X581266Y275326D01*
X581156Y275266D01*
X581031Y275226D01*
X580906Y275216D01*
X580781Y275226D01*
X580656Y275266D01*
X580546Y275326D01*
X580446Y275406D01*
X580366Y275506D01*
X580306Y275616D01*
X580266Y275741D01*
X580256Y275866D01*
Y277991D01*
X580226Y278021D01*
X580201Y278056D01*
X580171Y278091D01*
X580151Y278126D01*
X580126Y278161D01*
X580086Y278241D01*
X580041Y278361D01*
X580031Y278401D01*
X580021Y278446D01*
X580016Y278486D01*
X580006Y278531D01*
Y278701D01*
X580016Y278746D01*
X580021Y278786D01*
X580031Y278831D01*
X580041Y278871D01*
X580086Y278991D01*
X580126Y279071D01*
X580151Y279106D01*
X580171Y279141D01*
X580201Y279176D01*
X580226Y279211D01*
X580256Y279241D01*
Y281666D01*
X580266Y281791D01*
X580306Y281916D01*
X580366Y282026D01*
X580446Y282126D01*
X580546Y282206D01*
X580656Y282266D01*
X580781Y282306D01*
X580906Y282316D01*
G37*
G36*
G01X585630D02*
X585755Y282306D01*
X585880Y282266D01*
X585990Y282206D01*
X586090Y282126D01*
X586170Y282026D01*
X586230Y281916D01*
X586270Y281791D01*
X586280Y281666D01*
Y279236D01*
X586310Y279206D01*
X586410Y279066D01*
X586430Y279026D01*
X586445Y278991D01*
X586465Y278951D01*
X586480Y278911D01*
X586490Y278871D01*
X586505Y278826D01*
X586510Y278786D01*
X586520Y278746D01*
X586525Y278701D01*
Y278661D01*
X586530Y278616D01*
X586525Y278571D01*
Y278531D01*
X586520Y278486D01*
X586510Y278446D01*
X586505Y278406D01*
X586490Y278361D01*
X586480Y278321D01*
X586465Y278281D01*
X586445Y278241D01*
X586430Y278206D01*
X586410Y278166D01*
X586310Y278026D01*
X586280Y277996D01*
Y275866D01*
X586270Y275741D01*
X586230Y275616D01*
X586170Y275506D01*
X586090Y275406D01*
X585990Y275326D01*
X585880Y275266D01*
X585755Y275226D01*
X585630Y275216D01*
X585505Y275226D01*
X585380Y275266D01*
X585270Y275326D01*
X585170Y275406D01*
X585090Y275506D01*
X585030Y275616D01*
X584990Y275741D01*
X584980Y275866D01*
Y277991D01*
X584950Y278021D01*
X584925Y278056D01*
X584895Y278091D01*
X584875Y278126D01*
X584850Y278161D01*
X584810Y278241D01*
X584765Y278361D01*
X584755Y278401D01*
X584745Y278446D01*
X584740Y278486D01*
X584730Y278531D01*
Y278701D01*
X584740Y278746D01*
X584745Y278786D01*
X584755Y278831D01*
X584765Y278871D01*
X584810Y278991D01*
X584850Y279071D01*
X584875Y279106D01*
X584895Y279141D01*
X584925Y279176D01*
X584950Y279211D01*
X584980Y279241D01*
Y281666D01*
X584990Y281791D01*
X585030Y281916D01*
X585090Y282026D01*
X585170Y282126D01*
X585270Y282206D01*
X585380Y282266D01*
X585505Y282306D01*
X585630Y282316D01*
G37*
G36*
G01X590355D02*
X590480Y282306D01*
X590605Y282266D01*
X590715Y282206D01*
X590815Y282126D01*
X590895Y282026D01*
X590955Y281916D01*
X590995Y281791D01*
X591005Y281666D01*
Y279236D01*
X591035Y279206D01*
X591135Y279066D01*
X591155Y279026D01*
X591170Y278991D01*
X591190Y278951D01*
X591205Y278911D01*
X591215Y278871D01*
X591230Y278826D01*
X591235Y278786D01*
X591245Y278746D01*
X591250Y278701D01*
Y278661D01*
X591255Y278616D01*
X591250Y278571D01*
Y278531D01*
X591245Y278486D01*
X591235Y278446D01*
X591230Y278406D01*
X591215Y278361D01*
X591205Y278321D01*
X591190Y278281D01*
X591170Y278241D01*
X591155Y278206D01*
X591135Y278166D01*
X591035Y278026D01*
X591005Y277996D01*
Y275866D01*
X590995Y275741D01*
X590955Y275616D01*
X590895Y275506D01*
X590815Y275406D01*
X590715Y275326D01*
X590605Y275266D01*
X590480Y275226D01*
X590355Y275216D01*
X590230Y275226D01*
X590105Y275266D01*
X589995Y275326D01*
X589895Y275406D01*
X589815Y275506D01*
X589755Y275616D01*
X589715Y275741D01*
X589705Y275866D01*
Y277991D01*
X589675Y278021D01*
X589650Y278056D01*
X589620Y278091D01*
X589600Y278126D01*
X589575Y278161D01*
X589535Y278241D01*
X589490Y278361D01*
X589480Y278401D01*
X589470Y278446D01*
X589465Y278486D01*
X589455Y278531D01*
Y278701D01*
X589465Y278746D01*
X589470Y278786D01*
X589480Y278831D01*
X589490Y278871D01*
X589535Y278991D01*
X589575Y279071D01*
X589600Y279106D01*
X589620Y279141D01*
X589650Y279176D01*
X589675Y279211D01*
X589705Y279241D01*
Y281666D01*
X589715Y281791D01*
X589755Y281916D01*
X589815Y282026D01*
X589895Y282126D01*
X589995Y282206D01*
X590105Y282266D01*
X590230Y282306D01*
X590355Y282316D01*
G37*
G36*
G01X595079D02*
X595204Y282306D01*
X595329Y282266D01*
X595439Y282206D01*
X595539Y282126D01*
X595619Y282026D01*
X595679Y281916D01*
X595719Y281791D01*
X595729Y281666D01*
Y279236D01*
X595759Y279206D01*
X595859Y279066D01*
X595879Y279026D01*
X595894Y278991D01*
X595914Y278951D01*
X595929Y278911D01*
X595939Y278871D01*
X595954Y278826D01*
X595959Y278786D01*
X595969Y278746D01*
X595974Y278701D01*
Y278661D01*
X595979Y278616D01*
X595974Y278571D01*
Y278531D01*
X595969Y278486D01*
X595959Y278446D01*
X595954Y278406D01*
X595939Y278361D01*
X595929Y278321D01*
X595914Y278281D01*
X595894Y278241D01*
X595879Y278206D01*
X595859Y278166D01*
X595759Y278026D01*
X595729Y277996D01*
Y275866D01*
X595719Y275741D01*
X595679Y275616D01*
X595619Y275506D01*
X595539Y275406D01*
X595439Y275326D01*
X595329Y275266D01*
X595204Y275226D01*
X595079Y275216D01*
X594954Y275226D01*
X594829Y275266D01*
X594719Y275326D01*
X594619Y275406D01*
X594539Y275506D01*
X594479Y275616D01*
X594439Y275741D01*
X594429Y275866D01*
Y277991D01*
X594399Y278021D01*
X594374Y278056D01*
X594344Y278091D01*
X594324Y278126D01*
X594299Y278161D01*
X594259Y278241D01*
X594214Y278361D01*
X594204Y278401D01*
X594194Y278446D01*
X594189Y278486D01*
X594179Y278531D01*
Y278701D01*
X594189Y278746D01*
X594194Y278786D01*
X594204Y278831D01*
X594214Y278871D01*
X594259Y278991D01*
X594299Y279071D01*
X594324Y279106D01*
X594344Y279141D01*
X594374Y279176D01*
X594399Y279211D01*
X594429Y279241D01*
Y281666D01*
X594439Y281791D01*
X594479Y281916D01*
X594539Y282026D01*
X594619Y282126D01*
X594719Y282206D01*
X594829Y282266D01*
X594954Y282306D01*
X595079Y282316D01*
G37*
G36*
G01X599803D02*
X599928Y282306D01*
X600053Y282266D01*
X600163Y282206D01*
X600263Y282126D01*
X600343Y282026D01*
X600403Y281916D01*
X600443Y281791D01*
X600453Y281666D01*
Y279236D01*
X600483Y279206D01*
X600583Y279066D01*
X600603Y279026D01*
X600618Y278991D01*
X600638Y278951D01*
X600653Y278911D01*
X600663Y278871D01*
X600678Y278826D01*
X600683Y278786D01*
X600693Y278746D01*
X600698Y278701D01*
Y278661D01*
X600703Y278616D01*
X600698Y278571D01*
Y278531D01*
X600693Y278486D01*
X600683Y278446D01*
X600678Y278406D01*
X600663Y278361D01*
X600653Y278321D01*
X600638Y278281D01*
X600618Y278241D01*
X600603Y278206D01*
X600583Y278166D01*
X600483Y278026D01*
X600453Y277996D01*
Y275866D01*
X600443Y275741D01*
X600403Y275616D01*
X600343Y275506D01*
X600263Y275406D01*
X600163Y275326D01*
X600053Y275266D01*
X599928Y275226D01*
X599803Y275216D01*
X599678Y275226D01*
X599553Y275266D01*
X599443Y275326D01*
X599343Y275406D01*
X599263Y275506D01*
X599203Y275616D01*
X599163Y275741D01*
X599153Y275866D01*
Y277991D01*
X599123Y278021D01*
X599098Y278056D01*
X599068Y278091D01*
X599048Y278126D01*
X599023Y278161D01*
X598983Y278241D01*
X598938Y278361D01*
X598928Y278401D01*
X598918Y278446D01*
X598913Y278486D01*
X598903Y278531D01*
Y278701D01*
X598913Y278746D01*
X598918Y278786D01*
X598928Y278831D01*
X598938Y278871D01*
X598983Y278991D01*
X599023Y279071D01*
X599048Y279106D01*
X599068Y279141D01*
X599098Y279176D01*
X599123Y279211D01*
X599153Y279241D01*
Y281666D01*
X599163Y281791D01*
X599203Y281916D01*
X599263Y282026D01*
X599343Y282126D01*
X599443Y282206D01*
X599553Y282266D01*
X599678Y282306D01*
X599803Y282316D01*
G37*
G36*
G01X604528D02*
X604653Y282306D01*
X604778Y282266D01*
X604888Y282206D01*
X604988Y282126D01*
X605068Y282026D01*
X605128Y281916D01*
X605168Y281791D01*
X605178Y281666D01*
Y279236D01*
X605208Y279206D01*
X605308Y279066D01*
X605328Y279026D01*
X605343Y278991D01*
X605363Y278951D01*
X605378Y278911D01*
X605388Y278871D01*
X605403Y278826D01*
X605408Y278786D01*
X605418Y278746D01*
X605423Y278701D01*
Y278661D01*
X605428Y278616D01*
X605423Y278571D01*
Y278531D01*
X605418Y278486D01*
X605408Y278446D01*
X605403Y278406D01*
X605388Y278361D01*
X605378Y278321D01*
X605363Y278281D01*
X605343Y278241D01*
X605328Y278206D01*
X605308Y278166D01*
X605208Y278026D01*
X605178Y277996D01*
Y275866D01*
X605168Y275741D01*
X605128Y275616D01*
X605068Y275506D01*
X604988Y275406D01*
X604888Y275326D01*
X604778Y275266D01*
X604653Y275226D01*
X604528Y275216D01*
X604403Y275226D01*
X604278Y275266D01*
X604168Y275326D01*
X604068Y275406D01*
X603988Y275506D01*
X603928Y275616D01*
X603888Y275741D01*
X603878Y275866D01*
Y277991D01*
X603848Y278021D01*
X603823Y278056D01*
X603793Y278091D01*
X603773Y278126D01*
X603748Y278161D01*
X603708Y278241D01*
X603663Y278361D01*
X603653Y278401D01*
X603643Y278446D01*
X603638Y278486D01*
X603628Y278531D01*
Y278701D01*
X603638Y278746D01*
X603643Y278786D01*
X603653Y278831D01*
X603663Y278871D01*
X603708Y278991D01*
X603748Y279071D01*
X603773Y279106D01*
X603793Y279141D01*
X603823Y279176D01*
X603848Y279211D01*
X603878Y279241D01*
Y281666D01*
X603888Y281791D01*
X603928Y281916D01*
X603988Y282026D01*
X604068Y282126D01*
X604168Y282206D01*
X604278Y282266D01*
X604403Y282306D01*
X604528Y282316D01*
G37*
G36*
G01X609252D02*
X609377Y282306D01*
X609502Y282266D01*
X609612Y282206D01*
X609712Y282126D01*
X609792Y282026D01*
X609852Y281916D01*
X609892Y281791D01*
X609902Y281666D01*
Y279236D01*
X609932Y279206D01*
X610032Y279066D01*
X610052Y279026D01*
X610067Y278991D01*
X610087Y278951D01*
X610102Y278911D01*
X610112Y278871D01*
X610127Y278826D01*
X610132Y278786D01*
X610142Y278746D01*
X610147Y278701D01*
Y278661D01*
X610152Y278616D01*
X610147Y278571D01*
Y278531D01*
X610142Y278486D01*
X610132Y278446D01*
X610127Y278406D01*
X610112Y278361D01*
X610102Y278321D01*
X610087Y278281D01*
X610067Y278241D01*
X610052Y278206D01*
X610032Y278166D01*
X609932Y278026D01*
X609902Y277996D01*
Y275866D01*
X609892Y275741D01*
X609852Y275616D01*
X609792Y275506D01*
X609712Y275406D01*
X609612Y275326D01*
X609502Y275266D01*
X609377Y275226D01*
X609252Y275216D01*
X609127Y275226D01*
X609002Y275266D01*
X608892Y275326D01*
X608792Y275406D01*
X608712Y275506D01*
X608652Y275616D01*
X608612Y275741D01*
X608602Y275866D01*
Y277991D01*
X608572Y278021D01*
X608547Y278056D01*
X608517Y278091D01*
X608497Y278126D01*
X608472Y278161D01*
X608432Y278241D01*
X608387Y278361D01*
X608377Y278401D01*
X608367Y278446D01*
X608362Y278486D01*
X608352Y278531D01*
Y278701D01*
X608362Y278746D01*
X608367Y278786D01*
X608377Y278831D01*
X608387Y278871D01*
X608432Y278991D01*
X608472Y279071D01*
X608497Y279106D01*
X608517Y279141D01*
X608547Y279176D01*
X608572Y279211D01*
X608602Y279241D01*
Y281666D01*
X608612Y281791D01*
X608652Y281916D01*
X608712Y282026D01*
X608792Y282126D01*
X608892Y282206D01*
X609002Y282266D01*
X609127Y282306D01*
X609252Y282316D01*
G37*
G36*
G01X613977D02*
X614102Y282306D01*
X614227Y282266D01*
X614337Y282206D01*
X614437Y282126D01*
X614517Y282026D01*
X614577Y281916D01*
X614617Y281791D01*
X614627Y281666D01*
Y279236D01*
X614657Y279206D01*
X614757Y279066D01*
X614777Y279026D01*
X614792Y278991D01*
X614812Y278951D01*
X614827Y278911D01*
X614837Y278871D01*
X614852Y278826D01*
X614857Y278786D01*
X614867Y278746D01*
X614872Y278701D01*
Y278661D01*
X614877Y278616D01*
X614872Y278571D01*
Y278531D01*
X614867Y278486D01*
X614857Y278446D01*
X614852Y278406D01*
X614837Y278361D01*
X614827Y278321D01*
X614812Y278281D01*
X614792Y278241D01*
X614777Y278206D01*
X614757Y278166D01*
X614657Y278026D01*
X614627Y277996D01*
Y275866D01*
X614617Y275741D01*
X614577Y275616D01*
X614517Y275506D01*
X614437Y275406D01*
X614337Y275326D01*
X614227Y275266D01*
X614102Y275226D01*
X613977Y275216D01*
X613852Y275226D01*
X613727Y275266D01*
X613617Y275326D01*
X613517Y275406D01*
X613437Y275506D01*
X613377Y275616D01*
X613337Y275741D01*
X613327Y275866D01*
Y277991D01*
X613297Y278021D01*
X613272Y278056D01*
X613242Y278091D01*
X613222Y278126D01*
X613197Y278161D01*
X613157Y278241D01*
X613112Y278361D01*
X613102Y278401D01*
X613092Y278446D01*
X613087Y278486D01*
X613077Y278531D01*
Y278701D01*
X613087Y278746D01*
X613092Y278786D01*
X613102Y278831D01*
X613112Y278871D01*
X613157Y278991D01*
X613197Y279071D01*
X613222Y279106D01*
X613242Y279141D01*
X613272Y279176D01*
X613297Y279211D01*
X613327Y279241D01*
Y281666D01*
X613337Y281791D01*
X613377Y281916D01*
X613437Y282026D01*
X613517Y282126D01*
X613617Y282206D01*
X613727Y282266D01*
X613852Y282306D01*
X613977Y282316D01*
G37*
G36*
G01X618701D02*
X618826Y282306D01*
X618951Y282266D01*
X619061Y282206D01*
X619161Y282126D01*
X619241Y282026D01*
X619301Y281916D01*
X619341Y281791D01*
X619351Y281666D01*
Y279236D01*
X619381Y279206D01*
X619481Y279066D01*
X619501Y279026D01*
X619516Y278991D01*
X619536Y278951D01*
X619551Y278911D01*
X619561Y278871D01*
X619576Y278826D01*
X619581Y278786D01*
X619591Y278746D01*
X619596Y278701D01*
Y278661D01*
X619601Y278616D01*
X619596Y278571D01*
Y278531D01*
X619591Y278486D01*
X619581Y278446D01*
X619576Y278406D01*
X619561Y278361D01*
X619551Y278321D01*
X619536Y278281D01*
X619516Y278241D01*
X619501Y278206D01*
X619481Y278166D01*
X619381Y278026D01*
X619351Y277996D01*
Y275866D01*
X619341Y275741D01*
X619301Y275616D01*
X619241Y275506D01*
X619161Y275406D01*
X619061Y275326D01*
X618951Y275266D01*
X618826Y275226D01*
X618701Y275216D01*
X618576Y275226D01*
X618451Y275266D01*
X618341Y275326D01*
X618241Y275406D01*
X618161Y275506D01*
X618101Y275616D01*
X618061Y275741D01*
X618051Y275866D01*
Y277991D01*
X618021Y278021D01*
X617996Y278056D01*
X617966Y278091D01*
X617946Y278126D01*
X617921Y278161D01*
X617881Y278241D01*
X617836Y278361D01*
X617826Y278401D01*
X617816Y278446D01*
X617811Y278486D01*
X617801Y278531D01*
Y278701D01*
X617811Y278746D01*
X617816Y278786D01*
X617826Y278831D01*
X617836Y278871D01*
X617881Y278991D01*
X617921Y279071D01*
X617946Y279106D01*
X617966Y279141D01*
X617996Y279176D01*
X618021Y279211D01*
X618051Y279241D01*
Y281666D01*
X618061Y281791D01*
X618101Y281916D01*
X618161Y282026D01*
X618241Y282126D01*
X618341Y282206D01*
X618451Y282266D01*
X618576Y282306D01*
X618701Y282316D01*
G37*
G36*
G01X623425D02*
X623550Y282306D01*
X623675Y282266D01*
X623785Y282206D01*
X623885Y282126D01*
X623965Y282026D01*
X624025Y281916D01*
X624065Y281791D01*
X624075Y281666D01*
Y279236D01*
X624105Y279206D01*
X624205Y279066D01*
X624225Y279026D01*
X624240Y278991D01*
X624260Y278951D01*
X624275Y278911D01*
X624285Y278871D01*
X624300Y278826D01*
X624305Y278786D01*
X624315Y278746D01*
X624320Y278701D01*
Y278661D01*
X624325Y278616D01*
X624320Y278571D01*
Y278531D01*
X624315Y278486D01*
X624305Y278446D01*
X624300Y278406D01*
X624285Y278361D01*
X624275Y278321D01*
X624260Y278281D01*
X624240Y278241D01*
X624225Y278206D01*
X624205Y278166D01*
X624105Y278026D01*
X624075Y277996D01*
Y275866D01*
X624065Y275741D01*
X624025Y275616D01*
X623965Y275506D01*
X623885Y275406D01*
X623785Y275326D01*
X623675Y275266D01*
X623550Y275226D01*
X623425Y275216D01*
X623300Y275226D01*
X623175Y275266D01*
X623065Y275326D01*
X622965Y275406D01*
X622885Y275506D01*
X622825Y275616D01*
X622785Y275741D01*
X622775Y275866D01*
Y277991D01*
X622745Y278021D01*
X622720Y278056D01*
X622690Y278091D01*
X622670Y278126D01*
X622645Y278161D01*
X622605Y278241D01*
X622560Y278361D01*
X622550Y278401D01*
X622540Y278446D01*
X622535Y278486D01*
X622525Y278531D01*
Y278701D01*
X622535Y278746D01*
X622540Y278786D01*
X622550Y278831D01*
X622560Y278871D01*
X622605Y278991D01*
X622645Y279071D01*
X622670Y279106D01*
X622690Y279141D01*
X622720Y279176D01*
X622745Y279211D01*
X622775Y279241D01*
Y281666D01*
X622785Y281791D01*
X622825Y281916D01*
X622885Y282026D01*
X622965Y282126D01*
X623065Y282206D01*
X623175Y282266D01*
X623300Y282306D01*
X623425Y282316D01*
G37*
G36*
G01X628150D02*
X628275Y282306D01*
X628400Y282266D01*
X628510Y282206D01*
X628610Y282126D01*
X628690Y282026D01*
X628750Y281916D01*
X628790Y281791D01*
X628800Y281666D01*
Y279236D01*
X628830Y279206D01*
X628930Y279066D01*
X628950Y279026D01*
X628965Y278991D01*
X628985Y278951D01*
X629000Y278911D01*
X629010Y278871D01*
X629025Y278826D01*
X629030Y278786D01*
X629040Y278746D01*
X629045Y278701D01*
Y278661D01*
X629050Y278616D01*
X629045Y278571D01*
Y278531D01*
X629040Y278486D01*
X629030Y278446D01*
X629025Y278406D01*
X629010Y278361D01*
X629000Y278321D01*
X628985Y278281D01*
X628965Y278241D01*
X628950Y278206D01*
X628930Y278166D01*
X628830Y278026D01*
X628800Y277996D01*
Y275866D01*
X628790Y275741D01*
X628750Y275616D01*
X628690Y275506D01*
X628610Y275406D01*
X628510Y275326D01*
X628400Y275266D01*
X628275Y275226D01*
X628150Y275216D01*
X628025Y275226D01*
X627900Y275266D01*
X627790Y275326D01*
X627690Y275406D01*
X627610Y275506D01*
X627550Y275616D01*
X627510Y275741D01*
X627500Y275866D01*
Y277991D01*
X627470Y278021D01*
X627445Y278056D01*
X627415Y278091D01*
X627395Y278126D01*
X627370Y278161D01*
X627330Y278241D01*
X627285Y278361D01*
X627275Y278401D01*
X627265Y278446D01*
X627260Y278486D01*
X627250Y278531D01*
Y278701D01*
X627260Y278746D01*
X627265Y278786D01*
X627275Y278831D01*
X627285Y278871D01*
X627330Y278991D01*
X627370Y279071D01*
X627395Y279106D01*
X627415Y279141D01*
X627445Y279176D01*
X627470Y279211D01*
X627500Y279241D01*
Y281666D01*
X627510Y281791D01*
X627550Y281916D01*
X627610Y282026D01*
X627690Y282126D01*
X627790Y282206D01*
X627900Y282266D01*
X628025Y282306D01*
X628150Y282316D01*
G37*
G36*
G01X632874D02*
X632999Y282306D01*
X633124Y282266D01*
X633234Y282206D01*
X633334Y282126D01*
X633414Y282026D01*
X633474Y281916D01*
X633514Y281791D01*
X633524Y281666D01*
Y279236D01*
X633554Y279206D01*
X633654Y279066D01*
X633674Y279026D01*
X633689Y278991D01*
X633709Y278951D01*
X633724Y278911D01*
X633734Y278871D01*
X633749Y278826D01*
X633754Y278786D01*
X633764Y278746D01*
X633769Y278701D01*
Y278661D01*
X633774Y278616D01*
X633769Y278571D01*
Y278531D01*
X633764Y278486D01*
X633754Y278446D01*
X633749Y278406D01*
X633734Y278361D01*
X633724Y278321D01*
X633709Y278281D01*
X633689Y278241D01*
X633674Y278206D01*
X633654Y278166D01*
X633554Y278026D01*
X633524Y277996D01*
Y275866D01*
X633514Y275741D01*
X633474Y275616D01*
X633414Y275506D01*
X633334Y275406D01*
X633234Y275326D01*
X633124Y275266D01*
X632999Y275226D01*
X632874Y275216D01*
X632749Y275226D01*
X632624Y275266D01*
X632514Y275326D01*
X632414Y275406D01*
X632334Y275506D01*
X632274Y275616D01*
X632234Y275741D01*
X632224Y275866D01*
Y277991D01*
X632194Y278021D01*
X632169Y278056D01*
X632139Y278091D01*
X632119Y278126D01*
X632094Y278161D01*
X632054Y278241D01*
X632009Y278361D01*
X631999Y278401D01*
X631989Y278446D01*
X631984Y278486D01*
X631974Y278531D01*
Y278701D01*
X631984Y278746D01*
X631989Y278786D01*
X631999Y278831D01*
X632009Y278871D01*
X632054Y278991D01*
X632094Y279071D01*
X632119Y279106D01*
X632139Y279141D01*
X632169Y279176D01*
X632194Y279211D01*
X632224Y279241D01*
Y281666D01*
X632234Y281791D01*
X632274Y281916D01*
X632334Y282026D01*
X632414Y282126D01*
X632514Y282206D01*
X632624Y282266D01*
X632749Y282306D01*
X632874Y282316D01*
G37*
G36*
G01X637599D02*
X637724Y282306D01*
X637849Y282266D01*
X637959Y282206D01*
X638059Y282126D01*
X638139Y282026D01*
X638199Y281916D01*
X638239Y281791D01*
X638249Y281666D01*
Y279236D01*
X638279Y279206D01*
X638379Y279066D01*
X638399Y279026D01*
X638414Y278991D01*
X638434Y278951D01*
X638449Y278911D01*
X638459Y278871D01*
X638474Y278826D01*
X638479Y278786D01*
X638489Y278746D01*
X638494Y278701D01*
Y278661D01*
X638499Y278616D01*
X638494Y278571D01*
Y278531D01*
X638489Y278486D01*
X638479Y278446D01*
X638474Y278406D01*
X638459Y278361D01*
X638449Y278321D01*
X638434Y278281D01*
X638414Y278241D01*
X638399Y278206D01*
X638379Y278166D01*
X638279Y278026D01*
X638249Y277996D01*
Y275866D01*
X638239Y275741D01*
X638199Y275616D01*
X638139Y275506D01*
X638059Y275406D01*
X637959Y275326D01*
X637849Y275266D01*
X637724Y275226D01*
X637599Y275216D01*
X637474Y275226D01*
X637349Y275266D01*
X637239Y275326D01*
X637139Y275406D01*
X637059Y275506D01*
X636999Y275616D01*
X636959Y275741D01*
X636949Y275866D01*
Y277991D01*
X636919Y278021D01*
X636894Y278056D01*
X636864Y278091D01*
X636844Y278126D01*
X636819Y278161D01*
X636779Y278241D01*
X636734Y278361D01*
X636724Y278401D01*
X636714Y278446D01*
X636709Y278486D01*
X636699Y278531D01*
Y278701D01*
X636709Y278746D01*
X636714Y278786D01*
X636724Y278831D01*
X636734Y278871D01*
X636779Y278991D01*
X636819Y279071D01*
X636844Y279106D01*
X636864Y279141D01*
X636894Y279176D01*
X636919Y279211D01*
X636949Y279241D01*
Y281666D01*
X636959Y281791D01*
X636999Y281916D01*
X637059Y282026D01*
X637139Y282126D01*
X637239Y282206D01*
X637349Y282266D01*
X637474Y282306D01*
X637599Y282316D01*
G37*
G36*
G01X642323D02*
X642448Y282306D01*
X642573Y282266D01*
X642683Y282206D01*
X642783Y282126D01*
X642863Y282026D01*
X642923Y281916D01*
X642963Y281791D01*
X642973Y281666D01*
Y279236D01*
X643003Y279206D01*
X643103Y279066D01*
X643123Y279026D01*
X643138Y278991D01*
X643158Y278951D01*
X643173Y278911D01*
X643183Y278871D01*
X643198Y278826D01*
X643203Y278786D01*
X643213Y278746D01*
X643218Y278701D01*
Y278661D01*
X643223Y278616D01*
X643218Y278571D01*
Y278531D01*
X643213Y278486D01*
X643203Y278446D01*
X643198Y278406D01*
X643183Y278361D01*
X643173Y278321D01*
X643158Y278281D01*
X643138Y278241D01*
X643123Y278206D01*
X643103Y278166D01*
X643003Y278026D01*
X642973Y277996D01*
Y275866D01*
X642963Y275741D01*
X642923Y275616D01*
X642863Y275506D01*
X642783Y275406D01*
X642683Y275326D01*
X642573Y275266D01*
X642448Y275226D01*
X642323Y275216D01*
X642198Y275226D01*
X642073Y275266D01*
X641963Y275326D01*
X641863Y275406D01*
X641783Y275506D01*
X641723Y275616D01*
X641683Y275741D01*
X641673Y275866D01*
Y277991D01*
X641643Y278021D01*
X641618Y278056D01*
X641588Y278091D01*
X641568Y278126D01*
X641543Y278161D01*
X641503Y278241D01*
X641458Y278361D01*
X641448Y278401D01*
X641438Y278446D01*
X641433Y278486D01*
X641423Y278531D01*
Y278701D01*
X641433Y278746D01*
X641438Y278786D01*
X641448Y278831D01*
X641458Y278871D01*
X641503Y278991D01*
X641543Y279071D01*
X641568Y279106D01*
X641588Y279141D01*
X641618Y279176D01*
X641643Y279211D01*
X641673Y279241D01*
Y281666D01*
X641683Y281791D01*
X641723Y281916D01*
X641783Y282026D01*
X641863Y282126D01*
X641963Y282206D01*
X642073Y282266D01*
X642198Y282306D01*
X642323Y282316D01*
G37*
G36*
G01X647047D02*
X647172Y282306D01*
X647297Y282266D01*
X647407Y282206D01*
X647507Y282126D01*
X647587Y282026D01*
X647647Y281916D01*
X647687Y281791D01*
X647697Y281666D01*
Y279236D01*
X647727Y279206D01*
X647827Y279066D01*
X647847Y279026D01*
X647862Y278991D01*
X647882Y278951D01*
X647897Y278911D01*
X647907Y278871D01*
X647922Y278826D01*
X647927Y278786D01*
X647937Y278746D01*
X647942Y278701D01*
Y278661D01*
X647947Y278616D01*
X647942Y278571D01*
Y278531D01*
X647937Y278486D01*
X647927Y278446D01*
X647922Y278406D01*
X647907Y278361D01*
X647897Y278321D01*
X647882Y278281D01*
X647862Y278241D01*
X647847Y278206D01*
X647827Y278166D01*
X647727Y278026D01*
X647697Y277996D01*
Y275866D01*
X647687Y275741D01*
X647647Y275616D01*
X647587Y275506D01*
X647507Y275406D01*
X647407Y275326D01*
X647297Y275266D01*
X647172Y275226D01*
X647047Y275216D01*
X646922Y275226D01*
X646797Y275266D01*
X646687Y275326D01*
X646587Y275406D01*
X646507Y275506D01*
X646447Y275616D01*
X646407Y275741D01*
X646397Y275866D01*
Y277991D01*
X646367Y278021D01*
X646342Y278056D01*
X646312Y278091D01*
X646292Y278126D01*
X646267Y278161D01*
X646227Y278241D01*
X646182Y278361D01*
X646172Y278401D01*
X646162Y278446D01*
X646157Y278486D01*
X646147Y278531D01*
Y278701D01*
X646157Y278746D01*
X646162Y278786D01*
X646172Y278831D01*
X646182Y278871D01*
X646227Y278991D01*
X646267Y279071D01*
X646292Y279106D01*
X646312Y279141D01*
X646342Y279176D01*
X646367Y279211D01*
X646397Y279241D01*
Y281666D01*
X646407Y281791D01*
X646447Y281916D01*
X646507Y282026D01*
X646587Y282126D01*
X646687Y282206D01*
X646797Y282266D01*
X646922Y282306D01*
X647047Y282316D01*
G37*
G36*
G01X651772D02*
X651897Y282306D01*
X652022Y282266D01*
X652132Y282206D01*
X652232Y282126D01*
X652312Y282026D01*
X652372Y281916D01*
X652412Y281791D01*
X652422Y281666D01*
Y279236D01*
X652452Y279206D01*
X652552Y279066D01*
X652572Y279026D01*
X652587Y278991D01*
X652607Y278951D01*
X652622Y278911D01*
X652632Y278871D01*
X652647Y278826D01*
X652652Y278786D01*
X652662Y278746D01*
X652667Y278701D01*
Y278661D01*
X652672Y278616D01*
X652667Y278571D01*
Y278531D01*
X652662Y278486D01*
X652652Y278446D01*
X652647Y278406D01*
X652632Y278361D01*
X652622Y278321D01*
X652607Y278281D01*
X652587Y278241D01*
X652572Y278206D01*
X652552Y278166D01*
X652452Y278026D01*
X652422Y277996D01*
Y275866D01*
X652412Y275741D01*
X652372Y275616D01*
X652312Y275506D01*
X652232Y275406D01*
X652132Y275326D01*
X652022Y275266D01*
X651897Y275226D01*
X651772Y275216D01*
X651647Y275226D01*
X651522Y275266D01*
X651412Y275326D01*
X651312Y275406D01*
X651232Y275506D01*
X651172Y275616D01*
X651132Y275741D01*
X651122Y275866D01*
Y277991D01*
X651092Y278021D01*
X651067Y278056D01*
X651037Y278091D01*
X651017Y278126D01*
X650992Y278161D01*
X650952Y278241D01*
X650907Y278361D01*
X650897Y278401D01*
X650887Y278446D01*
X650882Y278486D01*
X650872Y278531D01*
Y278701D01*
X650882Y278746D01*
X650887Y278786D01*
X650897Y278831D01*
X650907Y278871D01*
X650952Y278991D01*
X650992Y279071D01*
X651017Y279106D01*
X651037Y279141D01*
X651067Y279176D01*
X651092Y279211D01*
X651122Y279241D01*
Y281666D01*
X651132Y281791D01*
X651172Y281916D01*
X651232Y282026D01*
X651312Y282126D01*
X651412Y282206D01*
X651522Y282266D01*
X651647Y282306D01*
X651772Y282316D01*
G37*
G36*
G01X665945D02*
X666070Y282306D01*
X666195Y282266D01*
X666305Y282206D01*
X666405Y282126D01*
X666485Y282026D01*
X666545Y281916D01*
X666585Y281791D01*
X666595Y281666D01*
Y279236D01*
X666625Y279206D01*
X666725Y279066D01*
X666745Y279026D01*
X666760Y278991D01*
X666780Y278951D01*
X666795Y278911D01*
X666805Y278871D01*
X666820Y278826D01*
X666825Y278786D01*
X666835Y278746D01*
X666840Y278701D01*
Y278661D01*
X666845Y278616D01*
X666840Y278571D01*
Y278531D01*
X666835Y278486D01*
X666825Y278446D01*
X666820Y278406D01*
X666805Y278361D01*
X666795Y278321D01*
X666780Y278281D01*
X666760Y278241D01*
X666745Y278206D01*
X666725Y278166D01*
X666625Y278026D01*
X666595Y277996D01*
Y275866D01*
X666585Y275741D01*
X666545Y275616D01*
X666485Y275506D01*
X666405Y275406D01*
X666305Y275326D01*
X666195Y275266D01*
X666070Y275226D01*
X665945Y275216D01*
X665820Y275226D01*
X665695Y275266D01*
X665585Y275326D01*
X665485Y275406D01*
X665405Y275506D01*
X665345Y275616D01*
X665305Y275741D01*
X665295Y275866D01*
Y277991D01*
X665265Y278021D01*
X665240Y278056D01*
X665210Y278091D01*
X665190Y278126D01*
X665165Y278161D01*
X665125Y278241D01*
X665080Y278361D01*
X665070Y278401D01*
X665060Y278446D01*
X665055Y278486D01*
X665045Y278531D01*
Y278701D01*
X665055Y278746D01*
X665060Y278786D01*
X665070Y278831D01*
X665080Y278871D01*
X665125Y278991D01*
X665165Y279071D01*
X665190Y279106D01*
X665210Y279141D01*
X665240Y279176D01*
X665265Y279211D01*
X665295Y279241D01*
Y281666D01*
X665305Y281791D01*
X665345Y281916D01*
X665405Y282026D01*
X665485Y282126D01*
X665585Y282206D01*
X665695Y282266D01*
X665820Y282306D01*
X665945Y282316D01*
G37*
G36*
G01X670670D02*
X670795Y282306D01*
X670920Y282266D01*
X671030Y282206D01*
X671130Y282126D01*
X671210Y282026D01*
X671270Y281916D01*
X671310Y281791D01*
X671320Y281666D01*
Y279236D01*
X671350Y279206D01*
X671450Y279066D01*
X671470Y279026D01*
X671485Y278991D01*
X671505Y278951D01*
X671520Y278911D01*
X671530Y278871D01*
X671545Y278826D01*
X671550Y278786D01*
X671560Y278746D01*
X671565Y278701D01*
Y278661D01*
X671570Y278616D01*
X671565Y278571D01*
Y278531D01*
X671560Y278486D01*
X671550Y278446D01*
X671545Y278406D01*
X671530Y278361D01*
X671520Y278321D01*
X671505Y278281D01*
X671485Y278241D01*
X671470Y278206D01*
X671450Y278166D01*
X671350Y278026D01*
X671320Y277996D01*
Y275866D01*
X671310Y275741D01*
X671270Y275616D01*
X671210Y275506D01*
X671130Y275406D01*
X671030Y275326D01*
X670920Y275266D01*
X670795Y275226D01*
X670670Y275216D01*
X670545Y275226D01*
X670420Y275266D01*
X670310Y275326D01*
X670210Y275406D01*
X670130Y275506D01*
X670070Y275616D01*
X670030Y275741D01*
X670020Y275866D01*
Y277991D01*
X669990Y278021D01*
X669965Y278056D01*
X669935Y278091D01*
X669915Y278126D01*
X669890Y278161D01*
X669850Y278241D01*
X669805Y278361D01*
X669795Y278401D01*
X669785Y278446D01*
X669780Y278486D01*
X669770Y278531D01*
Y278701D01*
X669780Y278746D01*
X669785Y278786D01*
X669795Y278831D01*
X669805Y278871D01*
X669850Y278991D01*
X669890Y279071D01*
X669915Y279106D01*
X669935Y279141D01*
X669965Y279176D01*
X669990Y279211D01*
X670020Y279241D01*
Y281666D01*
X670030Y281791D01*
X670070Y281916D01*
X670130Y282026D01*
X670210Y282126D01*
X670310Y282206D01*
X670420Y282266D01*
X670545Y282306D01*
X670670Y282316D01*
G37*
G36*
G01X675394D02*
X675519Y282306D01*
X675644Y282266D01*
X675754Y282206D01*
X675854Y282126D01*
X675934Y282026D01*
X675994Y281916D01*
X676034Y281791D01*
X676044Y281666D01*
Y279236D01*
X676074Y279206D01*
X676174Y279066D01*
X676194Y279026D01*
X676209Y278991D01*
X676229Y278951D01*
X676244Y278911D01*
X676254Y278871D01*
X676269Y278826D01*
X676274Y278786D01*
X676284Y278746D01*
X676289Y278701D01*
Y278661D01*
X676294Y278616D01*
X676289Y278571D01*
Y278531D01*
X676284Y278486D01*
X676274Y278446D01*
X676269Y278406D01*
X676254Y278361D01*
X676244Y278321D01*
X676229Y278281D01*
X676209Y278241D01*
X676194Y278206D01*
X676174Y278166D01*
X676074Y278026D01*
X676044Y277996D01*
Y275866D01*
X676034Y275741D01*
X675994Y275616D01*
X675934Y275506D01*
X675854Y275406D01*
X675754Y275326D01*
X675644Y275266D01*
X675519Y275226D01*
X675394Y275216D01*
X675269Y275226D01*
X675144Y275266D01*
X675034Y275326D01*
X674934Y275406D01*
X674854Y275506D01*
X674794Y275616D01*
X674754Y275741D01*
X674744Y275866D01*
Y277991D01*
X674714Y278021D01*
X674689Y278056D01*
X674659Y278091D01*
X674639Y278126D01*
X674614Y278161D01*
X674574Y278241D01*
X674529Y278361D01*
X674519Y278401D01*
X674509Y278446D01*
X674504Y278486D01*
X674494Y278531D01*
Y278701D01*
X674504Y278746D01*
X674509Y278786D01*
X674519Y278831D01*
X674529Y278871D01*
X674574Y278991D01*
X674614Y279071D01*
X674639Y279106D01*
X674659Y279141D01*
X674689Y279176D01*
X674714Y279211D01*
X674744Y279241D01*
Y281666D01*
X674754Y281791D01*
X674794Y281916D01*
X674854Y282026D01*
X674934Y282126D01*
X675034Y282206D01*
X675144Y282266D01*
X675269Y282306D01*
X675394Y282316D01*
G37*
G36*
G01X680118D02*
X680243Y282306D01*
X680368Y282266D01*
X680478Y282206D01*
X680578Y282126D01*
X680658Y282026D01*
X680718Y281916D01*
X680758Y281791D01*
X680768Y281666D01*
Y279236D01*
X680798Y279206D01*
X680898Y279066D01*
X680918Y279026D01*
X680933Y278991D01*
X680953Y278951D01*
X680968Y278911D01*
X680978Y278871D01*
X680993Y278826D01*
X680998Y278786D01*
X681008Y278746D01*
X681013Y278701D01*
Y278661D01*
X681018Y278616D01*
X681013Y278571D01*
Y278531D01*
X681008Y278486D01*
X680998Y278446D01*
X680993Y278406D01*
X680978Y278361D01*
X680968Y278321D01*
X680953Y278281D01*
X680933Y278241D01*
X680918Y278206D01*
X680898Y278166D01*
X680798Y278026D01*
X680768Y277996D01*
Y275866D01*
X680758Y275741D01*
X680718Y275616D01*
X680658Y275506D01*
X680578Y275406D01*
X680478Y275326D01*
X680368Y275266D01*
X680243Y275226D01*
X680118Y275216D01*
X679993Y275226D01*
X679868Y275266D01*
X679758Y275326D01*
X679658Y275406D01*
X679578Y275506D01*
X679518Y275616D01*
X679478Y275741D01*
X679468Y275866D01*
Y277991D01*
X679438Y278021D01*
X679413Y278056D01*
X679383Y278091D01*
X679363Y278126D01*
X679338Y278161D01*
X679298Y278241D01*
X679253Y278361D01*
X679243Y278401D01*
X679233Y278446D01*
X679228Y278486D01*
X679218Y278531D01*
Y278701D01*
X679228Y278746D01*
X679233Y278786D01*
X679243Y278831D01*
X679253Y278871D01*
X679298Y278991D01*
X679338Y279071D01*
X679363Y279106D01*
X679383Y279141D01*
X679413Y279176D01*
X679438Y279211D01*
X679468Y279241D01*
Y281666D01*
X679478Y281791D01*
X679518Y281916D01*
X679578Y282026D01*
X679658Y282126D01*
X679758Y282206D01*
X679868Y282266D01*
X679993Y282306D01*
X680118Y282316D01*
G37*
G36*
G01X684843D02*
X684968Y282306D01*
X685093Y282266D01*
X685203Y282206D01*
X685303Y282126D01*
X685383Y282026D01*
X685443Y281916D01*
X685483Y281791D01*
X685493Y281666D01*
Y279236D01*
X685523Y279206D01*
X685623Y279066D01*
X685643Y279026D01*
X685658Y278991D01*
X685678Y278951D01*
X685693Y278911D01*
X685703Y278871D01*
X685718Y278826D01*
X685723Y278786D01*
X685733Y278746D01*
X685738Y278701D01*
Y278661D01*
X685743Y278616D01*
X685738Y278571D01*
Y278531D01*
X685733Y278486D01*
X685723Y278446D01*
X685718Y278406D01*
X685703Y278361D01*
X685693Y278321D01*
X685678Y278281D01*
X685658Y278241D01*
X685643Y278206D01*
X685623Y278166D01*
X685523Y278026D01*
X685493Y277996D01*
Y275866D01*
X685483Y275741D01*
X685443Y275616D01*
X685383Y275506D01*
X685303Y275406D01*
X685203Y275326D01*
X685093Y275266D01*
X684968Y275226D01*
X684843Y275216D01*
X684718Y275226D01*
X684593Y275266D01*
X684483Y275326D01*
X684383Y275406D01*
X684303Y275506D01*
X684243Y275616D01*
X684203Y275741D01*
X684193Y275866D01*
Y277991D01*
X684163Y278021D01*
X684138Y278056D01*
X684108Y278091D01*
X684088Y278126D01*
X684063Y278161D01*
X684023Y278241D01*
X683978Y278361D01*
X683968Y278401D01*
X683958Y278446D01*
X683953Y278486D01*
X683943Y278531D01*
Y278701D01*
X683953Y278746D01*
X683958Y278786D01*
X683968Y278831D01*
X683978Y278871D01*
X684023Y278991D01*
X684063Y279071D01*
X684088Y279106D01*
X684108Y279141D01*
X684138Y279176D01*
X684163Y279211D01*
X684193Y279241D01*
Y281666D01*
X684203Y281791D01*
X684243Y281916D01*
X684303Y282026D01*
X684383Y282126D01*
X684483Y282206D01*
X684593Y282266D01*
X684718Y282306D01*
X684843Y282316D01*
G37*
G36*
G01X689567D02*
X689692Y282306D01*
X689817Y282266D01*
X689927Y282206D01*
X690027Y282126D01*
X690107Y282026D01*
X690167Y281916D01*
X690207Y281791D01*
X690217Y281666D01*
Y279236D01*
X690247Y279206D01*
X690347Y279066D01*
X690367Y279026D01*
X690382Y278991D01*
X690402Y278951D01*
X690417Y278911D01*
X690427Y278871D01*
X690442Y278826D01*
X690447Y278786D01*
X690457Y278746D01*
X690462Y278701D01*
Y278661D01*
X690467Y278616D01*
X690462Y278571D01*
Y278531D01*
X690457Y278486D01*
X690447Y278446D01*
X690442Y278406D01*
X690427Y278361D01*
X690417Y278321D01*
X690402Y278281D01*
X690382Y278241D01*
X690367Y278206D01*
X690347Y278166D01*
X690247Y278026D01*
X690217Y277996D01*
Y275866D01*
X690207Y275741D01*
X690167Y275616D01*
X690107Y275506D01*
X690027Y275406D01*
X689927Y275326D01*
X689817Y275266D01*
X689692Y275226D01*
X689567Y275216D01*
X689442Y275226D01*
X689317Y275266D01*
X689207Y275326D01*
X689107Y275406D01*
X689027Y275506D01*
X688967Y275616D01*
X688927Y275741D01*
X688917Y275866D01*
Y277991D01*
X688887Y278021D01*
X688862Y278056D01*
X688832Y278091D01*
X688812Y278126D01*
X688787Y278161D01*
X688747Y278241D01*
X688702Y278361D01*
X688692Y278401D01*
X688682Y278446D01*
X688677Y278486D01*
X688667Y278531D01*
Y278701D01*
X688677Y278746D01*
X688682Y278786D01*
X688692Y278831D01*
X688702Y278871D01*
X688747Y278991D01*
X688787Y279071D01*
X688812Y279106D01*
X688832Y279141D01*
X688862Y279176D01*
X688887Y279211D01*
X688917Y279241D01*
Y281666D01*
X688927Y281791D01*
X688967Y281916D01*
X689027Y282026D01*
X689107Y282126D01*
X689207Y282206D01*
X689317Y282266D01*
X689442Y282306D01*
X689567Y282316D01*
G37*
G36*
G01X694292D02*
X694417Y282306D01*
X694542Y282266D01*
X694652Y282206D01*
X694752Y282126D01*
X694832Y282026D01*
X694892Y281916D01*
X694932Y281791D01*
X694942Y281666D01*
Y279236D01*
X694972Y279206D01*
X695072Y279066D01*
X695092Y279026D01*
X695107Y278991D01*
X695127Y278951D01*
X695142Y278911D01*
X695152Y278871D01*
X695167Y278826D01*
X695172Y278786D01*
X695182Y278746D01*
X695187Y278701D01*
Y278661D01*
X695192Y278616D01*
X695187Y278571D01*
Y278531D01*
X695182Y278486D01*
X695172Y278446D01*
X695167Y278406D01*
X695152Y278361D01*
X695142Y278321D01*
X695127Y278281D01*
X695107Y278241D01*
X695092Y278206D01*
X695072Y278166D01*
X694972Y278026D01*
X694942Y277996D01*
Y275866D01*
X694932Y275741D01*
X694892Y275616D01*
X694832Y275506D01*
X694752Y275406D01*
X694652Y275326D01*
X694542Y275266D01*
X694417Y275226D01*
X694292Y275216D01*
X694167Y275226D01*
X694042Y275266D01*
X693932Y275326D01*
X693832Y275406D01*
X693752Y275506D01*
X693692Y275616D01*
X693652Y275741D01*
X693642Y275866D01*
Y277991D01*
X693612Y278021D01*
X693587Y278056D01*
X693557Y278091D01*
X693537Y278126D01*
X693512Y278161D01*
X693472Y278241D01*
X693427Y278361D01*
X693417Y278401D01*
X693407Y278446D01*
X693402Y278486D01*
X693392Y278531D01*
Y278701D01*
X693402Y278746D01*
X693407Y278786D01*
X693417Y278831D01*
X693427Y278871D01*
X693472Y278991D01*
X693512Y279071D01*
X693537Y279106D01*
X693557Y279141D01*
X693587Y279176D01*
X693612Y279211D01*
X693642Y279241D01*
Y281666D01*
X693652Y281791D01*
X693692Y281916D01*
X693752Y282026D01*
X693832Y282126D01*
X693932Y282206D01*
X694042Y282266D01*
X694167Y282306D01*
X694292Y282316D01*
G37*
G36*
G01X699016D02*
X699141Y282306D01*
X699266Y282266D01*
X699376Y282206D01*
X699476Y282126D01*
X699556Y282026D01*
X699616Y281916D01*
X699656Y281791D01*
X699666Y281666D01*
Y279236D01*
X699696Y279206D01*
X699796Y279066D01*
X699816Y279026D01*
X699831Y278991D01*
X699851Y278951D01*
X699866Y278911D01*
X699876Y278871D01*
X699891Y278826D01*
X699896Y278786D01*
X699906Y278746D01*
X699911Y278701D01*
Y278661D01*
X699916Y278616D01*
X699911Y278571D01*
Y278531D01*
X699906Y278486D01*
X699896Y278446D01*
X699891Y278406D01*
X699876Y278361D01*
X699866Y278321D01*
X699851Y278281D01*
X699831Y278241D01*
X699816Y278206D01*
X699796Y278166D01*
X699696Y278026D01*
X699666Y277996D01*
Y275866D01*
X699656Y275741D01*
X699616Y275616D01*
X699556Y275506D01*
X699476Y275406D01*
X699376Y275326D01*
X699266Y275266D01*
X699141Y275226D01*
X699016Y275216D01*
X698891Y275226D01*
X698766Y275266D01*
X698656Y275326D01*
X698556Y275406D01*
X698476Y275506D01*
X698416Y275616D01*
X698376Y275741D01*
X698366Y275866D01*
Y277991D01*
X698336Y278021D01*
X698311Y278056D01*
X698281Y278091D01*
X698261Y278126D01*
X698236Y278161D01*
X698196Y278241D01*
X698151Y278361D01*
X698141Y278401D01*
X698131Y278446D01*
X698126Y278486D01*
X698116Y278531D01*
Y278701D01*
X698126Y278746D01*
X698131Y278786D01*
X698141Y278831D01*
X698151Y278871D01*
X698196Y278991D01*
X698236Y279071D01*
X698261Y279106D01*
X698281Y279141D01*
X698311Y279176D01*
X698336Y279211D01*
X698366Y279241D01*
Y281666D01*
X698376Y281791D01*
X698416Y281916D01*
X698476Y282026D01*
X698556Y282126D01*
X698656Y282206D01*
X698766Y282266D01*
X698891Y282306D01*
X699016Y282316D01*
G37*
G36*
G01X703740D02*
X703865Y282306D01*
X703990Y282266D01*
X704100Y282206D01*
X704200Y282126D01*
X704280Y282026D01*
X704340Y281916D01*
X704380Y281791D01*
X704390Y281666D01*
Y279236D01*
X704420Y279206D01*
X704520Y279066D01*
X704540Y279026D01*
X704555Y278991D01*
X704575Y278951D01*
X704590Y278911D01*
X704600Y278871D01*
X704615Y278826D01*
X704620Y278786D01*
X704630Y278746D01*
X704635Y278701D01*
Y278661D01*
X704640Y278616D01*
X704635Y278571D01*
Y278531D01*
X704630Y278486D01*
X704620Y278446D01*
X704615Y278406D01*
X704600Y278361D01*
X704590Y278321D01*
X704575Y278281D01*
X704555Y278241D01*
X704540Y278206D01*
X704520Y278166D01*
X704420Y278026D01*
X704390Y277996D01*
Y275866D01*
X704380Y275741D01*
X704340Y275616D01*
X704280Y275506D01*
X704200Y275406D01*
X704100Y275326D01*
X703990Y275266D01*
X703865Y275226D01*
X703740Y275216D01*
X703615Y275226D01*
X703490Y275266D01*
X703380Y275326D01*
X703280Y275406D01*
X703200Y275506D01*
X703140Y275616D01*
X703100Y275741D01*
X703090Y275866D01*
Y277991D01*
X703060Y278021D01*
X703035Y278056D01*
X703005Y278091D01*
X702985Y278126D01*
X702960Y278161D01*
X702920Y278241D01*
X702875Y278361D01*
X702865Y278401D01*
X702855Y278446D01*
X702850Y278486D01*
X702840Y278531D01*
Y278701D01*
X702850Y278746D01*
X702855Y278786D01*
X702865Y278831D01*
X702875Y278871D01*
X702920Y278991D01*
X702960Y279071D01*
X702985Y279106D01*
X703005Y279141D01*
X703035Y279176D01*
X703060Y279211D01*
X703090Y279241D01*
Y281666D01*
X703100Y281791D01*
X703140Y281916D01*
X703200Y282026D01*
X703280Y282126D01*
X703380Y282206D01*
X703490Y282266D01*
X703615Y282306D01*
X703740Y282316D01*
G37*
G36*
G01X708465D02*
X708590Y282306D01*
X708715Y282266D01*
X708825Y282206D01*
X708925Y282126D01*
X709005Y282026D01*
X709065Y281916D01*
X709105Y281791D01*
X709115Y281666D01*
Y279236D01*
X709145Y279206D01*
X709245Y279066D01*
X709265Y279026D01*
X709280Y278991D01*
X709300Y278951D01*
X709315Y278911D01*
X709325Y278871D01*
X709340Y278826D01*
X709345Y278786D01*
X709355Y278746D01*
X709360Y278701D01*
Y278661D01*
X709365Y278616D01*
X709360Y278571D01*
Y278531D01*
X709355Y278486D01*
X709345Y278446D01*
X709340Y278406D01*
X709325Y278361D01*
X709315Y278321D01*
X709300Y278281D01*
X709280Y278241D01*
X709265Y278206D01*
X709245Y278166D01*
X709145Y278026D01*
X709115Y277996D01*
Y275866D01*
X709105Y275741D01*
X709065Y275616D01*
X709005Y275506D01*
X708925Y275406D01*
X708825Y275326D01*
X708715Y275266D01*
X708590Y275226D01*
X708465Y275216D01*
X708340Y275226D01*
X708215Y275266D01*
X708105Y275326D01*
X708005Y275406D01*
X707925Y275506D01*
X707865Y275616D01*
X707825Y275741D01*
X707815Y275866D01*
Y277991D01*
X707785Y278021D01*
X707760Y278056D01*
X707730Y278091D01*
X707710Y278126D01*
X707685Y278161D01*
X707645Y278241D01*
X707600Y278361D01*
X707590Y278401D01*
X707580Y278446D01*
X707575Y278486D01*
X707565Y278531D01*
Y278701D01*
X707575Y278746D01*
X707580Y278786D01*
X707590Y278831D01*
X707600Y278871D01*
X707645Y278991D01*
X707685Y279071D01*
X707710Y279106D01*
X707730Y279141D01*
X707760Y279176D01*
X707785Y279211D01*
X707815Y279241D01*
Y281666D01*
X707825Y281791D01*
X707865Y281916D01*
X707925Y282026D01*
X708005Y282126D01*
X708105Y282206D01*
X708215Y282266D01*
X708340Y282306D01*
X708465Y282316D01*
G37*
G36*
G01X713189D02*
X713314Y282306D01*
X713439Y282266D01*
X713549Y282206D01*
X713649Y282126D01*
X713729Y282026D01*
X713789Y281916D01*
X713829Y281791D01*
X713839Y281666D01*
Y279236D01*
X713869Y279206D01*
X713969Y279066D01*
X713989Y279026D01*
X714004Y278991D01*
X714024Y278951D01*
X714039Y278911D01*
X714049Y278871D01*
X714064Y278826D01*
X714069Y278786D01*
X714079Y278746D01*
X714084Y278701D01*
Y278661D01*
X714089Y278616D01*
X714084Y278571D01*
Y278531D01*
X714079Y278486D01*
X714069Y278446D01*
X714064Y278406D01*
X714049Y278361D01*
X714039Y278321D01*
X714024Y278281D01*
X714004Y278241D01*
X713989Y278206D01*
X713969Y278166D01*
X713869Y278026D01*
X713839Y277996D01*
Y275866D01*
X713829Y275741D01*
X713789Y275616D01*
X713729Y275506D01*
X713649Y275406D01*
X713549Y275326D01*
X713439Y275266D01*
X713314Y275226D01*
X713189Y275216D01*
X713064Y275226D01*
X712939Y275266D01*
X712829Y275326D01*
X712729Y275406D01*
X712649Y275506D01*
X712589Y275616D01*
X712549Y275741D01*
X712539Y275866D01*
Y277991D01*
X712509Y278021D01*
X712484Y278056D01*
X712454Y278091D01*
X712434Y278126D01*
X712409Y278161D01*
X712369Y278241D01*
X712324Y278361D01*
X712314Y278401D01*
X712304Y278446D01*
X712299Y278486D01*
X712289Y278531D01*
Y278701D01*
X712299Y278746D01*
X712304Y278786D01*
X712314Y278831D01*
X712324Y278871D01*
X712369Y278991D01*
X712409Y279071D01*
X712434Y279106D01*
X712454Y279141D01*
X712484Y279176D01*
X712509Y279211D01*
X712539Y279241D01*
Y281666D01*
X712549Y281791D01*
X712589Y281916D01*
X712649Y282026D01*
X712729Y282126D01*
X712829Y282206D01*
X712939Y282266D01*
X713064Y282306D01*
X713189Y282316D01*
G37*
G36*
G01X717914D02*
X718039Y282306D01*
X718164Y282266D01*
X718274Y282206D01*
X718374Y282126D01*
X718454Y282026D01*
X718514Y281916D01*
X718554Y281791D01*
X718564Y281666D01*
Y279236D01*
X718594Y279206D01*
X718694Y279066D01*
X718714Y279026D01*
X718729Y278991D01*
X718749Y278951D01*
X718764Y278911D01*
X718774Y278871D01*
X718789Y278826D01*
X718794Y278786D01*
X718804Y278746D01*
X718809Y278701D01*
Y278661D01*
X718814Y278616D01*
X718809Y278571D01*
Y278531D01*
X718804Y278486D01*
X718794Y278446D01*
X718789Y278406D01*
X718774Y278361D01*
X718764Y278321D01*
X718749Y278281D01*
X718729Y278241D01*
X718714Y278206D01*
X718694Y278166D01*
X718594Y278026D01*
X718564Y277996D01*
Y275866D01*
X718554Y275741D01*
X718514Y275616D01*
X718454Y275506D01*
X718374Y275406D01*
X718274Y275326D01*
X718164Y275266D01*
X718039Y275226D01*
X717914Y275216D01*
X717789Y275226D01*
X717664Y275266D01*
X717554Y275326D01*
X717454Y275406D01*
X717374Y275506D01*
X717314Y275616D01*
X717274Y275741D01*
X717264Y275866D01*
Y277991D01*
X717234Y278021D01*
X717209Y278056D01*
X717179Y278091D01*
X717159Y278126D01*
X717134Y278161D01*
X717094Y278241D01*
X717049Y278361D01*
X717039Y278401D01*
X717029Y278446D01*
X717024Y278486D01*
X717014Y278531D01*
Y278701D01*
X717024Y278746D01*
X717029Y278786D01*
X717039Y278831D01*
X717049Y278871D01*
X717094Y278991D01*
X717134Y279071D01*
X717159Y279106D01*
X717179Y279141D01*
X717209Y279176D01*
X717234Y279211D01*
X717264Y279241D01*
Y281666D01*
X717274Y281791D01*
X717314Y281916D01*
X717374Y282026D01*
X717454Y282126D01*
X717554Y282206D01*
X717664Y282266D01*
X717789Y282306D01*
X717914Y282316D01*
G37*
G36*
G01X722638D02*
X722763Y282306D01*
X722888Y282266D01*
X722998Y282206D01*
X723098Y282126D01*
X723178Y282026D01*
X723238Y281916D01*
X723278Y281791D01*
X723288Y281666D01*
Y279236D01*
X723318Y279206D01*
X723418Y279066D01*
X723438Y279026D01*
X723453Y278991D01*
X723473Y278951D01*
X723488Y278911D01*
X723498Y278871D01*
X723513Y278826D01*
X723518Y278786D01*
X723528Y278746D01*
X723533Y278701D01*
Y278661D01*
X723538Y278616D01*
X723533Y278571D01*
Y278531D01*
X723528Y278486D01*
X723518Y278446D01*
X723513Y278406D01*
X723498Y278361D01*
X723488Y278321D01*
X723473Y278281D01*
X723453Y278241D01*
X723438Y278206D01*
X723418Y278166D01*
X723318Y278026D01*
X723288Y277996D01*
Y275866D01*
X723278Y275741D01*
X723238Y275616D01*
X723178Y275506D01*
X723098Y275406D01*
X722998Y275326D01*
X722888Y275266D01*
X722763Y275226D01*
X722638Y275216D01*
X722513Y275226D01*
X722388Y275266D01*
X722278Y275326D01*
X722178Y275406D01*
X722098Y275506D01*
X722038Y275616D01*
X721998Y275741D01*
X721988Y275866D01*
Y277991D01*
X721958Y278021D01*
X721933Y278056D01*
X721903Y278091D01*
X721883Y278126D01*
X721858Y278161D01*
X721818Y278241D01*
X721773Y278361D01*
X721763Y278401D01*
X721753Y278446D01*
X721748Y278486D01*
X721738Y278531D01*
Y278701D01*
X721748Y278746D01*
X721753Y278786D01*
X721763Y278831D01*
X721773Y278871D01*
X721818Y278991D01*
X721858Y279071D01*
X721883Y279106D01*
X721903Y279141D01*
X721933Y279176D01*
X721958Y279211D01*
X721988Y279241D01*
Y281666D01*
X721998Y281791D01*
X722038Y281916D01*
X722098Y282026D01*
X722178Y282126D01*
X722278Y282206D01*
X722388Y282266D01*
X722513Y282306D01*
X722638Y282316D01*
G37*
G36*
G01X727362D02*
X727487Y282306D01*
X727612Y282266D01*
X727722Y282206D01*
X727822Y282126D01*
X727902Y282026D01*
X727962Y281916D01*
X728002Y281791D01*
X728012Y281666D01*
Y279236D01*
X728042Y279206D01*
X728142Y279066D01*
X728162Y279026D01*
X728177Y278991D01*
X728197Y278951D01*
X728212Y278911D01*
X728222Y278871D01*
X728237Y278826D01*
X728242Y278786D01*
X728252Y278746D01*
X728257Y278701D01*
Y278661D01*
X728262Y278616D01*
X728257Y278571D01*
Y278531D01*
X728252Y278486D01*
X728242Y278446D01*
X728237Y278406D01*
X728222Y278361D01*
X728212Y278321D01*
X728197Y278281D01*
X728177Y278241D01*
X728162Y278206D01*
X728142Y278166D01*
X728042Y278026D01*
X728012Y277996D01*
Y275866D01*
X728002Y275741D01*
X727962Y275616D01*
X727902Y275506D01*
X727822Y275406D01*
X727722Y275326D01*
X727612Y275266D01*
X727487Y275226D01*
X727362Y275216D01*
X727237Y275226D01*
X727112Y275266D01*
X727002Y275326D01*
X726902Y275406D01*
X726822Y275506D01*
X726762Y275616D01*
X726722Y275741D01*
X726712Y275866D01*
Y277991D01*
X726682Y278021D01*
X726657Y278056D01*
X726627Y278091D01*
X726607Y278126D01*
X726582Y278161D01*
X726542Y278241D01*
X726497Y278361D01*
X726487Y278401D01*
X726477Y278446D01*
X726472Y278486D01*
X726462Y278531D01*
Y278701D01*
X726472Y278746D01*
X726477Y278786D01*
X726487Y278831D01*
X726497Y278871D01*
X726542Y278991D01*
X726582Y279071D01*
X726607Y279106D01*
X726627Y279141D01*
X726657Y279176D01*
X726682Y279211D01*
X726712Y279241D01*
Y281666D01*
X726722Y281791D01*
X726762Y281916D01*
X726822Y282026D01*
X726902Y282126D01*
X727002Y282206D01*
X727112Y282266D01*
X727237Y282306D01*
X727362Y282316D01*
G37*
G36*
G01X732087D02*
X732212Y282306D01*
X732337Y282266D01*
X732447Y282206D01*
X732547Y282126D01*
X732627Y282026D01*
X732687Y281916D01*
X732727Y281791D01*
X732737Y281666D01*
Y279236D01*
X732767Y279206D01*
X732867Y279066D01*
X732887Y279026D01*
X732902Y278991D01*
X732922Y278951D01*
X732937Y278911D01*
X732947Y278871D01*
X732962Y278826D01*
X732967Y278786D01*
X732977Y278746D01*
X732982Y278701D01*
Y278661D01*
X732987Y278616D01*
X732982Y278571D01*
Y278531D01*
X732977Y278486D01*
X732967Y278446D01*
X732962Y278406D01*
X732947Y278361D01*
X732937Y278321D01*
X732922Y278281D01*
X732902Y278241D01*
X732887Y278206D01*
X732867Y278166D01*
X732767Y278026D01*
X732737Y277996D01*
Y275866D01*
X732727Y275741D01*
X732687Y275616D01*
X732627Y275506D01*
X732547Y275406D01*
X732447Y275326D01*
X732337Y275266D01*
X732212Y275226D01*
X732087Y275216D01*
X731962Y275226D01*
X731837Y275266D01*
X731727Y275326D01*
X731627Y275406D01*
X731547Y275506D01*
X731487Y275616D01*
X731447Y275741D01*
X731437Y275866D01*
Y277991D01*
X731407Y278021D01*
X731382Y278056D01*
X731352Y278091D01*
X731332Y278126D01*
X731307Y278161D01*
X731267Y278241D01*
X731222Y278361D01*
X731212Y278401D01*
X731202Y278446D01*
X731197Y278486D01*
X731187Y278531D01*
Y278701D01*
X731197Y278746D01*
X731202Y278786D01*
X731212Y278831D01*
X731222Y278871D01*
X731267Y278991D01*
X731307Y279071D01*
X731332Y279106D01*
X731352Y279141D01*
X731382Y279176D01*
X731407Y279211D01*
X731437Y279241D01*
Y281666D01*
X731447Y281791D01*
X731487Y281916D01*
X731547Y282026D01*
X731627Y282126D01*
X731727Y282206D01*
X731837Y282266D01*
X731962Y282306D01*
X732087Y282316D01*
G37*
G36*
G01X736811D02*
X736936Y282306D01*
X737061Y282266D01*
X737171Y282206D01*
X737271Y282126D01*
X737351Y282026D01*
X737411Y281916D01*
X737451Y281791D01*
X737461Y281666D01*
Y279236D01*
X737491Y279206D01*
X737591Y279066D01*
X737611Y279026D01*
X737626Y278991D01*
X737646Y278951D01*
X737661Y278911D01*
X737671Y278871D01*
X737686Y278826D01*
X737691Y278786D01*
X737701Y278746D01*
X737706Y278701D01*
Y278661D01*
X737711Y278616D01*
X737706Y278571D01*
Y278531D01*
X737701Y278486D01*
X737691Y278446D01*
X737686Y278406D01*
X737671Y278361D01*
X737661Y278321D01*
X737646Y278281D01*
X737626Y278241D01*
X737611Y278206D01*
X737591Y278166D01*
X737491Y278026D01*
X737461Y277996D01*
Y275866D01*
X737451Y275741D01*
X737411Y275616D01*
X737351Y275506D01*
X737271Y275406D01*
X737171Y275326D01*
X737061Y275266D01*
X736936Y275226D01*
X736811Y275216D01*
X736686Y275226D01*
X736561Y275266D01*
X736451Y275326D01*
X736351Y275406D01*
X736271Y275506D01*
X736211Y275616D01*
X736171Y275741D01*
X736161Y275866D01*
Y277991D01*
X736131Y278021D01*
X736106Y278056D01*
X736076Y278091D01*
X736056Y278126D01*
X736031Y278161D01*
X735991Y278241D01*
X735946Y278361D01*
X735936Y278401D01*
X735926Y278446D01*
X735921Y278486D01*
X735911Y278531D01*
Y278701D01*
X735921Y278746D01*
X735926Y278786D01*
X735936Y278831D01*
X735946Y278871D01*
X735991Y278991D01*
X736031Y279071D01*
X736056Y279106D01*
X736076Y279141D01*
X736106Y279176D01*
X736131Y279211D01*
X736161Y279241D01*
Y281666D01*
X736171Y281791D01*
X736211Y281916D01*
X736271Y282026D01*
X736351Y282126D01*
X736451Y282206D01*
X736561Y282266D01*
X736686Y282306D01*
X736811Y282316D01*
G37*
G36*
G01X741536D02*
X741661Y282306D01*
X741786Y282266D01*
X741896Y282206D01*
X741996Y282126D01*
X742076Y282026D01*
X742136Y281916D01*
X742176Y281791D01*
X742186Y281666D01*
Y279236D01*
X742216Y279206D01*
X742316Y279066D01*
X742336Y279026D01*
X742351Y278991D01*
X742371Y278951D01*
X742386Y278911D01*
X742396Y278871D01*
X742411Y278826D01*
X742416Y278786D01*
X742426Y278746D01*
X742431Y278701D01*
Y278661D01*
X742436Y278616D01*
X742431Y278571D01*
Y278531D01*
X742426Y278486D01*
X742416Y278446D01*
X742411Y278406D01*
X742396Y278361D01*
X742386Y278321D01*
X742371Y278281D01*
X742351Y278241D01*
X742336Y278206D01*
X742316Y278166D01*
X742216Y278026D01*
X742186Y277996D01*
Y275866D01*
X742176Y275741D01*
X742136Y275616D01*
X742076Y275506D01*
X741996Y275406D01*
X741896Y275326D01*
X741786Y275266D01*
X741661Y275226D01*
X741536Y275216D01*
X741411Y275226D01*
X741286Y275266D01*
X741176Y275326D01*
X741076Y275406D01*
X740996Y275506D01*
X740936Y275616D01*
X740896Y275741D01*
X740886Y275866D01*
Y277991D01*
X740856Y278021D01*
X740831Y278056D01*
X740801Y278091D01*
X740781Y278126D01*
X740756Y278161D01*
X740716Y278241D01*
X740671Y278361D01*
X740661Y278401D01*
X740651Y278446D01*
X740646Y278486D01*
X740636Y278531D01*
Y278701D01*
X740646Y278746D01*
X740651Y278786D01*
X740661Y278831D01*
X740671Y278871D01*
X740716Y278991D01*
X740756Y279071D01*
X740781Y279106D01*
X740801Y279141D01*
X740831Y279176D01*
X740856Y279211D01*
X740886Y279241D01*
Y281666D01*
X740896Y281791D01*
X740936Y281916D01*
X740996Y282026D01*
X741076Y282126D01*
X741176Y282206D01*
X741286Y282266D01*
X741411Y282306D01*
X741536Y282316D01*
G37*
G36*
G01X746260D02*
X746385Y282306D01*
X746510Y282266D01*
X746620Y282206D01*
X746720Y282126D01*
X746800Y282026D01*
X746860Y281916D01*
X746900Y281791D01*
X746910Y281666D01*
Y279236D01*
X746940Y279206D01*
X747040Y279066D01*
X747060Y279026D01*
X747075Y278991D01*
X747095Y278951D01*
X747110Y278911D01*
X747120Y278871D01*
X747135Y278826D01*
X747140Y278786D01*
X747150Y278746D01*
X747155Y278701D01*
Y278661D01*
X747160Y278616D01*
X747155Y278571D01*
Y278531D01*
X747150Y278486D01*
X747140Y278446D01*
X747135Y278406D01*
X747120Y278361D01*
X747110Y278321D01*
X747095Y278281D01*
X747075Y278241D01*
X747060Y278206D01*
X747040Y278166D01*
X746940Y278026D01*
X746910Y277996D01*
Y275866D01*
X746900Y275741D01*
X746860Y275616D01*
X746800Y275506D01*
X746720Y275406D01*
X746620Y275326D01*
X746510Y275266D01*
X746385Y275226D01*
X746260Y275216D01*
X746135Y275226D01*
X746010Y275266D01*
X745900Y275326D01*
X745800Y275406D01*
X745720Y275506D01*
X745660Y275616D01*
X745620Y275741D01*
X745610Y275866D01*
Y277991D01*
X745580Y278021D01*
X745555Y278056D01*
X745525Y278091D01*
X745505Y278126D01*
X745480Y278161D01*
X745440Y278241D01*
X745395Y278361D01*
X745385Y278401D01*
X745375Y278446D01*
X745370Y278486D01*
X745360Y278531D01*
Y278701D01*
X745370Y278746D01*
X745375Y278786D01*
X745385Y278831D01*
X745395Y278871D01*
X745440Y278991D01*
X745480Y279071D01*
X745505Y279106D01*
X745525Y279141D01*
X745555Y279176D01*
X745580Y279211D01*
X745610Y279241D01*
Y281666D01*
X745620Y281791D01*
X745660Y281916D01*
X745720Y282026D01*
X745800Y282126D01*
X745900Y282206D01*
X746010Y282266D01*
X746135Y282306D01*
X746260Y282316D01*
G37*
M02*
